G04 ================== begin FILE IDENTIFICATION RECORD ==================*
G04 Layout Name:  13948-1b.brd*
G04 Film Name:    TSILK*
G04 File Format:  Gerber RS274X*
G04 File Origin:  Cadence Allegro 16.5-S045*
G04 Origin Date:  Thu Nov 13 15:45:57 2014*
G04 *
G04 Layer:  VIA CLASS/FILMMASKTOP*
G04 Layer:  REF DES/ASSEMBLY_TOP*
G04 Layer:  PACKAGE GEOMETRY/SILKSCREEN_TOP*
G04 Layer:  DRAWING FORMAT/LAYER_PCB_STORY*
G04 Layer:  DRAWING FORMAT/LAYER_SILK_T*
G04 Layer:  BOARD GEOMETRY/SILKSCREEN_TOP*
G04 *
G04 Offset:    (0.00 0.00)*
G04 Mirror:    No*
G04 Mode:      Positive*
G04 Rotation:  0*
G04 FullContactRelief:  No*
G04 UndefLineWidth:     6.00*
G04 ================== end FILE IDENTIFICATION RECORD ====================*
%FSLAX35Y35*MOIN*%
%IR0*IPPOS*OFA0.00000B0.00000*MIA0B0*SFA1.00000B1.00000*%
%ADD10C,.026*%
%ADD11C,.01*%
%ADD12C,.02*%
%ADD13C,.012*%
%ADD14C,.013*%
%ADD15C,.014*%
%ADD16C,.015*%
%ADD17C,.025*%
%ADD18C,.016*%
%ADD19C,.019*%
%ADD20C,.0005*%
%ADD21C,.002*%
%ADD22C,.006*%
%ADD23C,.008*%
%ADD24C,.03*%
%ADD25C,.032*%
G75*
%LPD*%
G75*
G36*
G01X44520Y917888D02*
X73120D01*
Y905488D01*
X44520D01*
Y917888D01*
G37*
G36*
G01X97207Y733804D02*
Y748204D01*
X61337D01*
Y733804D01*
X97207D01*
G37*
G36*
G01X67372Y812204D02*
X58572D01*
Y816804D01*
X67372D01*
Y812204D01*
G37*
G36*
G01X66153Y871452D02*
Y857052D01*
X102023D01*
Y871452D01*
X66153D01*
G37*
G36*
G01X103304Y917920D02*
X131904D01*
Y905520D01*
X103304D01*
Y917920D01*
G37*
G36*
G01X138300Y847600D02*
Y838800D01*
X133700D01*
Y847600D01*
X138300D01*
G37*
G36*
G01X161387Y318281D02*
X163887Y320781D01*
X158887D01*
X161387Y318281D01*
G37*
G36*
G01X184743Y546896D02*
X174743D01*
Y551896D01*
X184743D01*
Y546896D01*
G37*
G36*
G01X184005Y576450D02*
X187005Y573450D01*
Y576450D01*
X184005D01*
G37*
G36*
G01X208150Y867350D02*
X213150Y872350D01*
X208150D01*
Y867350D01*
G37*
G36*
G01X242300Y887800D02*
X244000Y889500D01*
X245700Y887800D01*
X242300D01*
G37*
G36*
G01X234299Y912711D02*
X236299Y910711D01*
Y914711D01*
X234299Y912711D01*
G37*
G36*
G01X313822Y87424D02*
Y82424D01*
X318822Y87424D01*
X313822D01*
G37*
G36*
G01X352040Y228078D02*
Y234078D01*
X346040Y228078D01*
X352040D01*
G37*
G36*
G01X346329Y246400D02*
X344929Y247800D01*
X346329Y249200D01*
Y246400D01*
G37*
G36*
G01X335723Y454183D02*
Y462983D01*
X340323D01*
Y454183D01*
X335723D01*
G37*
G36*
G01X339823Y485383D02*
Y476583D01*
X335223D01*
Y485383D01*
X339823D01*
G37*
G36*
G01X340500Y938200D02*
X369100D01*
Y925800D01*
X340500D01*
Y938200D01*
G37*
G36*
G01X373000Y881700D02*
Y911000D01*
X387000D01*
Y881700D01*
X373000D01*
G37*
G36*
G01X391379Y258950D02*
X394379Y255950D01*
Y258950D01*
X391379D01*
G37*
G36*
G01X397498Y310942D02*
X389632Y318808D01*
X397498D01*
Y310942D01*
G37*
G36*
G01X392500Y938700D02*
X421100D01*
Y926300D01*
X392500D01*
Y938700D01*
G37*
G36*
G01X503765Y321825D02*
X496483D01*
G03X494461I-1011J-1550D01*
G01X409869D01*
G03X407847I-1011J-1550D01*
G01X400565D01*
Y329107D01*
G03Y331129I-1550J1011D01*
G01Y415721D01*
G03Y417743I-1550J1011D01*
G01Y425025D01*
X407847D01*
G03X409869I1011J1550D01*
G01X494461D01*
G03X496483I1011J1550D01*
G01X503765D01*
Y417743D01*
G03Y415721I1550J-1011D01*
G01Y331129D01*
G03Y329107I1550J-1011D01*
G01Y321825D01*
G37*
G36*
G01X437855Y275350D02*
X445855D01*
Y284450D01*
X437855D01*
Y275350D01*
G37*
G36*
G01X477923Y293383D02*
X479323Y294783D01*
X480723Y293383D01*
X477923D01*
G37*
G36*
G01X559205Y344078D02*
Y352078D01*
X550105D01*
Y344078D01*
X559205D01*
G37*
G36*
G01X643974Y576978D02*
Y585778D01*
X648574D01*
Y576978D01*
X643974D01*
G37*
G36*
G01X658962Y442614D02*
X663012D01*
X658962Y446664D01*
Y442614D01*
G37*
G36*
G01X710968Y773184D02*
Y764184D01*
X702968D01*
Y773184D01*
X710968D01*
G37*
G36*
G01X708968Y808684D02*
Y799684D01*
X700968D01*
Y808684D01*
X708968D01*
G37*
G36*
G01X739516Y139084D02*
X734516D01*
X739516Y134084D01*
Y139084D01*
G37*
G36*
G01X736060Y202435D02*
Y199565D01*
X730940D01*
Y202435D01*
X736060D01*
G37*
G36*
G01X727700Y572400D02*
Y581200D01*
X732300D01*
Y572400D01*
X727700D01*
G37*
G36*
G01X740300Y64540D02*
Y52600D01*
X744700D01*
Y64540D01*
X740300D01*
G37*
G36*
G01X755884Y547291D02*
X767084D01*
Y564691D01*
X755884D01*
Y547291D01*
G37*
G36*
G01X763800Y897900D02*
Y880100D01*
X749200D01*
Y897900D01*
X763800D01*
G37*
G36*
G01X774394Y581568D02*
Y572768D01*
X769794D01*
Y581568D01*
X774394D01*
G37*
G36*
G01X788768Y759384D02*
Y748184D01*
X806168D01*
Y759384D01*
X788768D01*
G37*
G36*
G01X796674Y460978D02*
X791674D01*
X796674Y455978D01*
Y460978D01*
G37*
G36*
G01X832924Y387728D02*
X837924D01*
X832924Y392728D01*
Y387728D01*
G37*
G36*
G01X869300Y636900D02*
X870700Y635500D01*
Y638300D01*
X869300Y636900D01*
G37*
G36*
G01X876700Y724900D02*
Y736100D01*
X859300D01*
Y724900D01*
X876700D01*
G37*
G36*
G01X965608Y382765D02*
X948358D01*
Y377235D01*
X965608D01*
Y382765D01*
G37*
G36*
G01X972756Y365300D02*
X970256Y362800D01*
X975256D01*
X972756Y365300D01*
G37*
G36*
G01X1001674Y198378D02*
X1012874D01*
Y215778D01*
X1001674D01*
Y198378D01*
G37*
G36*
G01X993900Y517700D02*
X1002700D01*
Y522300D01*
X993900D01*
Y517700D01*
G37*
G36*
G01X1007900D02*
X1016700D01*
Y522300D01*
X1007900D01*
Y517700D01*
G37*
G36*
G01X1035168Y141434D02*
X1039218D01*
X1035168Y145484D01*
Y141434D01*
G37*
G36*
G01X1049066Y870618D02*
Y875618D01*
X1044066Y870618D01*
X1049066D01*
G37*
G36*
G01X1061700Y266200D02*
X1060000Y264500D01*
X1058300Y266200D01*
X1061700D01*
G37*
G36*
G01X1095500Y82500D02*
X1085500D01*
Y87500D01*
X1095500D01*
Y82500D01*
G37*
G36*
G01X1098925Y107448D02*
Y102448D01*
X1096425Y104948D01*
X1098925Y107448D01*
G37*
G36*
G01X1088468Y736406D02*
Y741406D01*
X1090968Y738906D01*
X1088468Y736406D01*
G37*
G36*
G01X1137300Y564900D02*
X1109700D01*
Y427100D01*
X1137300D01*
Y564900D01*
G37*
G36*
G01X1130318Y884134D02*
X1125318D01*
X1130318Y879134D01*
Y884134D01*
G37*
G36*
G01X1157668Y230184D02*
Y241384D01*
X1140268D01*
Y230184D01*
X1157668D01*
G37*
G36*
G01X1170300Y565400D02*
X1142700D01*
Y427600D01*
X1170300D01*
Y565400D01*
G37*
G36*
G01X1150722Y573566D02*
Y568566D01*
X1153222Y571066D01*
X1150722Y573566D01*
G37*
G36*
G01X1164334Y598472D02*
X1175534D01*
Y615872D01*
X1164334D01*
Y598472D01*
G37*
G36*
G01X1181950Y386000D02*
Y378000D01*
X1191050D01*
Y386000D01*
X1181950D01*
G37*
G36*
G01X1200600Y530300D02*
Y502700D01*
X1338400D01*
Y530300D01*
X1200600D01*
G37*
G36*
G01X1204300Y788000D02*
X1213300D01*
Y780000D01*
X1204300D01*
Y788000D01*
G37*
G36*
G01X1220106Y377378D02*
Y189552D01*
X1227926D01*
Y377378D01*
X1220106D01*
G37*
G36*
G01X1227700Y574740D02*
Y578940D01*
X1225600Y576840D01*
X1227700Y574740D01*
G37*
G36*
G01X1234150Y764600D02*
X1229150Y769600D01*
Y764600D01*
X1234150D01*
G37*
G36*
G01X1238103Y190563D02*
X1240103Y188563D01*
Y192563D01*
X1238103Y190563D01*
G37*
G36*
G01X1255668Y430434D02*
X1259718D01*
X1255668Y434484D01*
Y430434D01*
G37*
G36*
G01X1259400Y581800D02*
X1270600D01*
Y599200D01*
X1259400D01*
Y581800D01*
G37*
G36*
G01X1275984Y24087D02*
X1273984Y26087D01*
X1277984D01*
X1275984Y24087D01*
G37*
G36*
G01X1291722Y307800D02*
Y290600D01*
X1310522D01*
Y307800D01*
X1291722D01*
G37*
G36*
G01X1302584Y816632D02*
Y805432D01*
X1319984D01*
Y816632D01*
X1302584D01*
G37*
G36*
G01X1347084Y316511D02*
Y286153D01*
X1384084D01*
Y316511D01*
X1347084D01*
G37*
G36*
G01X1384343Y288632D02*
X1346834D01*
Y314032D01*
X1384343D01*
Y288632D01*
G37*
G36*
G01X1351900Y446400D02*
X1346900D01*
X1351900Y441400D01*
Y446400D01*
G37*
G36*
G01X1340917Y560762D02*
X1344317D01*
X1342617Y559062D01*
X1340917Y560762D01*
G37*
G36*
G01X1360417Y582612D02*
X1355417Y577612D01*
X1360417D01*
Y582612D01*
G37*
G36*
G01X1396612Y112930D02*
Y107930D01*
X1394112Y110430D01*
X1396612Y112930D01*
G37*
%LPC*%
G75*
G54D24*
X402952Y410827D03*
Y406890D03*
Y402953D03*
Y399016D03*
Y395079D03*
Y391142D03*
Y387205D03*
Y383268D03*
Y379331D03*
Y375394D03*
Y371456D03*
Y367519D03*
Y363582D03*
Y359645D03*
Y355708D03*
Y351771D03*
Y347834D03*
Y343897D03*
Y339960D03*
Y336023D03*
X406889Y410827D03*
Y406890D03*
Y402953D03*
Y399016D03*
Y395079D03*
Y391142D03*
Y387205D03*
Y383268D03*
Y379331D03*
Y375394D03*
Y371456D03*
Y367519D03*
Y363582D03*
Y359645D03*
Y355708D03*
Y351771D03*
Y347834D03*
Y343897D03*
Y339960D03*
Y336023D03*
X410826Y410827D03*
Y406890D03*
Y402953D03*
Y399016D03*
Y395079D03*
Y391142D03*
Y387205D03*
Y383268D03*
Y379331D03*
Y375394D03*
Y371456D03*
Y367519D03*
Y363582D03*
Y359645D03*
Y355708D03*
Y351771D03*
Y347834D03*
Y343897D03*
Y339960D03*
Y336023D03*
X414763Y422638D03*
Y418701D03*
Y414764D03*
Y410827D03*
Y406890D03*
Y402953D03*
Y399016D03*
Y395079D03*
Y391142D03*
Y387205D03*
Y383268D03*
Y379331D03*
Y375394D03*
Y371456D03*
Y367519D03*
Y363582D03*
Y359645D03*
Y355708D03*
Y351771D03*
Y347834D03*
Y343897D03*
Y339960D03*
Y336023D03*
Y332086D03*
Y328149D03*
Y324212D03*
X418700Y422638D03*
Y418701D03*
Y414764D03*
Y410827D03*
Y406890D03*
Y402953D03*
Y399016D03*
Y395079D03*
Y391142D03*
Y387205D03*
Y383268D03*
Y379331D03*
Y375394D03*
Y371456D03*
Y367519D03*
Y363582D03*
Y359645D03*
Y355708D03*
Y351771D03*
Y347834D03*
Y343897D03*
Y339960D03*
Y336023D03*
Y332086D03*
Y328149D03*
Y324212D03*
X422637Y422638D03*
Y418701D03*
Y414764D03*
Y410827D03*
Y406890D03*
Y402953D03*
Y399016D03*
Y395079D03*
Y391142D03*
Y387205D03*
Y383268D03*
Y379331D03*
Y375394D03*
Y371456D03*
Y367519D03*
Y363582D03*
Y359645D03*
Y355708D03*
Y351771D03*
Y347834D03*
Y343897D03*
Y339960D03*
Y336023D03*
Y332086D03*
Y328149D03*
Y324212D03*
X426574Y422638D03*
Y418701D03*
Y414764D03*
Y410827D03*
Y406890D03*
Y402953D03*
Y399016D03*
Y395079D03*
Y391142D03*
Y387205D03*
Y383268D03*
Y379331D03*
Y375394D03*
Y371456D03*
Y367519D03*
Y363582D03*
Y359645D03*
Y355708D03*
Y351771D03*
Y347834D03*
Y343897D03*
Y339960D03*
Y336023D03*
Y332086D03*
Y328149D03*
Y324212D03*
X430511Y422638D03*
Y418701D03*
Y414764D03*
Y410827D03*
Y406890D03*
Y402953D03*
Y399016D03*
Y395079D03*
Y391142D03*
Y387205D03*
Y383268D03*
Y379331D03*
Y375394D03*
Y371456D03*
Y367519D03*
Y363582D03*
Y359645D03*
Y355708D03*
Y351771D03*
Y347834D03*
Y343897D03*
Y339960D03*
Y336023D03*
Y332086D03*
Y328149D03*
Y324212D03*
X434448Y422638D03*
Y418701D03*
Y414764D03*
Y410827D03*
Y406890D03*
Y402953D03*
Y399016D03*
Y395079D03*
Y391142D03*
Y387205D03*
Y383268D03*
Y379331D03*
Y375394D03*
Y371456D03*
Y367519D03*
Y363582D03*
Y359645D03*
Y355708D03*
Y351771D03*
Y347834D03*
Y343897D03*
Y339960D03*
Y336023D03*
Y332086D03*
Y328149D03*
Y324212D03*
X438385Y422638D03*
Y418701D03*
Y414764D03*
Y410827D03*
Y406890D03*
Y402953D03*
Y399016D03*
Y395079D03*
Y391142D03*
Y387205D03*
Y383268D03*
Y379331D03*
Y375394D03*
Y371456D03*
Y367519D03*
Y363582D03*
Y359645D03*
Y355708D03*
Y351771D03*
Y347834D03*
Y343897D03*
Y339960D03*
Y336023D03*
Y332086D03*
Y328149D03*
Y324212D03*
X442322Y422638D03*
Y418701D03*
Y414764D03*
Y410827D03*
Y406890D03*
Y402953D03*
Y399016D03*
Y395079D03*
Y391142D03*
Y387205D03*
Y383268D03*
Y379331D03*
Y375394D03*
Y371456D03*
Y367519D03*
Y363582D03*
Y359645D03*
Y355708D03*
Y351771D03*
Y347834D03*
Y343897D03*
Y339960D03*
Y336023D03*
Y332086D03*
Y328149D03*
Y324212D03*
X446259Y422638D03*
Y418701D03*
Y414764D03*
Y410827D03*
Y406890D03*
Y402953D03*
Y399016D03*
Y395079D03*
Y391142D03*
Y387205D03*
Y383268D03*
Y379331D03*
Y375394D03*
Y371456D03*
Y367519D03*
Y363582D03*
Y359645D03*
Y355708D03*
Y351771D03*
Y347834D03*
Y343897D03*
Y339960D03*
Y336023D03*
Y332086D03*
Y328149D03*
Y324212D03*
X450196Y422638D03*
Y418701D03*
Y414764D03*
Y410827D03*
Y406890D03*
Y402953D03*
Y399016D03*
Y395079D03*
Y391142D03*
Y387205D03*
Y383268D03*
Y379331D03*
Y375394D03*
Y371456D03*
Y367519D03*
Y363582D03*
Y359645D03*
Y355708D03*
Y351771D03*
Y347834D03*
Y343897D03*
Y339960D03*
Y336023D03*
Y332086D03*
Y328149D03*
Y324212D03*
X454134Y422638D03*
Y418701D03*
Y414764D03*
Y410827D03*
Y406890D03*
Y402953D03*
Y399016D03*
Y395079D03*
Y391142D03*
Y387205D03*
Y383268D03*
Y379331D03*
Y375394D03*
Y371456D03*
Y367519D03*
Y363582D03*
Y359645D03*
Y355708D03*
Y351771D03*
Y347834D03*
Y343897D03*
Y339960D03*
Y336023D03*
Y332086D03*
Y328149D03*
Y324212D03*
X458071Y422638D03*
Y418701D03*
Y414764D03*
Y410827D03*
Y406890D03*
Y402953D03*
Y399016D03*
Y395079D03*
Y391142D03*
Y387205D03*
Y383268D03*
Y379331D03*
Y375394D03*
Y371456D03*
Y367519D03*
Y363582D03*
Y359645D03*
Y355708D03*
Y351771D03*
Y347834D03*
Y343897D03*
Y339960D03*
Y336023D03*
Y332086D03*
Y328149D03*
Y324212D03*
X462008Y422638D03*
Y418701D03*
Y414764D03*
Y410827D03*
Y406890D03*
Y402953D03*
Y399016D03*
Y395079D03*
Y391142D03*
Y387205D03*
Y383268D03*
Y379331D03*
Y375394D03*
Y371456D03*
Y367519D03*
Y363582D03*
Y359645D03*
Y355708D03*
Y351771D03*
Y347834D03*
Y343897D03*
Y339960D03*
Y336023D03*
Y332086D03*
Y328149D03*
Y324212D03*
X465945Y422638D03*
Y418701D03*
Y414764D03*
Y410827D03*
Y406890D03*
Y402953D03*
Y399016D03*
Y395079D03*
Y391142D03*
Y387205D03*
Y383268D03*
Y379331D03*
Y375394D03*
Y371456D03*
Y367519D03*
Y363582D03*
Y359645D03*
Y355708D03*
Y351771D03*
Y347834D03*
Y343897D03*
Y339960D03*
Y336023D03*
Y332086D03*
Y328149D03*
Y324212D03*
X469882Y422638D03*
Y418701D03*
Y414764D03*
Y410827D03*
Y406890D03*
Y402953D03*
Y399016D03*
Y395079D03*
Y391142D03*
Y387205D03*
Y383268D03*
Y379331D03*
Y375394D03*
Y371456D03*
Y367519D03*
Y363582D03*
Y359645D03*
Y355708D03*
Y351771D03*
Y347834D03*
Y343897D03*
Y339960D03*
Y336023D03*
Y332086D03*
Y328149D03*
Y324212D03*
X473819Y422638D03*
Y418701D03*
Y414764D03*
Y410827D03*
Y406890D03*
Y402953D03*
Y399016D03*
Y395079D03*
Y391142D03*
Y387205D03*
Y383268D03*
Y379331D03*
Y375394D03*
Y371456D03*
Y367519D03*
Y363582D03*
Y359645D03*
Y355708D03*
Y351771D03*
Y347834D03*
Y343897D03*
Y339960D03*
Y336023D03*
Y332086D03*
Y328149D03*
Y324212D03*
X477756Y422638D03*
Y418701D03*
Y414764D03*
Y410827D03*
Y406890D03*
Y402953D03*
Y399016D03*
Y395079D03*
Y391142D03*
Y387205D03*
Y383268D03*
Y379331D03*
Y375394D03*
Y371456D03*
Y367519D03*
Y363582D03*
Y359645D03*
Y355708D03*
Y351771D03*
Y347834D03*
Y343897D03*
Y339960D03*
Y336023D03*
Y332086D03*
Y328149D03*
Y324212D03*
X481693Y422638D03*
Y418701D03*
Y414764D03*
Y410827D03*
Y406890D03*
Y402953D03*
Y399016D03*
Y395079D03*
Y391142D03*
Y387205D03*
Y383268D03*
Y379331D03*
Y375394D03*
Y371456D03*
Y367519D03*
Y363582D03*
Y359645D03*
Y355708D03*
Y351771D03*
Y347834D03*
Y343897D03*
Y339960D03*
Y336023D03*
Y332086D03*
Y328149D03*
Y324212D03*
X485630Y422638D03*
Y418701D03*
Y414764D03*
Y410827D03*
Y406890D03*
Y402953D03*
Y399016D03*
Y395079D03*
Y391142D03*
Y387205D03*
Y383268D03*
Y379331D03*
Y375394D03*
Y371456D03*
Y367519D03*
Y363582D03*
Y359645D03*
Y355708D03*
Y351771D03*
Y347834D03*
Y343897D03*
Y339960D03*
Y336023D03*
Y332086D03*
Y328149D03*
Y324212D03*
X489567Y422638D03*
Y418701D03*
Y414764D03*
Y410827D03*
Y406890D03*
Y402953D03*
Y399016D03*
Y395079D03*
Y391142D03*
Y387205D03*
Y383268D03*
Y379331D03*
Y375394D03*
Y371456D03*
Y367519D03*
Y363582D03*
Y359645D03*
Y355708D03*
Y351771D03*
Y347834D03*
Y343897D03*
Y339960D03*
Y336023D03*
Y332086D03*
Y328149D03*
Y324212D03*
X493504Y410827D03*
Y406890D03*
Y402953D03*
Y399016D03*
Y395079D03*
Y391142D03*
Y387205D03*
Y383268D03*
Y379331D03*
Y375394D03*
Y371456D03*
Y367519D03*
Y363582D03*
Y359645D03*
Y355708D03*
Y351771D03*
Y347834D03*
Y343897D03*
Y339960D03*
Y336023D03*
X497441Y410827D03*
Y406890D03*
Y402953D03*
Y399016D03*
Y395079D03*
Y391142D03*
Y387205D03*
Y383268D03*
Y379331D03*
Y375394D03*
Y371456D03*
Y367519D03*
Y363582D03*
Y359645D03*
Y355708D03*
Y351771D03*
Y347834D03*
Y343897D03*
Y339960D03*
Y336023D03*
X501378Y410827D03*
Y406890D03*
Y402953D03*
Y399016D03*
Y395079D03*
Y391142D03*
Y387205D03*
Y383268D03*
Y379331D03*
Y375394D03*
Y371456D03*
Y367519D03*
Y363582D03*
Y359645D03*
Y355708D03*
Y351771D03*
Y347834D03*
Y343897D03*
Y339960D03*
Y336023D03*
G54D25*
X402952Y418701D03*
Y414764D03*
Y332086D03*
Y328149D03*
X406889Y422638D03*
Y418701D03*
Y414764D03*
Y332086D03*
Y328149D03*
Y324212D03*
X410826Y422638D03*
Y418701D03*
Y414764D03*
Y332086D03*
Y328149D03*
Y324212D03*
X493504Y422638D03*
Y418701D03*
Y414764D03*
Y332086D03*
Y328149D03*
Y324212D03*
X497441Y422638D03*
Y418701D03*
Y414764D03*
Y332086D03*
Y328149D03*
Y324212D03*
X501378Y418701D03*
Y414764D03*
Y332086D03*
Y328149D03*
%LPD*%
G75*
G54D10*
X442278Y846000D03*
X455278D03*
X451278D03*
X459278D03*
X467278D03*
G54D20*
G01X121606Y312841D02*
X121503D01*
G01X121681Y312916D02*
X121428D01*
G01X121756Y312991D02*
X121353D01*
G01X121831Y313066D02*
X121278D01*
G01X121906Y313141D02*
X121203D01*
G01X121981Y313216D02*
X121128D01*
G01X122056Y313291D02*
X121053D01*
G01X122131Y313366D02*
X120978D01*
G01X122206Y313441D02*
X120903D01*
G01X122281Y313516D02*
X120828D01*
G01X122356Y313591D02*
X120753D01*
G01X122431Y313666D02*
X120678D01*
G01X122506Y313741D02*
X120603D01*
G01X122581Y313816D02*
X120528D01*
G01X120485Y313900D02*
X122638Y313883D01*
G01X122691Y313926D02*
X121554Y312788D01*
G01D02*
X120415Y313928D01*
G01X120474D02*
X122634D01*
G01X122690D02*
X120415D01*
G01X122618Y313853D02*
X120490D01*
G01X122543Y313778D02*
X120565D01*
G01X122468Y313703D02*
X120640D01*
G01X122393Y313628D02*
X120715D01*
G01X122318Y313553D02*
X120790D01*
G01X122243Y313478D02*
X120865D01*
G01X122168Y313403D02*
X120940D01*
G01X122093Y313328D02*
X121015D01*
G01X122018Y313253D02*
X121090D01*
G01X121943Y313178D02*
X121165D01*
G01X121868Y313103D02*
X121240D01*
G01X121793Y313028D02*
X121315D01*
G01X121718Y312953D02*
X121390D01*
G01X121643Y312878D02*
X121465D01*
G01X121568Y312803D02*
X121540D01*
G01X143143Y309731D02*
X143040D01*
G01X143218Y309806D02*
X142965D01*
G01X143293Y309881D02*
X142890D01*
G01X143368Y309956D02*
X142815D01*
G01X143443Y310031D02*
X142740D01*
G01X143518Y310106D02*
X142665D01*
G01X143593Y310181D02*
X142590D01*
G01X143668Y310256D02*
X142515D01*
G01X143743Y310331D02*
X142440D01*
G01X143818Y310406D02*
X142365D01*
G01X143893Y310481D02*
X142290D01*
G01X143968Y310556D02*
X142215D01*
G01X144043Y310631D02*
X142140D01*
G01X144118Y310706D02*
X142065D01*
G01X142022Y310790D02*
X144175Y310773D01*
G01X144228Y310816D02*
X143091Y309678D01*
G01D02*
X141952Y310818D01*
G01X142011D02*
X144171D01*
G01X144227D02*
X141952D01*
G01X144155Y310743D02*
X142027D01*
G01X144080Y310668D02*
X142102D01*
G01X144005Y310593D02*
X142177D01*
G01X143930Y310518D02*
X142252D01*
G01X143855Y310443D02*
X142327D01*
G01X143780Y310368D02*
X142402D01*
G01X143705Y310293D02*
X142477D01*
G01X143630Y310218D02*
X142552D01*
G01X143555Y310143D02*
X142627D01*
G01X143480Y310068D02*
X142702D01*
G01X143405Y309993D02*
X142777D01*
G01X143330Y309918D02*
X142852D01*
G01X143255Y309843D02*
X142927D01*
G01X143180Y309768D02*
X143002D01*
G01X143105Y309693D02*
X143077D01*
G54D11*
G01X86004Y-25590D02*
G03X75532I-5236J0D01*
G01X117499D02*
G03X107027I-5236J0D01*
G01X148994D02*
G03X138522I-5236J0D01*
G01X180490D02*
G03X170017I-5236J0D01*
G01X211985D02*
G03X201512I-5236J0D01*
G01X243480D02*
G03X233007I-5236J0D01*
G54D21*
G01X367170Y809090D02*
X366510D01*
G01X366610Y809180D02*
X367270D01*
G01X367360Y809290D02*
X366710D01*
G01X366810Y809380D02*
X367460D01*
G01X367560Y809490D02*
X366900D01*
G01X367000Y809590D02*
X367650D01*
G01X367750Y809680D02*
X367100D01*
G01X367190Y809790D02*
X367850D01*
G01X367940Y809880D02*
X367290D01*
G01X367380Y809990D02*
X368040D01*
G01X368140Y810090D02*
X367480D01*
G01X367580Y810180D02*
X368230D01*
G01X368330Y810290D02*
X367685D01*
G01X367680D02*
X367730D01*
G01X367770Y810380D02*
X367810D01*
G01X367770D02*
X368420D01*
G01X368520Y810490D02*
X367870D01*
G01X367970Y810590D02*
X368620D01*
G01X368720Y810680D02*
X368060D01*
G01X368160Y810790D02*
X368810D01*
G01X368910Y810880D02*
X368250D01*
G01X368350Y810990D02*
X369010D01*
G01X369100Y811090D02*
X368450D01*
G01X368550Y811180D02*
X369200D01*
G01X369290Y811290D02*
X368640D01*
G01X368740Y811380D02*
X369390D01*
G01X369490Y811490D02*
X368830D01*
G01X368930Y811590D02*
X369590D01*
G01X369680Y811680D02*
X369030D01*
G01X374510Y809680D02*
X375160D01*
G01X371030Y810280D02*
X371140D01*
G01X371030Y810290D02*
Y810280D01*
G01X370830Y812640D02*
X371030Y810290D01*
G01X371130Y810380D02*
X371020D01*
G01X371025D02*
X376620D01*
G01X376685Y810290D02*
X371030D01*
G01X371270Y809240D02*
X372160D01*
G01X371230Y809280D02*
X371270Y809240D01*
G01X371230Y809960D02*
Y809280D01*
G01X371200Y810030D02*
X371230Y809960D01*
G01X371050Y810190D02*
X371200Y810030D01*
G01X371040Y810210D02*
X371050Y810190D01*
G01X371030Y810270D02*
X371040Y810210D01*
G01X372200Y809290D02*
X371230D01*
G01Y809490D02*
X372200D01*
G01Y809680D02*
X371230D01*
G01Y809880D02*
X372200D01*
G01X371480Y810590D02*
X371010D01*
G01X370990Y810680D02*
X371460D01*
G01X371450Y810880D02*
X370980D01*
G01X370960Y811090D02*
X371430D01*
G01X371410Y811290D02*
X370940D01*
G01X370930Y811490D02*
X371400D01*
G01X371380Y811680D02*
X370910D01*
G01X371150Y810090D02*
X376930D01*
G01X371470Y810660D02*
X371250Y813240D01*
G01X371470Y810590D02*
Y810660D01*
G01X371570Y810500D02*
X371470Y810590D01*
G01X375670Y810500D02*
X371570D01*
G01X371390Y811590D02*
X370920D01*
G01X370940Y811380D02*
X371400D01*
G01X371420Y811180D02*
X370960D01*
G01X370970Y810990D02*
X371440D01*
G01X371460Y810790D02*
X370990D01*
G01X371220Y809990D02*
X372270D01*
G01X372200Y809280D02*
X372160Y809240D01*
G01X372200Y809920D02*
Y809280D01*
G01X372300Y810020D02*
X372200Y809920D01*
G01Y809380D02*
X371230D01*
G01Y809590D02*
X372200D01*
G01Y809790D02*
X371230D01*
G01X375770Y810970D02*
Y810980D01*
G01X375760Y810900D02*
X375770Y810970D01*
G01X375760Y810640D02*
Y810900D01*
G01X375770Y810620D02*
X375760Y810640D01*
G01X375670Y810500D02*
X375770Y810620D01*
G01Y810990D02*
X376540D01*
G01X376500Y810790D02*
X375760D01*
G01X375740Y810590D02*
X376540D01*
G01X375810Y811160D02*
X375770Y810980D01*
G01X375810Y811170D02*
Y811160D01*
G01X375920Y811480D02*
X375810Y811170D01*
G01X375930Y811490D02*
X375920Y811480D01*
G01X376140Y811800D02*
X375930Y811490D01*
G01X375760Y810880D02*
X376520D01*
G01X376560Y810490D02*
X371010D01*
G01X376550Y810510D02*
X376560Y810490D01*
G01X376500Y810770D02*
X376550Y810510D01*
G01X376500Y810780D02*
Y810770D01*
G01Y810800D02*
Y810780D01*
G01X371050Y810180D02*
X376790D01*
G01X376710Y810250D02*
X376650Y810340D01*
G01X376720Y810240D02*
X376710Y810250D01*
G01X376730Y810230D02*
X376720Y810240D01*
G01X376570Y810480D02*
X376560Y810490D01*
G01X376650Y810350D02*
X376570Y810480D01*
G01X376520Y810680D02*
X375760D01*
G01X375790Y811090D02*
X376560D01*
G01X376550Y811060D02*
X376500Y810800D01*
G01X376560Y811080D02*
X376550Y811060D01*
G01X376780Y810810D02*
X376790Y810830D01*
G01X376730Y811340D02*
X376950Y811500D01*
G01X376720Y811330D02*
X376730Y811340D01*
G01X376710Y811310D02*
X376720Y811330D01*
G01X376570Y811100D02*
X376710Y811310D01*
G01X376560Y811080D02*
X376570Y811100D01*
G01X376790Y811380D02*
X375890D01*
G01X375850Y811290D02*
X376690D01*
G01X376620Y811180D02*
X375810D01*
G01X375990Y811590D02*
X377250D01*
G01X378790Y811680D02*
X376070D01*
G01X376650Y810290D02*
X376690D01*
G01X376730Y810230D02*
X376950Y810070D01*
G01X376520Y809490D02*
X378070D01*
G01X378230Y809590D02*
X376340D01*
G01X375900Y810020D02*
X372300D01*
G01X375980Y809990D02*
X375900Y810020D01*
G01X375990Y809980D02*
X375980Y809990D01*
G01X375990Y809970D02*
Y809980D01*
G01X376030Y809900D02*
X375990Y809970D01*
G01X376040Y809900D02*
X376030D01*
G01X376050Y809890D02*
X376040Y809900D01*
G01X376120Y809790D02*
X376050Y809890D01*
G01X376130Y809780D02*
X376120Y809790D01*
G01X376360Y809560D02*
X376130Y809780D01*
G01Y809790D02*
X378470D01*
G01X376380Y809550D02*
X376360Y809560D01*
G01X377180Y809250D02*
X377520Y809260D01*
G01X377170Y809250D02*
X377180D01*
G01X377160D02*
X377170D01*
G01X377000Y809270D02*
X377160Y809250D01*
G01X376980Y809270D02*
X377000D01*
G01X376380Y809550D02*
X376980Y809270D01*
G01X377630Y809290D02*
X376960D01*
G01Y810060D02*
X376950Y810070D01*
G01X376980Y810060D02*
X376960D01*
G01X377150Y810000D02*
X376980Y810060D01*
G01X377370Y809990D02*
X377390D01*
G01X377240D02*
X377370D01*
G01X377170Y810000D02*
X377240Y809990D01*
G01X377150Y810000D02*
X377170D01*
G01X376810Y810620D02*
X376780Y810810D01*
G01X376820Y810590D02*
X376810Y810620D01*
G01X376990Y810370D02*
X376820Y810590D01*
G01X377010Y810360D02*
X376990Y810370D01*
G01X377180Y810280D02*
X377010Y810360D01*
G01X377190Y810280D02*
X377180D01*
G01X377230Y810270D02*
X377190Y810280D01*
G01X377290Y810270D02*
X377230D01*
G01X377310D02*
X377290D01*
G01X377340Y811300D02*
X377350D01*
G01X377250D02*
X377340D01*
G01X377230Y811290D02*
X377250Y811300D01*
G01X376920Y811130D02*
X377230Y811290D01*
G01X376900Y811110D02*
X376920Y811130D01*
G01X376790Y810830D02*
X376900Y811110D01*
G01X376960Y811510D02*
X376950Y811500D01*
G01X376980Y811510D02*
X376960D01*
G01X377150Y811570D02*
X376980Y811510D01*
G01X377170Y811570D02*
X377150D01*
G01X377240Y811580D02*
X377170Y811570D01*
G01X377260Y811590D02*
X377240Y811580D01*
G01X377320Y811590D02*
X377260D01*
G01X377350Y811580D02*
X377320Y811590D01*
G01X376930Y811490D02*
X375930D01*
G01X376840Y810970D02*
X377780D01*
G01X377800Y810770D02*
X376790D01*
G01X376840Y810570D02*
X377750D01*
G01X377570Y810370D02*
X377000D01*
G01X377310Y810270D02*
X377440Y810290D01*
G01X377640Y811160D02*
X376990D01*
G01X377390Y811580D02*
X377590Y811530D01*
G01X377350Y811580D02*
X377390D01*
G01X378980Y811490D02*
X377650D01*
G01X377630Y811510D02*
X377590Y811530D01*
G01X377630Y811510D02*
X377940Y811250D01*
G01X377710Y811070D02*
X376880D01*
G01X376800Y810870D02*
X377790D01*
G01X377600Y811200D02*
X377350Y811300D01*
G01X377620Y811190D02*
X377600Y811200D01*
G01X377770Y810990D02*
X377620Y811190D01*
G01X377780Y810960D02*
X377770Y810990D01*
G01X377440Y811270D02*
X377170D01*
G01X377460Y810290D02*
X377440D01*
G01X377680Y810430D02*
X377460Y810290D01*
G01X377690Y810450D02*
X377680Y810430D01*
G01X377800Y810680D02*
X377690Y810450D01*
G01X377810Y810700D02*
X377800Y810680D01*
G01X377780Y810960D02*
X377810Y810700D01*
G01X377650Y810090D02*
X378670D01*
G01X377530Y809260D02*
X377520D01*
G01X377820Y809330D02*
X377530Y809260D01*
G01X377830Y809340D02*
X377820Y809330D01*
G01X378340Y809650D02*
X377830Y809340D01*
G01X377590Y810040D02*
X377630Y810060D01*
G01X377390Y809990D02*
X377590Y810040D01*
G01X377700Y810470D02*
X376920D01*
G01X376800Y810660D02*
X377800D01*
G01X375980Y809990D02*
X378610D01*
G01X378430Y809740D02*
X378340Y809650D01*
G01X378490Y809810D02*
X378430Y809740D01*
G01X378620Y810000D02*
X378490Y809810D01*
G01X378380Y809680D02*
X376230D01*
G01X376050Y809880D02*
X378540D01*
G01X378740Y810250D02*
X378800Y810420D01*
G01X378700Y810150D02*
X378740Y810250D01*
G01X378700Y810140D02*
Y810150D01*
G01X378630Y810010D02*
X378700Y810140D01*
G01X378620Y810000D02*
X378630Y810010D01*
G01X378790Y810380D02*
X377975D01*
G01X377980D02*
X378040D01*
G01X377940Y810320D02*
X377630Y810060D01*
G01X377970Y810370D02*
X377940Y810320D01*
G01X377770Y810180D02*
X378720D01*
G01X378750Y810290D02*
X377960D01*
G01X378720D02*
X378750D01*
G01X377970Y811200D02*
X377940Y811250D01*
G01X378090Y810810D02*
X377970Y811200D01*
G01X378090Y810750D02*
Y810810D01*
G01X377970Y810370D02*
X378090Y810750D01*
G01X377900Y811290D02*
X379160D01*
G01X379350Y811090D02*
X378010D01*
G01X378070Y810880D02*
X379530D01*
G01X378830Y810680D02*
X378070D01*
G01X378010Y810490D02*
X378810D01*
G01X377900Y809380D02*
X376740D01*
G01X378880Y811590D02*
X377330D01*
G01X377770Y811380D02*
X379070D01*
G01X379250Y811180D02*
X377980D01*
G01X378030Y810990D02*
X379440D01*
G01X379630Y810790D02*
X378940D01*
G01X378800Y810440D02*
Y810420D01*
G01X378840Y810710D02*
X378800Y810440D01*
G01X378900Y810790D02*
X378840Y810710D01*
G01X378820Y810590D02*
X378040D01*
G01X378900Y810790D02*
X379010Y810770D01*
G01X378090Y810790D02*
X378900D01*
G01X382470Y807740D02*
X378660Y811830D01*
G01X379010Y810770D02*
X382140Y807400D01*
G01X365200Y807720D02*
X370620Y813330D01*
G01X365170Y807690D02*
X365200Y807720D01*
G01X365180Y807670D02*
X365170Y807690D01*
G01X365490Y807400D02*
X365180Y807670D01*
G01X365520Y807390D02*
X365490Y807400D01*
G01X365540D02*
X365520Y807390D01*
G01X370660Y812700D02*
X365540Y807400D01*
G01X365620Y807490D02*
X365390D01*
G01X365270Y807590D02*
X365720D01*
G01X365820Y807680D02*
X365170D01*
G01X365260Y807790D02*
X365920D01*
G01X366010Y807880D02*
X365360D01*
G01X365450Y807990D02*
X366110D01*
G01X366200Y808090D02*
X365550D01*
G01X365640Y808180D02*
X366300D01*
G01X366400Y808290D02*
X365740D01*
G01X365840Y808380D02*
X366490D01*
G01X366590Y808490D02*
X365940D01*
G01X366030Y808590D02*
X366690D01*
G01X366780Y808680D02*
X366130D01*
G01X366230Y808790D02*
X366880D01*
G01X366980Y808880D02*
X366320D01*
G01X366420Y808990D02*
X367070D01*
G01X369120Y811790D02*
X369780D01*
G01X369970Y811990D02*
X369320D01*
G01X364870Y826600D02*
X364900Y826620D01*
G01X364870Y826060D02*
Y826600D01*
G01X364880Y826040D02*
X364870Y826060D01*
G01X364930Y825930D02*
X364880Y826040D01*
G01X364940Y825920D02*
X364930Y825930D01*
G01X370120Y820330D02*
X364940Y825920D01*
G01X364870Y826590D02*
X364930D01*
G01X364870Y826490D02*
X365020D01*
G01X365110Y826380D02*
X364870D01*
G01Y826290D02*
X365210D01*
G01X365300Y826180D02*
X364870D01*
G01Y826090D02*
X365390D01*
G01X365490Y825990D02*
X364900D01*
G01X364970Y825880D02*
X365580D01*
G01X365670Y825790D02*
X365060D01*
G01X365150Y825680D02*
X365760D01*
G01X365860Y825590D02*
X365250D01*
G01X365340Y825490D02*
X365950D01*
G01X366040Y825380D02*
X365430D01*
G01X365520Y825290D02*
X366140D01*
G01X366230Y825180D02*
X365620D01*
G01X365710Y825090D02*
X366320D01*
G01X366420Y824990D02*
X365800D01*
G01X365900Y824880D02*
X366510D01*
G01X366600Y824790D02*
X365990D01*
G01X366080Y824680D02*
X366700D01*
G01X366790Y824590D02*
X366180D01*
G01X366270Y824490D02*
X366880D01*
G01X366980Y824380D02*
X366360D01*
G01X366450Y824290D02*
X367070D01*
G01X367160Y824180D02*
X366550D01*
G01X366640Y824090D02*
X367250D01*
G01X367350Y823990D02*
X366730D01*
G01X366830Y823880D02*
X367440D01*
G01X367530Y823790D02*
X366920D01*
G01X367010Y823680D02*
X367620D01*
G01X367720Y823590D02*
X367110D01*
G01X367200Y823490D02*
X367810D01*
G01X367900Y823380D02*
X367290D01*
G01X367380Y823290D02*
X368000D01*
G01X368090Y823180D02*
X367480D01*
G01X367570Y823090D02*
X368180D01*
G01X368280Y822990D02*
X367660D01*
G01X367750Y822880D02*
X368370D01*
G01X368460Y822790D02*
X367850D01*
G01X367940Y822680D02*
X368560D01*
G01X368650Y822590D02*
X368030D01*
G01X368120Y822490D02*
X368740D01*
G01X368840Y822380D02*
X368220D01*
G01X368310Y822290D02*
X368930D01*
G01X369020Y822180D02*
X368400D01*
G01X368490Y822090D02*
X369120D01*
G01X369210Y821990D02*
X368590D01*
G01X368680Y821880D02*
X369300D01*
G01X369390Y821790D02*
X368770D01*
G01X368870Y821680D02*
X369490D01*
G01X369580Y821590D02*
X368960D01*
G01X369050Y821490D02*
X369670D01*
G01X369770Y821380D02*
X369150D01*
G01X369330Y821180D02*
X370570D01*
G01X370580Y820990D02*
X369520D01*
G01X369270Y823280D02*
X369780D01*
G01X369230Y823240D02*
X369270Y823280D01*
G01X369230Y822780D02*
Y823240D01*
G01X369270Y822740D02*
X369230Y822780D01*
G01Y823180D02*
X379480D01*
G01X379410Y822990D02*
X369230D01*
G01Y822790D02*
X379250D01*
G01X371880Y824090D02*
X370450D01*
G01X369870Y823350D02*
X369780Y823280D01*
G01X369890Y823400D02*
X369870Y823350D01*
G01X369890Y823410D02*
Y823400D01*
G01X370010Y823660D02*
X369890Y823410D01*
G01X370030Y823670D02*
X370010Y823660D01*
G01X370460Y824090D02*
X370030Y823670D01*
G01X369790Y823290D02*
X370520D01*
G01X370630Y823620D02*
X370740Y823690D01*
G01X370460Y823450D02*
X370630Y823620D01*
G01X370440Y823340D02*
X370460Y823450D01*
G01X370530Y823280D02*
X370440Y823340D01*
G01X370600Y823590D02*
X369980D01*
G01X369930Y823490D02*
X370500D01*
G01X370450Y823380D02*
X369880D01*
G01X370140Y823790D02*
X371820D01*
G01Y823990D02*
X370350D01*
G01X370700Y820390D02*
X373930Y816910D01*
G01X370690Y820390D02*
X370700D01*
G01X370650Y820440D02*
X370690Y820390D01*
G01X370620Y820500D02*
X370650Y820440D01*
G01X370440Y822630D02*
X370620Y820500D01*
G01X370540Y822740D02*
X370440Y822630D01*
G01X370960Y816590D02*
X370490D01*
G01X370480Y816790D02*
X370940D01*
G01X370920Y816990D02*
X370460D01*
G01X370440Y817180D02*
X370910D01*
G01X370890Y817380D02*
X370420D01*
G01X370400Y817590D02*
X370870D01*
G01X370860Y817790D02*
X370390D01*
G01X370370Y817990D02*
X370840D01*
G01X370820Y818180D02*
X370350D01*
G01X370340Y818380D02*
X370810D01*
G01X370790Y818590D02*
X370320D01*
G01X370300Y818790D02*
X370770D01*
G01X370750Y818990D02*
X370290D01*
G01X370270Y819180D02*
X370740D01*
G01X370720Y819380D02*
X370250D01*
G01X370240Y819490D02*
X370750D01*
G01X371250Y819790D02*
X370220D01*
G01X370200Y819990D02*
X371070D01*
G01X370140Y820300D02*
X370120Y820330D01*
G01X370180Y820200D02*
X370140Y820300D01*
G01X370180Y820190D02*
Y820200D01*
G01Y820180D02*
Y820190D01*
G01X370880Y820180D02*
X370180D01*
G01X370080Y820380D02*
X370700D01*
G01X370630Y820490D02*
X369980D01*
G01X369890Y820590D02*
X370620D01*
G01X370610Y820680D02*
X369800D01*
G01X369700Y820790D02*
X370600D01*
G01X370590Y820880D02*
X369610D01*
G01X369420Y821090D02*
X370570D01*
G01X370560Y821290D02*
X370080D01*
G01X369870Y822740D02*
X369270D01*
G01X369970Y822650D02*
X369870Y822740D01*
G01X370090Y821300D02*
X369970Y822650D01*
G01X369930Y822680D02*
X370490D01*
G01X370440Y822590D02*
X369980D01*
G01X369990Y822490D02*
X370460D01*
G01Y822380D02*
X369990D01*
G01X370000Y822290D02*
X370470D01*
G01X370480Y822180D02*
X370010D01*
G01X370020Y822090D02*
X370490D01*
G01X370500Y821990D02*
X370030D01*
G01X370040Y821880D02*
X370510D01*
G01Y821790D02*
X370050D01*
G01Y821680D02*
X370520D01*
G01X370530Y821590D02*
X370070D01*
G01Y821490D02*
X370540D01*
G01X370550Y821380D02*
X370080D01*
G01X369920Y821230D02*
X364900Y826620D01*
G01X370030Y821200D02*
X369920Y821230D01*
G01X370090Y821300D02*
X370030Y821200D01*
G01X369240Y821290D02*
X369860D01*
G01X370180Y820180D02*
X370620Y815030D01*
G01X370630Y814990D02*
X371100D01*
G01X371110Y814790D02*
X370640D01*
G01X370660Y814590D02*
X371130D01*
G01X371150Y814380D02*
X370680D01*
G01X370700Y814180D02*
X371170D01*
G01X371210Y814090D02*
X370710D01*
G01X370720Y813440D02*
X370620Y813330D01*
G01X370750Y813510D02*
X370720Y813440D01*
G01X370570Y813290D02*
X371260D01*
G01Y813090D02*
X370380D01*
G01X370190Y812880D02*
X371280D01*
G01X370640Y812680D02*
X369990D01*
G01X369900Y812590D02*
X370550D01*
G01X370450Y812490D02*
X369800D01*
G01X369700Y812380D02*
X370360D01*
G01X370260Y812290D02*
X369610D01*
G01X369420Y812090D02*
X370070D01*
G01X369870Y811880D02*
X369220D01*
G01X370600Y815290D02*
X371070D01*
G01X371050Y815490D02*
X370590D01*
G01X370570Y815680D02*
X371040D01*
G01X371020Y815880D02*
X370550D01*
G01X370530Y816090D02*
X371000D01*
G01X370990Y816290D02*
X370520D01*
G01X370510Y816380D02*
X370980D01*
G01X370970Y816490D02*
X370500D01*
G01X370480Y816680D02*
X370950D01*
G01X370940Y816880D02*
X370470D01*
G01X370450Y817090D02*
X370920D01*
G01X370900Y817290D02*
X370430D01*
G01X370420Y817490D02*
X370880D01*
G01X370860Y817680D02*
X370400D01*
G01X370380Y817880D02*
X370850D01*
G01X370830Y818090D02*
X370360D01*
G01X370350Y818290D02*
X370810D01*
G01X370800Y818490D02*
X370330D01*
G01X370310Y818680D02*
X370780D01*
G01X370760Y818880D02*
X370290D01*
G01X370280Y819090D02*
X370740D01*
G01X370730Y819290D02*
X370260D01*
G01X370890Y819510D02*
X373620Y816570D01*
G01X370770Y819530D02*
X370890Y819510D01*
G01X370720Y819430D02*
X370770Y819530D01*
G01X370990Y816180D02*
X370530D01*
G01X370540Y815990D02*
X371010D01*
G01X371030Y815790D02*
X370560D01*
G01X370580Y815590D02*
X371050D01*
G01X371060Y815380D02*
X370590D01*
G01X370610Y815180D02*
X371080D01*
G01X371090Y815090D02*
X370620D01*
G01X370750Y813570D02*
Y813510D01*
G01X370620Y815030D02*
X370750Y813570D01*
G01X370740Y813490D02*
X371420D01*
G01X371270Y813310D02*
X371250Y813240D01*
G01X371320Y813390D02*
X371270Y813310D01*
G01X371250Y813180D02*
X370480D01*
G01X370290Y812990D02*
X371270D01*
G01X371290Y812680D02*
X370790D01*
G01X370760Y812720D02*
X370660Y812700D01*
G01X370760Y812720D02*
X370830Y812640D01*
G01X370890Y811880D02*
X371360D01*
G01X371350Y812090D02*
X370880D01*
G01X370860Y812290D02*
X371330D01*
G01X371310Y812490D02*
X370850D01*
G01X370740Y813680D02*
X371610D01*
G01X371800Y813880D02*
X370720D01*
G01X370690Y814290D02*
X371160D01*
G01X371170Y814140D02*
X370720Y819430D01*
G01X370910Y819490D02*
X371530D01*
G01X371720Y819290D02*
X371100D01*
G01X371280Y819090D02*
X371900D01*
G01X371160Y819880D02*
X370210D01*
G01X370190Y820090D02*
X370980D01*
G01X370790Y820290D02*
X370150D01*
G01X370850Y823700D02*
X370740Y823690D01*
G01X370900Y823610D02*
X370850Y823700D01*
G01X370900Y823380D02*
Y823610D01*
G01X370800Y823280D02*
X370900Y823380D01*
G01X370530Y823280D02*
X370800D01*
G01X370730Y823680D02*
X370040D01*
G01X370910Y824670D02*
X370940Y824690D01*
G01X370900Y824640D02*
X370910Y824670D01*
G01X370900Y824440D02*
Y824640D01*
G01X370890Y824400D02*
X370900Y824440D01*
G01X370870Y824350D02*
X370890Y824400D01*
G01X370820Y824290D02*
X370870Y824350D01*
G01X370730Y824250D02*
X370820Y824290D01*
G01X370460Y824090D02*
X370730Y824250D01*
G01X370940Y824680D02*
X371770D01*
G01X370900Y824490D02*
X373790D01*
G01X373780Y824290D02*
X370800D01*
G01X370850Y823680D02*
X371820D01*
G01Y823490D02*
X370900D01*
G01X370810Y823290D02*
X371920D01*
G01X371110Y814880D02*
X370640D01*
G01X370650Y814680D02*
X371120D01*
G01X371140Y814490D02*
X370670D01*
G01X371240Y814050D02*
X371340Y814080D01*
G01X371170Y814140D02*
X371240Y814050D01*
G01X371320Y813380D02*
X370670D01*
G01X370750Y813590D02*
X371510D01*
G01X371330Y813390D02*
X371320D01*
G01X371330Y813400D02*
Y813390D01*
G01Y813400D02*
X373920Y816090D01*
G01X373730Y815880D02*
X373090D01*
G01X372890Y815680D02*
X373540D01*
G01X373350Y815490D02*
X372700D01*
G01X372510Y815290D02*
X373150D01*
G01X373060Y815180D02*
X372410D01*
G01X372460Y815240D02*
X371340Y814080D01*
G01X371350Y814090D02*
X371990D01*
G01X371900Y813990D02*
X370720D01*
G01X370730Y813790D02*
X371710D01*
G01X371450Y814180D02*
X372090D01*
G01X372190Y814290D02*
X371550D01*
G01X371640Y814380D02*
X372290D01*
G01X372380Y814490D02*
X371740D01*
G01X371830Y814590D02*
X372480D01*
G01X372570Y814680D02*
X371930D01*
G01X372030Y814790D02*
X372670D01*
G01X372770Y814880D02*
X372120D01*
G01X372220Y814990D02*
X372860D01*
G01X372960Y815090D02*
X372310D01*
G01X373140Y817090D02*
X373770D01*
G01X373580Y817290D02*
X372960D01*
G01X372770Y817490D02*
X373390D01*
G01X373210Y817680D02*
X372580D01*
G01X372490Y817790D02*
X373110D01*
G01X373020Y817880D02*
X372400D01*
G01X372310Y817990D02*
X372930D01*
G01X372830Y818090D02*
X372210D01*
G01X372120Y818180D02*
X372740D01*
G01X372650Y818290D02*
X372030D01*
G01X371930Y818380D02*
X372560D01*
G01X372460Y818490D02*
X371840D01*
G01X371750Y818590D02*
X372370D01*
G01X372280Y818680D02*
X371650D01*
G01X371560Y818790D02*
X372180D01*
G01X372090Y818880D02*
X371470D01*
G01X371380Y818990D02*
X372000D01*
G01X371810Y819180D02*
X371190D01*
G01X371000Y819380D02*
X371620D01*
G01X371440Y819590D02*
X370240D01*
G01X370230Y819680D02*
X371350D01*
G01X373200Y818960D02*
X373240Y818920D01*
G01X371820Y823380D02*
X370900D01*
G01X371920Y823280D02*
X371820Y823380D01*
G01X370900Y823590D02*
X371820D01*
G01X373150Y824290D02*
X373260Y824180D01*
G01X372880Y824260D02*
X373150Y824290D01*
G01X372600Y824230D02*
X372880Y824260D01*
G01X372480Y824220D02*
X372600Y824230D01*
G01X372380Y824200D02*
X372480Y824220D01*
G01X372130Y824160D02*
X372380Y824200D01*
G01X372120Y824160D02*
X372130D01*
G01X372030Y824140D02*
X372120Y824160D01*
G01X372020Y824140D02*
X372030D01*
G01X371900Y824120D02*
X372020Y824140D01*
G01X371820Y824020D02*
X371900Y824120D01*
G01X371820Y823380D02*
Y824020D01*
G01X371760Y824690D02*
X370940D01*
G01X371780Y824680D02*
X371760Y824690D01*
G01X371810Y824670D02*
X371780Y824680D01*
G01X371840Y824650D02*
X371810Y824670D01*
G01X371920Y824630D02*
X371840Y824650D01*
G01X371940Y824640D02*
X371920Y824630D01*
G01X372180Y824680D02*
X371940Y824640D01*
G01X372680Y824750D02*
X372180Y824680D01*
G01X372800Y824760D02*
X372680Y824750D01*
G01X372860Y824760D02*
X372800D01*
G01X373020Y824780D02*
X372860Y824760D01*
G01X373160Y824790D02*
X373020Y824780D01*
G01X370620Y824180D02*
X372270D01*
G01X371820Y823880D02*
X370250D01*
G01X371920Y823280D02*
X377760D01*
G01X375830Y824790D02*
X373140D01*
G01X373160D02*
X373260Y824890D01*
G01X371290Y812790D02*
X370090D01*
G01X370830Y812590D02*
X371300D01*
G01X371320Y812380D02*
X370850D01*
G01X370870Y812180D02*
X371340D01*
G01X371350Y811990D02*
X370880D01*
G01X370900Y811790D02*
X371370D01*
G01X374380Y816420D02*
Y816560D01*
G01X377080Y813520D02*
X374380Y816420D01*
G01X374400Y816590D02*
X373610D01*
G01X373620Y816430D02*
X372460Y815240D01*
G01X373620Y816570D02*
Y816430D01*
G01X372610Y815380D02*
X373250D01*
G01X373440Y815590D02*
X372800D01*
G01X372990Y815790D02*
X373640D01*
G01X373830Y815990D02*
X373180D01*
G01X374070Y816090D02*
X375750Y814270D01*
G01X373920Y816090D02*
X374070D01*
G01X373280D02*
X373920D01*
G01X375740Y814290D02*
X376370D01*
G01X376180Y814490D02*
X375550D01*
G01X375370Y814680D02*
X376000D01*
G01X375810Y814880D02*
X375180D01*
G01X375090Y814990D02*
X375720D01*
G01X375620Y815090D02*
X374990D01*
G01X374900Y815180D02*
X375530D01*
G01X375440Y815290D02*
X374810D01*
G01X374720Y815380D02*
X375350D01*
G01X375250Y815490D02*
X374620D01*
G01X374530Y815590D02*
X375160D01*
G01X375070Y815680D02*
X374440D01*
G01X374350Y815790D02*
X374980D01*
G01X374880Y815880D02*
X374250D01*
G01X374160Y815990D02*
X374790D01*
G01X374700Y816090D02*
X374050D01*
G01X374420Y816380D02*
X373570D01*
G01X373620Y816490D02*
X374380D01*
G01X374500Y816680D02*
X373510D01*
G01X373420Y816790D02*
X374600D01*
G01X374700Y816880D02*
X373330D01*
G01X373240Y816990D02*
X373860D01*
G01X374070Y816910D02*
X375500Y818380D01*
G01X373930Y816910D02*
X374070D01*
G01X375400Y818290D02*
X376040D01*
G01X375850Y818090D02*
X375210D01*
G01X375120Y817990D02*
X375750D01*
G01X375660Y817880D02*
X375020D01*
G01X374920Y817790D02*
X375560D01*
G01X375470Y817680D02*
X374830D01*
G01X374730Y817590D02*
X375370D01*
G01X375270Y817490D02*
X374630D01*
G01X374540Y817380D02*
X375180D01*
G01X375080Y817290D02*
X374440D01*
G01X374350Y817180D02*
X374980D01*
G01X374890Y817090D02*
X374250D01*
G01X374150Y816990D02*
X374790D01*
G01X374510Y816290D02*
X373480D01*
G01X373380Y816180D02*
X374600D01*
G01X373670Y817180D02*
X373050D01*
G01X372860Y817380D02*
X373490D01*
G01X373300Y817590D02*
X372680D01*
G01X373290Y818920D02*
X375780D01*
G01X373240D02*
X373290D01*
G01X375790Y818680D02*
X376430D01*
G01X376240Y818490D02*
X375600D01*
G01X376720Y818990D02*
X373200D01*
G01X373240Y819950D02*
X373290D01*
G01X373200Y819910D02*
X373240Y819950D01*
G01X373200Y818960D02*
Y819910D01*
G01Y819790D02*
X376460D01*
G01X376490Y819590D02*
X373200D01*
G01Y819380D02*
X377110D01*
G01X376910Y819180D02*
X373200D01*
G01X373260Y823840D02*
Y824180D01*
G01X373300Y823790D02*
X373260Y823840D01*
G01X373250Y824180D02*
X375880D01*
G01X375750Y823790D02*
X373300D01*
G01X375800Y823840D02*
X375750Y823790D01*
G01X375800Y824120D02*
Y823840D01*
G01X373260Y823880D02*
X375800D01*
G01Y823990D02*
X373260D01*
G01Y824090D02*
X375800D01*
G01X375350Y824400D02*
Y824360D01*
G01X375250Y824500D02*
X375350Y824400D01*
G01X373810Y824500D02*
X375250D01*
G01X373710Y824400D02*
X373810Y824500D01*
G01X373710Y824360D02*
Y824400D01*
G01X373810Y824250D02*
X373710Y824360D01*
G01X375250Y824250D02*
X373810D01*
G01X375350Y824360D02*
X375250Y824250D01*
G01X375350Y824380D02*
X377320D01*
G01X377030Y824490D02*
X375260D01*
G01X373260Y824920D02*
Y824890D01*
G01X373300Y824960D02*
X373260Y824920D01*
G01X375750Y824960D02*
X373300D01*
G01X375800Y824920D02*
X375750Y824960D01*
G01X375800Y824820D02*
Y824920D01*
G01X373250Y824880D02*
X375800D01*
G01X373710Y824380D02*
X370880D01*
G01X370900Y824590D02*
X376660D01*
G01X375880Y824720D02*
X375800Y824820D01*
G01X375930Y824720D02*
X375880D01*
G01X376490Y824630D02*
X375930Y824720D01*
G01X376670Y824590D02*
X376490Y824630D01*
G01X376110Y824680D02*
X372240D01*
G01X376310Y824150D02*
X376720Y824060D01*
G01X376020Y824200D02*
X376310Y824150D01*
G01X375990Y824200D02*
X376020D01*
G01X375910Y824220D02*
X375990Y824200D01*
G01X375800Y824120D02*
X375910Y824220D01*
G01X376100Y824180D02*
X377690D01*
G01X376410Y819950D02*
X373290D01*
G01X373200Y819880D02*
X376460D01*
G01X376450Y819910D02*
X376410Y819950D01*
G01X376630Y819560D02*
X376830Y819760D01*
G01X376520Y819530D02*
X376630Y819560D01*
G01X376460Y819630D02*
X376520Y819530D01*
G01X376460Y819810D02*
Y819630D01*
G01Y819820D02*
Y819810D01*
G01X376450Y819910D02*
X376460Y819820D01*
G01X376660Y819590D02*
X377300D01*
G01X376460Y819680D02*
X373200D01*
G01X375310Y818180D02*
X375950D01*
G01X375870Y818860D02*
X375780Y818920D01*
G01X375850Y818750D02*
X375870Y818860D01*
G01X375500Y818380D02*
X375850Y818750D01*
G01X376140Y818380D02*
X375500D01*
G01X375830Y818880D02*
X376620D01*
G01X376530Y818790D02*
X375860D01*
G01X375700Y818590D02*
X376330D01*
G01X375900Y814790D02*
X375270D01*
G01X375460Y814590D02*
X376090D01*
G01X376270Y814380D02*
X375640D01*
G01X375830Y814180D02*
X376460D01*
G01X376550Y814090D02*
X375920D01*
G01X376010Y813990D02*
X376650D01*
G01X376740Y813880D02*
X376110D01*
G01X376200Y813790D02*
X376830D01*
G01X377020Y813590D02*
X376390D01*
G01X376570Y813380D02*
X377710D01*
G01X377700Y813290D02*
X376670D01*
G01X376150Y811810D02*
X376140Y811800D01*
G01X376390Y812030D02*
X376150Y811810D01*
G01X376400Y812030D02*
X376390D01*
G01X376520Y812110D02*
X376400Y812030D01*
G01X376530Y812120D02*
X376520Y812110D01*
G01X376590Y812150D02*
X376530Y812120D01*
G01X376750Y812220D02*
X376590Y812150D01*
G01X376660Y812180D02*
X378330D01*
G01X378420Y812090D02*
X376480D01*
G01X376240Y811880D02*
X378610D01*
G01X376840Y812250D02*
X376750Y812220D01*
G01X376850Y812260D02*
X376840Y812250D01*
G01X376990Y812290D02*
X376850Y812260D01*
G01X377070Y812310D02*
X376990Y812290D01*
G01X376850Y813090D02*
X375750Y814270D01*
G01X377110Y812810D02*
X376850Y813090D01*
G01X377140Y812760D02*
X377110Y812810D01*
G01X377170Y812610D02*
X377140Y812760D01*
G01X377180Y812590D02*
X377170Y812610D01*
G01X377180Y812570D02*
Y812590D01*
G01X377160Y812400D02*
X377180Y812570D01*
G01X377160Y812390D02*
Y812400D01*
G01X377070Y812310D02*
X377160Y812390D01*
G01X376290Y813680D02*
X376930D01*
G01X377250Y813580D02*
X377760Y819810D01*
G01X377190Y813500D02*
X377250Y813580D01*
G01X377080Y813520D02*
X377190Y813500D01*
G01X376850Y819790D02*
X376830Y819760D01*
G01X377490Y819790D02*
X376850D01*
G01D02*
X377660Y820630D01*
G01X377240Y820180D02*
X379500D01*
G01Y819990D02*
X377050D01*
G01X376750Y819680D02*
X377390D01*
G01X377200Y819490D02*
X373200D01*
G01Y819290D02*
X377010D01*
G01X376810Y819090D02*
X373200D01*
G01X377420Y815590D02*
X377880D01*
G01X377870Y815380D02*
X377400D01*
G01X377380Y815180D02*
X377850D01*
G01X377840Y814990D02*
X377370D01*
G01X377350Y814790D02*
X377820D01*
G01X377810Y814590D02*
X377340D01*
G01X377320Y814380D02*
X377790D01*
G01X377770Y814180D02*
X377310D01*
G01X377290Y813990D02*
X377750D01*
G01X377740Y813790D02*
X377270D01*
G01X377250Y813590D02*
X377720D01*
G01X377680Y813090D02*
X376850D01*
G01X377040Y812880D02*
X377680D01*
G01X377860Y812680D02*
X377160D01*
G01X377170Y812490D02*
X378050D01*
G01X377000Y823980D02*
X376720Y824060D01*
G01X377010Y823970D02*
X377000Y823980D01*
G01X377120Y823940D02*
X377010Y823970D01*
G01X377120Y823930D02*
Y823940D01*
G01X377230Y823890D02*
X377120Y823930D01*
G01X377240Y823880D02*
X377230Y823890D01*
G01X378100Y823880D02*
X377240D01*
G01X376960Y823990D02*
X377990D01*
G01X376790Y824550D02*
X376670Y824590D01*
G01X376900Y824530D02*
X376790Y824550D01*
G01X377140Y824450D02*
X376900Y824530D01*
G01X377250Y824410D02*
X377140Y824450D01*
G01X377310Y824390D02*
X377250Y824410D01*
G01X376600Y824090D02*
X377850D01*
G01X377530Y824290D02*
X375280D01*
G01X377850Y823330D02*
X377760Y823280D01*
G01X377840Y823430D02*
X377850Y823330D01*
G01X377770Y823540D02*
X377840Y823430D01*
G01X377750Y823560D02*
X377770Y823540D01*
G01X377450Y823780D02*
X377750Y823560D01*
G01X377440Y823790D02*
X377450Y823780D01*
G01X377430Y823790D02*
X377440D01*
G01X377240Y823880D02*
X377430Y823790D01*
G01X377770Y823290D02*
X379490D01*
G01X379470Y823490D02*
X377810D01*
G01X377580Y823680D02*
X379390D01*
G01X379500Y821680D02*
X377720D01*
G01X377690Y820660D02*
X377660Y820630D01*
G01X377720Y820720D02*
X377690Y820660D01*
G01X377720Y821740D02*
Y820720D01*
G01X377620Y820590D02*
X378290D01*
G01X378460Y820790D02*
X377720D01*
G01Y820990D02*
X378650D01*
G01X378840Y821180D02*
X377720D01*
G01Y821290D02*
X379500D01*
G01Y821490D02*
X377720D01*
G01X377830Y821820D02*
X377930Y821920D01*
G01X377760Y821820D02*
X377830D01*
G01X377720Y821780D02*
X377760Y821820D01*
G01X377720Y821740D02*
Y821780D01*
G01X377430Y820380D02*
X379500D01*
G01X378220Y819680D02*
X377750D01*
G01X377590Y819890D02*
X374380Y816560D01*
G01X377700Y819910D02*
X377590Y819890D01*
G01X377760Y819810D02*
X377700Y819910D01*
G01X377480Y816380D02*
X377950D01*
G01X377960Y816490D02*
X377490D01*
G01X377510Y816680D02*
X377980D01*
G01X377990Y816880D02*
X377530D01*
G01X377540Y817090D02*
X378010D01*
G01X378020Y817290D02*
X377560D01*
G01X377570Y817490D02*
X378040D01*
G01X378060Y817680D02*
X377590D01*
G01X377610Y817880D02*
X378070D01*
G01X378090Y818090D02*
X377620D01*
G01X377640Y818290D02*
X378110D01*
G01X378120Y818490D02*
X377660D01*
G01X377670Y818680D02*
X378140D01*
G01X378150Y818880D02*
X377690D01*
G01X377700Y819090D02*
X378170D01*
G01X378190Y819290D02*
X377720D01*
G01X377740Y819490D02*
X378200D01*
G01X377590Y819880D02*
X376950D01*
G01X377470Y816180D02*
X377940D01*
G01X377920Y815990D02*
X377450D01*
G01X377440Y815790D02*
X377900D01*
G01X377890Y815680D02*
X377430D01*
G01X377410Y815490D02*
X377880D01*
G01X377860Y815290D02*
X377390D01*
G01X377380Y815090D02*
X377850D01*
G01X377830Y814880D02*
X377360D01*
G01X377350Y814680D02*
X377810D01*
G01X377800Y814490D02*
X377330D01*
G01X377310Y814290D02*
X377780D01*
G01X377760Y814090D02*
X377300D01*
G01X377280Y813880D02*
X377750D01*
G01X377730Y813680D02*
X377260D01*
G01X377720Y813490D02*
X376480D01*
G01X376760Y813180D02*
X377690D01*
G01X377680Y812990D02*
X376950D01*
G01X377120Y812790D02*
X377760D01*
G01X377700Y812850D02*
X378660Y811830D01*
G01X377690Y812870D02*
X377670Y812940D01*
G01X377700Y812860D02*
X377690Y812870D01*
G01X377700Y812850D02*
Y812860D01*
G01X377460Y824330D02*
X377310Y824390D01*
G01X377470Y824320D02*
X377460Y824330D01*
G01X378720Y824040D02*
X378780Y824050D01*
G01X378710Y824040D02*
X378720D01*
G01X378600Y824010D02*
X378710Y824040D01*
G01X378590Y824010D02*
X378600D01*
G01X378460Y823960D02*
X378590Y824010D01*
G01X378460Y823950D02*
Y823960D01*
G01X378400Y823920D02*
X378460Y823950D01*
G01X378380Y823900D02*
X378400Y823920D01*
G01X378320Y823850D02*
X378380Y823900D01*
G01X378300Y823830D02*
X378320Y823850D01*
G01X378160Y823830D02*
X378300D01*
G01X377980Y824000D02*
X378160Y823830D01*
G01X377970Y824010D02*
X377980Y824000D01*
G01X377470Y824320D02*
X377970Y824010D01*
G01X378530Y823990D02*
X379050D01*
G01X379100Y822680D02*
X377940D01*
G01X377990Y822630D02*
X377930Y821920D01*
G01X377900Y821880D02*
X378450D01*
G01X378740Y822610D02*
X378770Y822600D01*
G01X378660Y822620D02*
X378740Y822610D01*
G01X378590Y822640D02*
X378660Y822620D01*
G01X378580Y822640D02*
X378590D01*
G01X378450Y822550D02*
X378580Y822640D01*
G01X378400Y821940D02*
X378450Y822550D01*
G01X378500Y821830D02*
X378400Y821940D01*
G01X378500Y822590D02*
X377990D01*
G01X377890Y822740D02*
X370540D01*
G01X377990Y822630D02*
X377890Y822740D01*
G01X377530Y820490D02*
X378350D01*
G01X378320Y820640D02*
X378870Y821220D01*
G01X378290Y820590D02*
X378320Y820640D01*
G01X378290Y820550D02*
Y820590D01*
G01X378390Y820440D02*
X378290Y820550D01*
G01X378750Y821090D02*
X377720D01*
G01Y820880D02*
X378550D01*
G01X378360Y820680D02*
X377700D01*
G01X377720Y819880D02*
X378250D01*
G01X378240Y819870D02*
X377670Y812940D01*
G01X377950Y812590D02*
X377180D01*
G01X377150Y812380D02*
X378140D01*
G01X378230Y812290D02*
X376960D01*
G01X376350Y811990D02*
X378510D01*
G01X378700Y811790D02*
X376130D01*
G01X377440Y815880D02*
X377910D01*
G01X377930Y816090D02*
X377460D01*
G01X377480Y816290D02*
X377940D01*
G01X377970Y816590D02*
X377500D01*
G01X377510Y816790D02*
X377980D01*
G01X378000Y816990D02*
X377530D01*
G01X377550Y817180D02*
X378010D01*
G01X378030Y817380D02*
X377570D01*
G01X377580Y817590D02*
X378050D01*
G01X378070Y817790D02*
X377600D01*
G01X377610Y817990D02*
X378080D01*
G01X378100Y818180D02*
X377630D01*
G01X377650Y818380D02*
X378110D01*
G01X378130Y818590D02*
X377660D01*
G01X377680Y818790D02*
X378140D01*
G01X378160Y818990D02*
X377700D01*
G01X377710Y819180D02*
X378180D01*
G01X378200Y819380D02*
X377730D01*
G01X377740Y819590D02*
X378210D01*
G01X378230Y819790D02*
X377760D01*
G01X378240Y819870D02*
X378330Y819960D01*
G01X378660Y821820D02*
X378780D01*
G01X378500Y821830D02*
X378660Y821820D01*
G01X378410Y821990D02*
X377940D01*
G01X377950Y822090D02*
X378420D01*
G01Y822180D02*
X377960D01*
G01Y822290D02*
X378430D01*
G01X378440Y822380D02*
X377970D01*
G01X377980Y822490D02*
X378450D01*
G01X378850Y824050D02*
X378780D01*
G01X378860Y824040D02*
X378850Y824050D01*
G01X379120Y823970D02*
X378860Y824040D01*
G01X379000Y822630D02*
X379230Y822750D01*
G01X378980Y822630D02*
X379000D01*
G01X378860Y822610D02*
X378980Y822630D01*
G01X378850Y822610D02*
X378860D01*
G01X378790Y822600D02*
X378850Y822610D01*
G01X378770Y822600D02*
X378790D01*
G01X378360Y823880D02*
X379220D01*
G01X379330Y823790D02*
X377440D01*
G01X377720Y823590D02*
X379440D01*
G01X379480Y823380D02*
X377850D01*
G01X379340Y822880D02*
X369230D01*
G01Y823090D02*
X379440D01*
G01X378980Y821990D02*
X379610D01*
G01X379460Y819960D02*
X378330D01*
G01X378980Y821240D02*
X378870Y821220D01*
G01X379040Y821140D02*
X378980Y821240D01*
G01X379040Y820540D02*
Y821140D01*
G01X378940Y820440D02*
X379040Y820540D01*
G01X378390Y820440D02*
X378940D01*
G01X379010Y821180D02*
X379500D01*
G01Y821090D02*
X379040D01*
G01Y820990D02*
X379500D01*
G01Y820880D02*
X379040D01*
G01Y820790D02*
X379500D01*
G01Y820680D02*
X379040D01*
G01Y820590D02*
X379500D01*
G01Y820490D02*
X378990D01*
G01X379500Y820290D02*
X377330D01*
G01X377140Y820090D02*
X379500D01*
G01Y821380D02*
X377720D01*
G01Y821590D02*
X379500D01*
G01Y821790D02*
X377720D01*
G01X378780Y821820D02*
X378850Y821850D01*
G01X378880Y821880D02*
X379520D01*
G01X378850Y821850D02*
X383430Y826590D01*
G01X379090Y810680D02*
X379720D01*
G01X379810Y810590D02*
X379180D01*
G01X379270Y810490D02*
X379910D01*
G01X379960Y810380D02*
X380000D01*
G01X380010D02*
X379370D01*
G01X379460Y810290D02*
X380095D01*
G01X380090D02*
X380040D01*
G01X380195Y810180D02*
X379550D01*
G01X379640Y810090D02*
X380280D01*
G01X380370Y809990D02*
X379735D01*
G01X379835Y809880D02*
X380470D01*
G01X380560Y809790D02*
X379920D01*
G01X380025Y809680D02*
X380650D01*
G01X380750Y809590D02*
X380110D01*
G01X380200Y809490D02*
X380840D01*
G01X380930Y809380D02*
X380290D01*
G01X380380Y809290D02*
X381030D01*
G01X381210Y809090D02*
X380570D01*
G01X380480Y809180D02*
X381120D01*
G01X381300Y808990D02*
X380660D01*
G01X380760Y808880D02*
X381400D01*
G01X381490Y808790D02*
X380850D01*
G01X380940Y808680D02*
X381580D01*
G01X381680Y808590D02*
X381030D01*
G01X381130Y808490D02*
X381770D01*
G01X381860Y808380D02*
X381220D01*
G01X381310Y808290D02*
X381960D01*
G01X382050Y808180D02*
X381410D01*
G01X381500Y808090D02*
X382140D01*
G01X382330Y807880D02*
X381690D01*
G01X381870Y807680D02*
X382480D01*
G01X382140Y807400D02*
X382160Y807380D01*
G01X382060Y807490D02*
X382280D01*
G01X382240Y807990D02*
X381590D01*
G01X381780Y807790D02*
X382420D01*
G01X382190Y807400D02*
X382160Y807380D01*
G01X382480Y807690D02*
X382190Y807400D01*
G01X382490Y807710D02*
X382480Y807690D01*
G01Y807720D02*
X382490Y807710D01*
G01X382470Y807740D02*
X382480Y807720D01*
G01X381960Y807590D02*
X382380D01*
G01X379130Y823960D02*
X379120Y823970D01*
G01X379330Y823790D02*
X379130Y823960D01*
G01X379340Y823780D02*
X379330Y823790D01*
G01X379460Y823550D02*
X379340Y823780D01*
G01X379470Y823530D02*
X379460Y823550D01*
G01X379490Y823250D02*
X379470Y823530D01*
G01X379490Y823240D02*
Y823250D01*
G01X379410Y822980D02*
X379490Y823240D01*
G01X379400Y822970D02*
X379410Y822980D01*
G01X379240Y822770D02*
X379400Y822970D01*
G01X379230Y822750D02*
X379240Y822770D01*
G01X379750Y822790D02*
X380380D01*
G01X380480Y822880D02*
X379850D01*
G01X379940Y822990D02*
X380580D01*
G01X380670Y823090D02*
X380040D01*
G01X380140Y823180D02*
X380770D01*
G01X380860Y823290D02*
X380240D01*
G01X380330Y823380D02*
X380960D01*
G01X381060Y823490D02*
X380430D01*
G01X380530Y823590D02*
X381160D01*
G01X381350Y823790D02*
X380720D01*
G01X380910Y823990D02*
X381540D01*
G01X380290Y822680D02*
X379660D01*
G01X379560Y822590D02*
X380190D01*
G01X380090Y822490D02*
X379460D01*
G01X379360Y822380D02*
X380000D01*
G01X379900Y822290D02*
X379270D01*
G01X379170Y822180D02*
X379810D01*
G01X379710Y822090D02*
X379080D01*
G01X379500Y819980D02*
X379460Y819960D01*
G01X379500Y819990D02*
Y819980D01*
G01Y821810D02*
Y819990D01*
G01Y821820D02*
Y821810D01*
G01X379530Y821900D02*
X379500Y821820D01*
G01X383460Y825980D02*
X379530Y821900D01*
G01X380620Y823680D02*
X381250D01*
G01X381440Y823880D02*
X380810D01*
G01X381010Y824090D02*
X381640D01*
G01X381740Y824180D02*
X381110D01*
G01X381200Y824290D02*
X381830D01*
G01X381930Y824380D02*
X381300D01*
G01X381400Y824490D02*
X382020D01*
G01X382120Y824590D02*
X381490D01*
G01X381680Y824790D02*
X382310D01*
G01X382510Y824990D02*
X381880D01*
G01X382070Y825180D02*
X382700D01*
G01X382600Y825090D02*
X381980D01*
G01X382170Y825290D02*
X382790D01*
G01X382890Y825380D02*
X382260D01*
G01X382360Y825490D02*
X382990D01*
G01X383090Y825590D02*
X382460D01*
G01X382550Y825680D02*
X383180D01*
G01X383280Y825790D02*
X382650D01*
G01X382750Y825880D02*
X383370D01*
G01X383480Y826090D02*
X382940D01*
G01X383470Y826010D02*
X383480Y826090D01*
G01X383460Y825980D02*
X383470Y826010D01*
G01X382850Y825990D02*
X383460D01*
G01X383480Y826580D02*
X383430Y826590D01*
G01X383480Y826090D02*
Y826580D01*
G01X383420Y826590D02*
X383460D01*
G01X383480Y826490D02*
X383330D01*
G01X383230Y826380D02*
X383480D01*
G01Y826290D02*
X383130D01*
G01X383040Y826180D02*
X383480D01*
G01X382410Y824880D02*
X381780D01*
G01X381590Y824680D02*
X382220D01*
G54D12*
G01X-245081Y-422119D02*
G02I-12000J0D01*
G01X-250231D02*
G02I-6850J0D01*
G01X-241081D02*
X-273081D01*
G01X-257081Y-438119D02*
Y-406119D01*
G01X-241081Y-438119D02*
Y-518119D01*
G01D02*
X1034819D01*
G01X-241081Y-473619D02*
X1034819D01*
G01X-241081Y-438119D02*
X1034819D01*
G01X42020Y905488D02*
Y897688D01*
G01X57597Y675314D02*
Y665714D01*
G01X63038Y857202D02*
Y846252D01*
G01X68772Y816804D02*
Y823504D01*
G01X92397Y675314D02*
Y665714D01*
G01X100322Y748054D02*
Y759004D01*
G01X100804Y905520D02*
Y897720D01*
G01X110804Y805920D02*
X102804D01*
G01X133700Y849000D02*
X127000D01*
G01X187493Y551696D02*
Y558696D01*
G01X199300Y909510D02*
X194300D01*
G01X211000Y820500D02*
Y825500D01*
G01X207400Y909510D02*
X202400D01*
G01X209850Y917400D02*
X218950D01*
G01X226823Y553183D02*
X218023D01*
G01X247319Y-438119D02*
Y-518119D01*
G01X248500Y844000D02*
Y839000D01*
G01X271000Y186000D02*
Y191000D01*
G01Y178000D02*
Y183000D01*
G01X268500Y906100D02*
X274500D01*
G01X310985Y225372D02*
Y230372D01*
G01Y233372D02*
Y238372D01*
G01X302929Y339500D02*
Y344500D01*
G01X360500Y778500D02*
X300500D01*
Y681500D01*
X590000D01*
Y778500D01*
X360500D01*
G01X326485Y238372D02*
Y233372D01*
G01Y230372D02*
Y225372D01*
G01X330929Y316500D02*
X325929D01*
G01Y331000D02*
X330929D01*
G01X325929Y345500D02*
X330929D01*
G01X325929Y360000D02*
X330929D01*
G01X316055Y440000D02*
X321055D01*
G01X324055D02*
X329055D01*
G01X335223Y486783D02*
X328523D01*
G01X321205Y523500D02*
Y513900D01*
G01X338929Y316500D02*
X333929D01*
G01Y331000D02*
X338929D01*
G01X333929Y345500D02*
X338929D01*
G01X333929Y360000D02*
X338929D01*
G01X340323Y452783D02*
X347023D01*
G01X345548Y523594D02*
Y513994D01*
G01X338000Y925800D02*
Y918000D01*
G01X371400Y63500D02*
Y68500D01*
G01X384819Y-438119D02*
Y-518119D01*
G01X390000Y926300D02*
Y918500D01*
G01X408929Y253900D02*
Y248900D01*
G01Y261900D02*
Y256900D01*
G01X441155Y288250D02*
Y292900D01*
G01X449329Y103850D02*
Y99200D01*
G01X446155Y272900D02*
X453855D01*
G01X499819Y-438119D02*
Y-518119D01*
G01X517650Y142900D02*
X522300D01*
G01X531429Y172300D02*
Y163500D01*
G01X561655Y352378D02*
Y360078D01*
G01X569500Y429000D02*
Y434000D01*
G01Y437000D02*
Y442000D01*
G01X582382Y273500D02*
X577382D01*
G01X637300Y364500D02*
X620700D01*
G01X623500Y423500D02*
Y418500D01*
G01Y415500D02*
Y410500D01*
G01Y439500D02*
Y434500D01*
G01Y431500D02*
Y426500D01*
G01X657800Y364500D02*
X641200D01*
G01X638000Y399500D02*
X643000D01*
G01X646000D02*
X651000D01*
G01X654500D02*
X659500D01*
G01X648574Y575578D02*
X655274D01*
G01X667319Y-438119D02*
Y-518119D01*
G01X666500Y356800D02*
Y340200D01*
G01Y377300D02*
Y360700D01*
G01X685462Y481964D02*
Y476964D01*
G01Y489964D02*
Y484964D01*
G01Y497964D02*
Y492964D01*
G01X685500Y522000D02*
Y517000D01*
G01Y514000D02*
Y509000D01*
G01X685462Y505964D02*
Y500964D01*
G01X740300Y66700D02*
X734200D01*
G01X727500Y199565D02*
Y193825D01*
G01X732300Y571000D02*
X739000D01*
G01X740000Y901000D02*
X751000D01*
G01X769794Y582968D02*
X763094D01*
G01X782500Y359000D02*
Y364000D01*
G01Y367000D02*
Y372000D01*
G01Y375000D02*
Y380000D01*
G01Y383000D02*
Y388000D01*
G01X789500Y729000D02*
X784500D01*
G01X820500Y379500D02*
Y384500D01*
G01Y371500D02*
Y376500D01*
G01Y395500D02*
Y400500D01*
G01Y387500D02*
Y392500D01*
G01X814338Y439540D02*
X809338D01*
G01X822938D02*
X817938D01*
G01X837319Y-438119D02*
Y-518119D01*
G01X851500Y367500D02*
Y372500D01*
G01Y376000D02*
Y381000D01*
G01X848500Y724000D02*
Y729000D01*
G01X992500Y517700D02*
Y511000D01*
G01X1006500Y517700D02*
Y511000D01*
G01X1034819Y-438119D02*
Y-518119D01*
G01X1066819Y-422119D02*
X1034819D01*
G01X1031000Y258000D02*
X1026000D01*
G01X1039000D02*
X1034000D01*
G01X1050819Y-438119D02*
Y-406119D01*
G01X1062819Y-422119D02*
G02I-12000J0D01*
G01X1057669D02*
G02I-6850J0D01*
G01X1043468Y176784D02*
X1048468D01*
G01X1049216Y909468D02*
Y904468D01*
G01Y917468D02*
Y912468D01*
G01X1064000Y177000D02*
X1069000D01*
G01X1056500Y861000D02*
Y856000D01*
G01Y853000D02*
Y848000D01*
G01Y877000D02*
Y872000D01*
G01Y869000D02*
Y864000D01*
G01X1074500Y162000D02*
X1069500D01*
G01X1082500D02*
X1077500D01*
G01X1072000Y177000D02*
X1077000D01*
G01X1082968Y886284D02*
X1087968D01*
G01X1098250Y87300D02*
Y94300D01*
G01X1090968Y886284D02*
X1095968D01*
G01X1116968Y252284D02*
X1111968D01*
G01X1114468Y274984D02*
X1106468D01*
G01X1126000Y829500D02*
X1131000D01*
G01X1138968Y880284D02*
X1143968D01*
G01X1146968D02*
X1151968D01*
G01X1165859Y803801D02*
X1172159D01*
Y797501D01*
G01X1154968Y880284D02*
X1159968D01*
G01X1162968D02*
X1167968D01*
G01X1179500Y377700D02*
Y370000D01*
G01X1193170Y659882D02*
Y653582D01*
X1186870D01*
G01X1254968Y470284D02*
X1259968D01*
G01X1261000Y573000D02*
Y568000D01*
G01X1275000Y466500D02*
X1280000D01*
G01X1283566Y34133D02*
Y43033D01*
G01X1283122Y311000D02*
X1291722D01*
G01X1296000Y450000D02*
X1291000D01*
G01Y466500D02*
X1296000D01*
G01X1283000D02*
X1288000D01*
G01X1292968Y652984D02*
X1284968D01*
G01X1292468Y684484D02*
X1284468D01*
G01X1309450Y10050D02*
X1315550D01*
G01X1314668Y886784D02*
Y894784D01*
G01X1317950Y10050D02*
X1324050D01*
G01X1326350Y59100D02*
X1321700D01*
G01X1336668Y655784D02*
Y663784D01*
G01X1369000Y426000D02*
X1364000D01*
G01X1368500Y390500D02*
Y385500D01*
G01Y382500D02*
Y377500D01*
G01X1377000Y426000D02*
X1372000D01*
G01X1389996Y33691D02*
Y26191D01*
G01X1382496Y33691D02*
X1389996D01*
G01X1395984Y325832D02*
Y315732D01*
G01X1386884Y314032D02*
Y324132D01*
G54D22*
G01X-185516Y-508119D02*
Y-490619D01*
G01X-176346D02*
Y-508119D01*
G01Y-499369D02*
X-185516D01*
G01X-163431Y-508119D02*
X-165178Y-507827D01*
X-166706Y-506661D01*
X-168016Y-504911D01*
X-168890Y-502869D01*
X-169326Y-500536D01*
Y-498202D01*
X-168890Y-495869D01*
X-168016Y-493827D01*
X-166706Y-492078D01*
X-165178Y-490911D01*
X-163431Y-490619D01*
X-161685Y-490911D01*
X-160156Y-492078D01*
X-158846Y-493827D01*
X-157972Y-495869D01*
X-157536Y-498202D01*
Y-500536D01*
X-157972Y-502869D01*
X-158846Y-504911D01*
X-160156Y-506661D01*
X-161685Y-507827D01*
X-163431Y-508119D01*
G01X-150953D02*
Y-490619D01*
X-140909Y-508119D01*
Y-490619D01*
G01X-124064Y-508119D02*
X-132798D01*
Y-490619D01*
X-124064D01*
G01X-127558Y-499077D02*
X-132798D01*
G01X-110931Y-508119D02*
Y-500244D01*
X-115298Y-490619D01*
G01X-106564D02*
X-110931Y-500244D01*
G01X-74185Y-498786D02*
X-73311Y-497911D01*
X-72656Y-496453D01*
X-72219Y-494410D01*
X-72656Y-492661D01*
X-73529Y-491494D01*
X-75058Y-490619D01*
X-80953D01*
Y-508119D01*
X-73748D01*
X-72219Y-506953D01*
X-71346Y-505202D01*
X-70909Y-503161D01*
X-71346Y-501119D01*
X-72656Y-499369D01*
X-74185Y-498786D01*
X-80953D01*
G01X-63890Y-508119D02*
X-58431Y-490619D01*
X-52972Y-508119D01*
G01X-54938Y-501994D02*
X-61925D01*
G01X-45734Y-508119D02*
Y-490619D01*
X-41368D01*
X-39621Y-491494D01*
X-38311Y-492661D01*
X-37219Y-494410D01*
X-36346Y-496453D01*
X-36128Y-499369D01*
X-36346Y-502286D01*
X-37219Y-504328D01*
X-38311Y-506078D01*
X-39621Y-507244D01*
X-41368Y-508119D01*
X-45734D01*
G01X-22121Y-499369D02*
X-17754D01*
Y-504619D01*
X-19064Y-506369D01*
X-20593Y-507536D01*
X-22776Y-508119D01*
X-24959Y-507536D01*
X-26488Y-506369D01*
X-27798Y-504619D01*
X-28671Y-502577D01*
X-29108Y-500244D01*
Y-498202D01*
X-28671Y-496453D01*
X-27798Y-494410D01*
X-26488Y-492661D01*
X-25178Y-491494D01*
X-23431Y-490619D01*
X-21903D01*
X-20156Y-491202D01*
X-18846Y-492369D01*
G01X-1564Y-508119D02*
X-10298D01*
Y-490619D01*
X-1564D01*
G01X-5058Y-499077D02*
X-10298D01*
G01X7202Y-508119D02*
Y-490619D01*
X12661D01*
X14407Y-491494D01*
X15499Y-492661D01*
X15936Y-494994D01*
X15499Y-497328D01*
X14189Y-498786D01*
X12661Y-499661D01*
X7202D01*
G01X12661D02*
X15936Y-508119D01*
G01X48315Y-498786D02*
X49189Y-497911D01*
X49844Y-496453D01*
X50281Y-494410D01*
X49844Y-492661D01*
X48971Y-491494D01*
X47442Y-490619D01*
X41547D01*
Y-508119D01*
X48752D01*
X50281Y-506953D01*
X51154Y-505202D01*
X51591Y-503161D01*
X51154Y-501119D01*
X49844Y-499369D01*
X48315Y-498786D01*
X41547D01*
G01X58610Y-508119D02*
X64069Y-490619D01*
X69528Y-508119D01*
G01X67562Y-501994D02*
X60575D01*
G01X76984Y-505786D02*
X78731Y-507244D01*
X80696Y-508119D01*
X82442D01*
X84189Y-507244D01*
X85499Y-505786D01*
X86154Y-503744D01*
X85717Y-501703D01*
X84626Y-499952D01*
X82661Y-498786D01*
X80041Y-498202D01*
X78512Y-497036D01*
X77857Y-494994D01*
X78294Y-492952D01*
X79386Y-491494D01*
X80914Y-490619D01*
X82442D01*
X83971Y-491202D01*
X85281Y-492661D01*
G01X103436Y-508119D02*
X94702D01*
Y-490619D01*
X103436D01*
G01X99942Y-499077D02*
X94702D01*
G01X118315Y-498786D02*
X119189Y-497911D01*
X119844Y-496453D01*
X120281Y-494410D01*
X119844Y-492661D01*
X118971Y-491494D01*
X117442Y-490619D01*
X111547D01*
Y-508119D01*
X118752D01*
X120281Y-506953D01*
X121154Y-505202D01*
X121591Y-503161D01*
X121154Y-501119D01*
X119844Y-499369D01*
X118315Y-498786D01*
X111547D01*
G01X134069Y-508119D02*
X132322Y-507827D01*
X130794Y-506661D01*
X129484Y-504911D01*
X128610Y-502869D01*
X128174Y-500536D01*
Y-498202D01*
X128610Y-495869D01*
X129484Y-493827D01*
X130794Y-492078D01*
X132322Y-490911D01*
X134069Y-490619D01*
X135815Y-490911D01*
X137344Y-492078D01*
X138654Y-493827D01*
X139528Y-495869D01*
X139964Y-498202D01*
Y-500536D01*
X139528Y-502869D01*
X138654Y-504911D01*
X137344Y-506661D01*
X135815Y-507827D01*
X134069Y-508119D01*
G01X146110D02*
X151569Y-490619D01*
X157028Y-508119D01*
G01X155062Y-501994D02*
X148075D01*
G01X164702Y-508119D02*
Y-490619D01*
X170161D01*
X171907Y-491494D01*
X172999Y-492661D01*
X173436Y-494994D01*
X172999Y-497328D01*
X171689Y-498786D01*
X170161Y-499661D01*
X164702D01*
G01X170161D02*
X173436Y-508119D01*
G01X181766D02*
Y-490619D01*
X186132D01*
X187879Y-491494D01*
X189189Y-492661D01*
X190281Y-494410D01*
X191154Y-496453D01*
X191372Y-499369D01*
X191154Y-502286D01*
X190281Y-504328D01*
X189189Y-506078D01*
X187879Y-507244D01*
X186132Y-508119D01*
X181766D01*
G01X-37858Y-463119D02*
Y-445619D01*
X-32181Y-460202D01*
X-26504Y-445619D01*
Y-463119D01*
G01X-14681D02*
X-15991Y-462827D01*
X-17301Y-461661D01*
X-18175Y-459619D01*
X-18611Y-457286D01*
X-18175Y-454952D01*
X-17301Y-452911D01*
X-15991Y-451744D01*
X-14681Y-451453D01*
X-13371Y-451744D01*
X-12061Y-452911D01*
X-11188Y-454952D01*
X-10969Y-457286D01*
X-11188Y-459619D01*
X-12061Y-461661D01*
X-13371Y-462827D01*
X-14681Y-463119D01*
G01X6749Y-445619D02*
Y-463119D01*
G01Y-460495D02*
X5876Y-461953D01*
X4565Y-462827D01*
X3037Y-463119D01*
X1291Y-462536D01*
X-19Y-461078D01*
X-893Y-459328D01*
X-1111Y-457286D01*
X-893Y-455244D01*
X-19Y-453494D01*
X1291Y-452036D01*
X3037Y-451453D01*
X4565Y-451744D01*
X5657Y-452328D01*
X6749Y-453494D01*
G01X17044Y-455244D02*
X24031D01*
X23376Y-453202D01*
X22284Y-452036D01*
X20756Y-451453D01*
X19227Y-451744D01*
X17917Y-452619D01*
X17044Y-454661D01*
X16607Y-456411D01*
Y-458161D01*
X17044Y-459911D01*
X18136Y-461661D01*
X19446Y-462827D01*
X20974Y-463119D01*
X22502Y-462536D01*
X24031Y-460786D01*
G01X37819Y-463119D02*
Y-445619D01*
G01X281019Y-508119D02*
Y-490619D01*
X278399Y-494119D01*
G01Y-508119D02*
X283639D01*
G01X293716Y-504619D02*
X295025Y-506661D01*
X296772Y-507827D01*
X298737Y-508119D01*
X300484Y-507827D01*
X302231Y-506369D01*
X303322Y-504619D01*
X303541Y-502869D01*
X303104Y-500828D01*
X301576Y-499369D01*
X300047Y-498786D01*
X298082D01*
G01X300047D02*
X301357Y-497911D01*
X302449Y-496453D01*
X302886Y-494703D01*
X302449Y-492952D01*
X301357Y-491494D01*
X299392Y-490619D01*
X297427Y-490911D01*
X295462Y-492078D01*
G01X312307Y-506078D02*
X313836Y-507536D01*
X315582Y-508119D01*
X317329Y-507536D01*
X318857Y-505786D01*
X319949Y-503161D01*
X320386Y-500536D01*
Y-497328D01*
X319949Y-494703D01*
X318857Y-492369D01*
X317547Y-491202D01*
X316019Y-490619D01*
X314272Y-491202D01*
X312962Y-492369D01*
X312089Y-494119D01*
X311652Y-496453D01*
X312089Y-498494D01*
X313181Y-500536D01*
X314491Y-501703D01*
X316019Y-501994D01*
X317765Y-501411D01*
X319076Y-499952D01*
X320386Y-497328D01*
G01X336139Y-508119D02*
Y-490619D01*
X328060Y-503161D01*
X338978D01*
G01X351019Y-508119D02*
X352547Y-507827D01*
X354294Y-506953D01*
X355386Y-505495D01*
X355822Y-503452D01*
X355386Y-501411D01*
X354076Y-499661D01*
X352111Y-498786D01*
X349927D01*
X348617Y-498202D01*
X347525Y-496744D01*
X347089Y-494703D01*
X347744Y-492661D01*
X349272Y-491202D01*
X351019Y-490619D01*
X352765Y-491202D01*
X354294Y-492661D01*
X354949Y-494703D01*
X354512Y-496744D01*
X353421Y-498202D01*
X352111Y-498786D01*
X349927D01*
X347962Y-499661D01*
X346652Y-501411D01*
X346216Y-503452D01*
X346652Y-505495D01*
X347744Y-506953D01*
X349491Y-507827D01*
X351019Y-508119D01*
G01X267902Y-463119D02*
Y-445619D01*
X273142D01*
X274889Y-446494D01*
X276199Y-448536D01*
X276636Y-450869D01*
X276199Y-453202D01*
X275107Y-454952D01*
X273142Y-455828D01*
X267902D01*
G01X294572Y-447078D02*
X293262Y-446202D01*
X291734Y-445619D01*
X289987D01*
X288022Y-446494D01*
X286494Y-447952D01*
X285402Y-449703D01*
X284529Y-452619D01*
X284310Y-455244D01*
X284747Y-457869D01*
X285402Y-459619D01*
X286712Y-461369D01*
X288241Y-462536D01*
X289769Y-463119D01*
X291297D01*
X292826Y-462536D01*
X294136Y-461661D01*
X295228Y-460495D01*
G01X309015Y-453786D02*
X309889Y-452911D01*
X310544Y-451453D01*
X310981Y-449410D01*
X310544Y-447661D01*
X309671Y-446494D01*
X308142Y-445619D01*
X302247D01*
Y-463119D01*
X309452D01*
X310981Y-461953D01*
X311854Y-460202D01*
X312291Y-458161D01*
X311854Y-456119D01*
X310544Y-454369D01*
X309015Y-453786D01*
X302247D01*
G01X318219Y-468952D02*
X331319D01*
G01X337247Y-463119D02*
Y-445619D01*
X347291Y-463119D01*
Y-445619D01*
G01X359769Y-463119D02*
X358022Y-462827D01*
X356494Y-461661D01*
X355184Y-459911D01*
X354310Y-457869D01*
X353874Y-455536D01*
Y-453202D01*
X354310Y-450869D01*
X355184Y-448827D01*
X356494Y-447078D01*
X358022Y-445911D01*
X359769Y-445619D01*
X361515Y-445911D01*
X363044Y-447078D01*
X364354Y-448827D01*
X365228Y-450869D01*
X365664Y-453202D01*
Y-455536D01*
X365228Y-457869D01*
X364354Y-459911D01*
X363044Y-461661D01*
X361515Y-462827D01*
X359769Y-463119D01*
G01X410610Y-445619D02*
X416069Y-463119D01*
X421528Y-445619D01*
G01X437936Y-463119D02*
X429202D01*
Y-445619D01*
X437936D01*
G01X434442Y-454077D02*
X429202D01*
G01X446702Y-463119D02*
Y-445619D01*
X452161D01*
X453907Y-446494D01*
X454999Y-447661D01*
X455436Y-449994D01*
X454999Y-452328D01*
X453689Y-453786D01*
X452161Y-454661D01*
X446702D01*
G01X452161D02*
X455436Y-463119D01*
G01X468569Y-463702D02*
X468132Y-463411D01*
Y-462827D01*
X468569Y-462536D01*
X469006Y-462827D01*
Y-463411D01*
X468569Y-463702D01*
G01X433569Y-508119D02*
Y-490619D01*
X430949Y-494119D01*
G01Y-508119D02*
X436189D01*
G01X452815Y-498786D02*
X453689Y-497911D01*
X454344Y-496453D01*
X454781Y-494410D01*
X454344Y-492661D01*
X453471Y-491494D01*
X451942Y-490619D01*
X446047D01*
Y-508119D01*
X453252D01*
X454781Y-506953D01*
X455654Y-505202D01*
X456091Y-503161D01*
X455654Y-501119D01*
X454344Y-499369D01*
X452815Y-498786D01*
X446047D01*
G01X548519Y-490619D02*
Y-508119D01*
G01X543497Y-490619D02*
X553541D01*
G01X561434Y-505786D02*
X563181Y-507244D01*
X565146Y-508119D01*
X566892D01*
X568639Y-507244D01*
X569949Y-505786D01*
X570604Y-503744D01*
X570167Y-501703D01*
X569076Y-499952D01*
X567111Y-498786D01*
X564491Y-498202D01*
X562962Y-497036D01*
X562307Y-494994D01*
X562744Y-492952D01*
X563836Y-491494D01*
X565364Y-490619D01*
X566892D01*
X568421Y-491202D01*
X569731Y-492661D01*
G01X580899Y-490619D02*
X586139D01*
G01X583519D02*
Y-508119D01*
G01X580899D02*
X586139D01*
G01X596652Y-490619D02*
Y-508119D01*
X605386D01*
G01X613716D02*
Y-490619D01*
G01X622012D02*
X613716Y-501411D01*
G01X623322Y-508119D02*
X617427Y-496453D01*
G01X544152Y-445619D02*
Y-463119D01*
X552886D01*
G01X569949D02*
Y-451453D01*
G01Y-453494D02*
X569076Y-452328D01*
X567765Y-451744D01*
X566237Y-451453D01*
X564709Y-452036D01*
X563399Y-453202D01*
X562525Y-454952D01*
X562089Y-457286D01*
X562525Y-459619D01*
X563399Y-461369D01*
X564709Y-462536D01*
X566237Y-463119D01*
X567765Y-462827D01*
X569076Y-461953D01*
X569949Y-460786D01*
G01X578934Y-468369D02*
X580244Y-468952D01*
X581991Y-468369D01*
X583082Y-467203D01*
X583956Y-465744D01*
X585265Y-461078D01*
X588104Y-451453D01*
G01X581117D02*
X585265Y-461078D01*
G01X597744Y-455244D02*
X604731D01*
X604076Y-453202D01*
X602984Y-452036D01*
X601456Y-451453D01*
X599927Y-451744D01*
X598617Y-452619D01*
X597744Y-454661D01*
X597307Y-456411D01*
Y-458161D01*
X597744Y-459911D01*
X598836Y-461661D01*
X600146Y-462827D01*
X601674Y-463119D01*
X603202Y-462536D01*
X604731Y-460786D01*
G01X615462Y-463119D02*
Y-451453D01*
G01Y-453786D02*
X616554Y-452619D01*
X617646Y-451744D01*
X619174Y-451453D01*
X620265Y-451744D01*
X621576Y-452619D01*
G01X686702Y-490619D02*
Y-508119D01*
X695436D01*
G01X703984Y-513369D02*
X705294Y-513952D01*
X707041Y-513369D01*
X708132Y-512203D01*
X709006Y-510744D01*
X710315Y-506078D01*
X713154Y-496453D01*
G01X706167D02*
X710315Y-506078D01*
G01X722357Y-508119D02*
Y-496453D01*
G01Y-499369D02*
X723231Y-497911D01*
X724541Y-496744D01*
X726287Y-496453D01*
X727815Y-496744D01*
X729126Y-497911D01*
X729781Y-499952D01*
Y-508119D01*
G01X739857D02*
Y-496453D01*
G01Y-499369D02*
X740731Y-497911D01*
X742041Y-496744D01*
X743787Y-496453D01*
X745315Y-496744D01*
X746626Y-497911D01*
X747281Y-499952D01*
Y-508119D01*
G01X774202Y-490619D02*
Y-508119D01*
X782936D01*
G01X796069Y-496453D02*
Y-508119D01*
G01Y-491786D02*
X795632Y-491494D01*
Y-490911D01*
X796069Y-490619D01*
X796506Y-490911D01*
Y-491494D01*
X796069Y-491786D01*
G01X809857Y-496453D02*
Y-504619D01*
X810731Y-506661D01*
X812041Y-507827D01*
X813569Y-508119D01*
X815097Y-507827D01*
X816407Y-506661D01*
X817281Y-504619D01*
G01Y-508119D02*
Y-496453D01*
G01X686266Y-463119D02*
Y-445619D01*
X690632D01*
X692379Y-446494D01*
X693689Y-447661D01*
X694781Y-449410D01*
X695654Y-451453D01*
X695872Y-454369D01*
X695654Y-457286D01*
X694781Y-459328D01*
X693689Y-461078D01*
X692379Y-462244D01*
X690632Y-463119D01*
X686266D01*
G01X705294Y-455244D02*
X712281D01*
X711626Y-453202D01*
X710534Y-452036D01*
X709006Y-451453D01*
X707477Y-451744D01*
X706167Y-452619D01*
X705294Y-454661D01*
X704857Y-456411D01*
Y-458161D01*
X705294Y-459911D01*
X706386Y-461661D01*
X707696Y-462827D01*
X709224Y-463119D01*
X710752Y-462536D01*
X712281Y-460786D01*
G01X722794Y-461078D02*
X723886Y-462244D01*
X725414Y-463119D01*
X726724D01*
X728034Y-462536D01*
X728907Y-461661D01*
X729344Y-460495D01*
X729126Y-458744D01*
X728252Y-457869D01*
X724322Y-456119D01*
X723449Y-454077D01*
X723886Y-452619D01*
X724759Y-451744D01*
X726069Y-451453D01*
X727379Y-451744D01*
X728689Y-452619D01*
G01X743569Y-451453D02*
Y-463119D01*
G01Y-446786D02*
X743132Y-446494D01*
Y-445911D01*
X743569Y-445619D01*
X744006Y-445911D01*
Y-446494D01*
X743569Y-446786D01*
G01X758012Y-467494D02*
X759541Y-468661D01*
X761287Y-468952D01*
X762815Y-468661D01*
X764126Y-467203D01*
X764999Y-465161D01*
Y-451453D01*
G01Y-453786D02*
X764126Y-452619D01*
X762815Y-451744D01*
X761287Y-451453D01*
X759541Y-452036D01*
X758449Y-453202D01*
X757575Y-455244D01*
X757139Y-457286D01*
X757357Y-459036D01*
X758231Y-461078D01*
X759541Y-462536D01*
X761287Y-463119D01*
X762597Y-462827D01*
X764126Y-461661D01*
X764999Y-460495D01*
G01X774857Y-463119D02*
Y-451453D01*
G01Y-454369D02*
X775731Y-452911D01*
X777041Y-451744D01*
X778787Y-451453D01*
X780315Y-451744D01*
X781626Y-452911D01*
X782281Y-454952D01*
Y-463119D01*
G01X792794Y-455244D02*
X799781D01*
X799126Y-453202D01*
X798034Y-452036D01*
X796506Y-451453D01*
X794977Y-451744D01*
X793667Y-452619D01*
X792794Y-454661D01*
X792357Y-456411D01*
Y-458161D01*
X792794Y-459911D01*
X793886Y-461661D01*
X795196Y-462827D01*
X796724Y-463119D01*
X798252Y-462536D01*
X799781Y-460786D01*
G01X810512Y-463119D02*
Y-451453D01*
G01Y-453786D02*
X811604Y-452619D01*
X812696Y-451744D01*
X814224Y-451453D01*
X815315Y-451744D01*
X816626Y-452619D01*
G01X857269Y-508119D02*
Y-490619D01*
X854649Y-494119D01*
G01Y-508119D02*
X859889D01*
G01X874769D02*
Y-490619D01*
X872149Y-494119D01*
G01Y-508119D02*
X877389D01*
G01X888339Y-508702D02*
X896199Y-490619D01*
G01X909769Y-508119D02*
Y-490619D01*
X907149Y-494119D01*
G01Y-508119D02*
X912389D01*
G01X922466Y-504619D02*
X923775Y-506661D01*
X925522Y-507827D01*
X927487Y-508119D01*
X929234Y-507827D01*
X930981Y-506369D01*
X932072Y-504619D01*
X932291Y-502869D01*
X931854Y-500828D01*
X930326Y-499369D01*
X928797Y-498786D01*
X926832D01*
G01X928797D02*
X930107Y-497911D01*
X931199Y-496453D01*
X931636Y-494703D01*
X931199Y-492952D01*
X930107Y-491494D01*
X928142Y-490619D01*
X926177Y-490911D01*
X924212Y-492078D01*
G01X940839Y-508702D02*
X948699Y-490619D01*
G01X958121Y-493536D02*
X959431Y-491786D01*
X960959Y-490911D01*
X962706Y-490619D01*
X964889Y-491202D01*
X966417Y-492661D01*
X966854Y-494410D01*
X966636Y-496161D01*
X965762Y-497619D01*
X961396Y-500536D01*
X959431Y-502577D01*
X958121Y-505495D01*
X957684Y-508119D01*
X966854D01*
G01X979769Y-490619D02*
X978022Y-491202D01*
X976712Y-492661D01*
X975839Y-494410D01*
X975184Y-496744D01*
X974966Y-499369D01*
X975184Y-501994D01*
X975839Y-504328D01*
X976712Y-506078D01*
X978022Y-507536D01*
X979769Y-508119D01*
X981515Y-507536D01*
X982826Y-506078D01*
X983699Y-504328D01*
X984354Y-501994D01*
X984572Y-499369D01*
X984354Y-496744D01*
X983699Y-494410D01*
X982826Y-492661D01*
X981515Y-491202D01*
X979769Y-490619D01*
G01X997269Y-508119D02*
Y-490619D01*
X994649Y-494119D01*
G01Y-508119D02*
X999889D01*
G01X1017389D02*
Y-490619D01*
X1009310Y-503161D01*
X1020228D01*
G01X904966Y-463119D02*
Y-445619D01*
X909332D01*
X911079Y-446494D01*
X912389Y-447661D01*
X913481Y-449410D01*
X914354Y-451453D01*
X914572Y-454369D01*
X914354Y-457286D01*
X913481Y-459328D01*
X912389Y-461078D01*
X911079Y-462244D01*
X909332Y-463119D01*
X904966D01*
G01X931199D02*
Y-451453D01*
G01Y-453494D02*
X930326Y-452328D01*
X929015Y-451744D01*
X927487Y-451453D01*
X925959Y-452036D01*
X924649Y-453202D01*
X923775Y-454952D01*
X923339Y-457286D01*
X923775Y-459619D01*
X924649Y-461369D01*
X925959Y-462536D01*
X927487Y-463119D01*
X929015Y-462827D01*
X930326Y-461953D01*
X931199Y-460786D01*
G01X944769Y-445619D02*
Y-463119D01*
G01X941712Y-451453D02*
X947826D01*
G01X958994Y-455244D02*
X965981D01*
X965326Y-453202D01*
X964234Y-452036D01*
X962706Y-451453D01*
X961177Y-451744D01*
X959867Y-452619D01*
X958994Y-454661D01*
X958557Y-456411D01*
Y-458161D01*
X958994Y-459911D01*
X960086Y-461661D01*
X961396Y-462827D01*
X962924Y-463119D01*
X964452Y-462536D01*
X965981Y-460786D01*
G01X10405Y307086D02*
Y273428D01*
X107705D01*
G01Y307086D02*
Y433028D01*
X10405D01*
Y307086D01*
X107705D01*
G01X17304Y843203D02*
X19096D01*
X19471Y843370D01*
X19721Y843703D01*
X19804Y844120D01*
X19721Y844537D01*
X19471Y844870D01*
X19096Y845037D01*
X17304D01*
G01X19429Y846303D02*
X19637Y846553D01*
X19762Y846845D01*
X19804Y847220D01*
X19721Y847595D01*
X19554Y847887D01*
X19262Y848095D01*
X18929Y848137D01*
X18596Y848053D01*
X18387Y847845D01*
X18221Y847553D01*
X18179Y847262D01*
X18221Y846970D01*
X18387Y846595D01*
X17304Y846720D01*
Y847845D01*
G01Y850320D02*
X17387Y849987D01*
X17596Y849737D01*
X17846Y849570D01*
X18179Y849445D01*
X18554Y849403D01*
X18929Y849445D01*
X19262Y849570D01*
X19512Y849737D01*
X19721Y849987D01*
X19804Y850320D01*
X19721Y850653D01*
X19512Y850903D01*
X19262Y851070D01*
X18929Y851195D01*
X18554Y851237D01*
X18179Y851195D01*
X17846Y851070D01*
X17596Y850903D01*
X17387Y850653D01*
X17304Y850320D01*
G01X4321Y839720D02*
Y842220D01*
X5362D01*
X5696Y842095D01*
X5904Y841928D01*
X5987Y841595D01*
X5904Y841262D01*
X5654Y841053D01*
X5362Y840928D01*
X4321D01*
G01X5362D02*
X5987Y839720D01*
G01X7462Y840762D02*
X7754Y841053D01*
X8004Y841220D01*
X8337Y841303D01*
X8629Y841220D01*
X8837Y841053D01*
X9004Y840803D01*
X9046Y840512D01*
X9004Y840262D01*
X8837Y840012D01*
X8587Y839803D01*
X8296Y839720D01*
X7962Y839803D01*
X7671Y840053D01*
X7504Y840428D01*
X7462Y840845D01*
X7546Y841387D01*
X7671Y841678D01*
X7879Y841970D01*
X8171Y842178D01*
X8462Y842220D01*
X8754Y842137D01*
X8962Y841928D01*
G01X10562Y841803D02*
X10812Y842053D01*
X11104Y842178D01*
X11437Y842220D01*
X11854Y842137D01*
X12146Y841928D01*
X12229Y841678D01*
X12187Y841428D01*
X12021Y841220D01*
X11187Y840803D01*
X10812Y840512D01*
X10562Y840095D01*
X10479Y839720D01*
X12229D01*
G01X14454D02*
Y842220D01*
X13954Y841720D01*
G01Y839720D02*
X14954D01*
G01X4321Y844220D02*
Y846720D01*
X5362D01*
X5696Y846595D01*
X5904Y846428D01*
X5987Y846095D01*
X5904Y845762D01*
X5654Y845553D01*
X5362Y845428D01*
X4321D01*
G01X5362D02*
X5987Y844220D01*
G01X7462Y845262D02*
X7754Y845553D01*
X8004Y845720D01*
X8337Y845803D01*
X8629Y845720D01*
X8837Y845553D01*
X9004Y845303D01*
X9046Y845012D01*
X9004Y844762D01*
X8837Y844512D01*
X8587Y844303D01*
X8296Y844220D01*
X7962Y844303D01*
X7671Y844553D01*
X7504Y844928D01*
X7462Y845345D01*
X7546Y845887D01*
X7671Y846178D01*
X7879Y846470D01*
X8171Y846678D01*
X8462Y846720D01*
X8754Y846637D01*
X8962Y846428D01*
G01X10562Y846303D02*
X10812Y846553D01*
X11104Y846678D01*
X11437Y846720D01*
X11854Y846637D01*
X12146Y846428D01*
X12229Y846178D01*
X12187Y845928D01*
X12021Y845720D01*
X11187Y845303D01*
X10812Y845012D01*
X10562Y844595D01*
X10479Y844220D01*
X12229D01*
G01X13537Y844720D02*
X13787Y844428D01*
X14121Y844262D01*
X14496Y844220D01*
X14829Y844262D01*
X15162Y844470D01*
X15371Y844720D01*
X15412Y844970D01*
X15329Y845262D01*
X15037Y845470D01*
X14746Y845553D01*
X14371D01*
G01X14746D02*
X14996Y845678D01*
X15204Y845887D01*
X15287Y846137D01*
X15204Y846387D01*
X14996Y846595D01*
X14621Y846720D01*
X14246Y846678D01*
X13871Y846512D01*
G01X11000Y854017D02*
X8500D01*
Y855058D01*
X8625Y855392D01*
X8792Y855600D01*
X9125Y855683D01*
X9458Y855600D01*
X9667Y855350D01*
X9792Y855058D01*
Y854017D01*
G01Y855058D02*
X11000Y855683D01*
G01X9958Y857158D02*
X9667Y857450D01*
X9500Y857700D01*
X9417Y858033D01*
X9500Y858325D01*
X9667Y858533D01*
X9917Y858700D01*
X10208Y858742D01*
X10458Y858700D01*
X10708Y858533D01*
X10917Y858283D01*
X11000Y857992D01*
X10917Y857658D01*
X10667Y857367D01*
X10292Y857200D01*
X9875Y857158D01*
X9333Y857242D01*
X9042Y857367D01*
X8750Y857575D01*
X8542Y857867D01*
X8500Y858158D01*
X8583Y858450D01*
X8792Y858658D01*
G01X8917Y860258D02*
X8667Y860508D01*
X8542Y860800D01*
X8500Y861133D01*
X8583Y861550D01*
X8792Y861842D01*
X9042Y861925D01*
X9292Y861883D01*
X9500Y861717D01*
X9917Y860883D01*
X10208Y860508D01*
X10625Y860258D01*
X11000Y860175D01*
Y861925D01*
G01X10625Y863233D02*
X10833Y863483D01*
X10958Y863775D01*
X11000Y864150D01*
X10917Y864525D01*
X10750Y864817D01*
X10458Y865025D01*
X10125Y865067D01*
X9792Y864983D01*
X9583Y864775D01*
X9417Y864483D01*
X9375Y864192D01*
X9417Y863900D01*
X9583Y863525D01*
X8500Y863650D01*
Y864775D01*
G01X4321Y848720D02*
Y851220D01*
X5362D01*
X5696Y851095D01*
X5904Y850928D01*
X5987Y850595D01*
X5904Y850262D01*
X5654Y850053D01*
X5362Y849928D01*
X4321D01*
G01X5362D02*
X5987Y848720D01*
G01X7462Y849762D02*
X7754Y850053D01*
X8004Y850220D01*
X8337Y850303D01*
X8629Y850220D01*
X8837Y850053D01*
X9004Y849803D01*
X9046Y849512D01*
X9004Y849262D01*
X8837Y849012D01*
X8587Y848803D01*
X8296Y848720D01*
X7962Y848803D01*
X7671Y849053D01*
X7504Y849428D01*
X7462Y849845D01*
X7546Y850387D01*
X7671Y850678D01*
X7879Y850970D01*
X8171Y851178D01*
X8462Y851220D01*
X8754Y851137D01*
X8962Y850928D01*
G01X10562Y850803D02*
X10812Y851053D01*
X11104Y851178D01*
X11437Y851220D01*
X11854Y851137D01*
X12146Y850928D01*
X12229Y850678D01*
X12187Y850428D01*
X12021Y850220D01*
X11187Y849803D01*
X10812Y849512D01*
X10562Y849095D01*
X10479Y848720D01*
X12229D01*
G01X13662Y850803D02*
X13912Y851053D01*
X14204Y851178D01*
X14537Y851220D01*
X14954Y851137D01*
X15246Y850928D01*
X15329Y850678D01*
X15287Y850428D01*
X15121Y850220D01*
X14287Y849803D01*
X13912Y849512D01*
X13662Y849095D01*
X13579Y848720D01*
X15329D01*
G01X16304Y889737D02*
X13804D01*
Y890778D01*
X13929Y891112D01*
X14096Y891320D01*
X14429Y891403D01*
X14762Y891320D01*
X14971Y891070D01*
X15096Y890778D01*
Y889737D01*
G01Y890778D02*
X16304Y891403D01*
G01Y893670D02*
X13804D01*
X14304Y893170D01*
G01X16304D02*
Y894170D01*
G01X15929Y895853D02*
X16137Y896103D01*
X16262Y896395D01*
X16304Y896770D01*
X16221Y897145D01*
X16054Y897437D01*
X15762Y897645D01*
X15429Y897687D01*
X15096Y897603D01*
X14887Y897395D01*
X14721Y897103D01*
X14679Y896812D01*
X14721Y896520D01*
X14887Y896145D01*
X13804Y896270D01*
Y897395D01*
G01X15929Y898953D02*
X16137Y899203D01*
X16262Y899495D01*
X16304Y899870D01*
X16221Y900245D01*
X16054Y900537D01*
X15762Y900745D01*
X15429Y900787D01*
X15096Y900703D01*
X14887Y900495D01*
X14721Y900203D01*
X14679Y899912D01*
X14721Y899620D01*
X14887Y899245D01*
X13804Y899370D01*
Y900495D01*
G01X11804Y889737D02*
X9304D01*
Y890778D01*
X9429Y891112D01*
X9596Y891320D01*
X9929Y891403D01*
X10262Y891320D01*
X10471Y891070D01*
X10596Y890778D01*
Y889737D01*
G01Y890778D02*
X11804Y891403D01*
G01Y893670D02*
X9304D01*
X9804Y893170D01*
G01X11804D02*
Y894170D01*
G01X11429Y895853D02*
X11637Y896103D01*
X11762Y896395D01*
X11804Y896770D01*
X11721Y897145D01*
X11554Y897437D01*
X11262Y897645D01*
X10929Y897687D01*
X10596Y897603D01*
X10387Y897395D01*
X10221Y897103D01*
X10179Y896812D01*
X10221Y896520D01*
X10387Y896145D01*
X9304Y896270D01*
Y897395D01*
G01X10762Y899078D02*
X10471Y899370D01*
X10304Y899620D01*
X10221Y899953D01*
X10304Y900245D01*
X10471Y900453D01*
X10721Y900620D01*
X11012Y900662D01*
X11262Y900620D01*
X11512Y900453D01*
X11721Y900203D01*
X11804Y899912D01*
X11721Y899578D01*
X11471Y899287D01*
X11096Y899120D01*
X10679Y899078D01*
X10137Y899162D01*
X9846Y899287D01*
X9554Y899495D01*
X9346Y899787D01*
X9304Y900078D01*
X9387Y900370D01*
X9596Y900578D01*
G01X7304Y889737D02*
X4804D01*
Y890778D01*
X4929Y891112D01*
X5096Y891320D01*
X5429Y891403D01*
X5762Y891320D01*
X5971Y891070D01*
X6096Y890778D01*
Y889737D01*
G01Y890778D02*
X7304Y891403D01*
G01Y893670D02*
X4804D01*
X5304Y893170D01*
G01X7304D02*
Y894170D01*
G01X6929Y895853D02*
X7137Y896103D01*
X7262Y896395D01*
X7304Y896770D01*
X7221Y897145D01*
X7054Y897437D01*
X6762Y897645D01*
X6429Y897687D01*
X6096Y897603D01*
X5887Y897395D01*
X5721Y897103D01*
X5679Y896812D01*
X5721Y896520D01*
X5887Y896145D01*
X4804Y896270D01*
Y897395D01*
G01X7304Y899870D02*
X7262Y900162D01*
X7137Y900495D01*
X6929Y900703D01*
X6637Y900787D01*
X6346Y900703D01*
X6096Y900453D01*
X5971Y900078D01*
Y899662D01*
X5887Y899412D01*
X5679Y899203D01*
X5387Y899120D01*
X5096Y899245D01*
X4887Y899537D01*
X4804Y899870D01*
X4887Y900203D01*
X5096Y900495D01*
X5387Y900620D01*
X5679Y900537D01*
X5887Y900328D01*
X5971Y900078D01*
Y899662D01*
X6096Y899287D01*
X6346Y899037D01*
X6637Y898953D01*
X6929Y899037D01*
X7137Y899245D01*
X7262Y899578D01*
X7304Y899870D01*
G01X15321Y883720D02*
Y886220D01*
X16362D01*
X16696Y886095D01*
X16904Y885928D01*
X16987Y885595D01*
X16904Y885262D01*
X16654Y885053D01*
X16362Y884928D01*
X15321D01*
G01X16362D02*
X16987Y883720D01*
G01X18337Y884095D02*
X18587Y883887D01*
X18879Y883762D01*
X19254Y883720D01*
X19629Y883803D01*
X19921Y883970D01*
X20129Y884262D01*
X20171Y884595D01*
X20087Y884928D01*
X19879Y885137D01*
X19587Y885303D01*
X19296Y885345D01*
X19004Y885303D01*
X18629Y885137D01*
X18754Y886220D01*
X19879D01*
G01X21437Y884220D02*
X21687Y883928D01*
X22021Y883762D01*
X22396Y883720D01*
X22729Y883762D01*
X23062Y883970D01*
X23271Y884220D01*
X23312Y884470D01*
X23229Y884762D01*
X22937Y884970D01*
X22646Y885053D01*
X22271D01*
G01X22646D02*
X22896Y885178D01*
X23104Y885387D01*
X23187Y885637D01*
X23104Y885887D01*
X22896Y886095D01*
X22521Y886220D01*
X22146Y886178D01*
X21771Y886012D01*
G01X25371Y883720D02*
X25454Y884262D01*
X25579Y884720D01*
X25746Y885137D01*
X25954Y885595D01*
X26287Y886220D01*
X24621D01*
G01X31355Y360828D02*
Y408128D01*
G01X86755Y360828D02*
X31355D01*
G01Y408128D02*
X86755D01*
G01X41000Y549000D02*
X122500D01*
Y480000D01*
X26500D01*
Y549000D01*
X41000D01*
G01X31722Y506425D02*
X31930Y506758D01*
X32055Y507133D01*
Y507467D01*
X31930Y507800D01*
X31722Y508050D01*
X31430Y508175D01*
X31138Y508092D01*
X30888Y507883D01*
X30722Y507508D01*
X30638Y507008D01*
X30472Y506717D01*
X30180Y506592D01*
X29888Y506675D01*
X29680Y506883D01*
X29555Y507175D01*
Y507467D01*
X29638Y507758D01*
X29847Y508008D01*
G01X32055Y509567D02*
X29555D01*
Y510608D01*
X29680Y510942D01*
X29847Y511150D01*
X30180Y511233D01*
X30513Y511150D01*
X30722Y510900D01*
X30847Y510608D01*
Y509567D01*
G01Y510608D02*
X32055Y511233D01*
G01Y513500D02*
X32013Y513792D01*
X31888Y514125D01*
X31680Y514333D01*
X31388Y514417D01*
X31097Y514333D01*
X30847Y514083D01*
X30722Y513708D01*
Y513292D01*
X30638Y513042D01*
X30430Y512833D01*
X30138Y512750D01*
X29847Y512875D01*
X29638Y513167D01*
X29555Y513500D01*
X29638Y513833D01*
X29847Y514125D01*
X30138Y514250D01*
X30430Y514167D01*
X30638Y513958D01*
X30722Y513708D01*
Y513292D01*
X30847Y512917D01*
X31097Y512667D01*
X31388Y512583D01*
X31680Y512667D01*
X31888Y512875D01*
X32013Y513208D01*
X32055Y513500D01*
G01X31013Y515808D02*
X30722Y516100D01*
X30555Y516350D01*
X30472Y516683D01*
X30555Y516975D01*
X30722Y517183D01*
X30972Y517350D01*
X31263Y517392D01*
X31513Y517350D01*
X31763Y517183D01*
X31972Y516933D01*
X32055Y516642D01*
X31972Y516308D01*
X31722Y516017D01*
X31347Y515850D01*
X30930Y515808D01*
X30388Y515892D01*
X30097Y516017D01*
X29805Y516225D01*
X29597Y516517D01*
X29555Y516808D01*
X29638Y517100D01*
X29847Y517308D01*
G01X29972Y518908D02*
X29722Y519158D01*
X29597Y519450D01*
X29555Y519783D01*
X29638Y520200D01*
X29847Y520492D01*
X30097Y520575D01*
X30347Y520533D01*
X30555Y520367D01*
X30972Y519533D01*
X31263Y519158D01*
X31680Y518908D01*
X32055Y518825D01*
Y520575D01*
G01X36222Y506425D02*
X36430Y506758D01*
X36555Y507133D01*
Y507467D01*
X36430Y507800D01*
X36222Y508050D01*
X35930Y508175D01*
X35638Y508092D01*
X35388Y507883D01*
X35222Y507508D01*
X35138Y507008D01*
X34972Y506717D01*
X34680Y506592D01*
X34388Y506675D01*
X34180Y506883D01*
X34055Y507175D01*
Y507467D01*
X34138Y507758D01*
X34347Y508008D01*
G01X36555Y509567D02*
X34055D01*
Y510608D01*
X34180Y510942D01*
X34347Y511150D01*
X34680Y511233D01*
X35013Y511150D01*
X35222Y510900D01*
X35347Y510608D01*
Y509567D01*
G01Y510608D02*
X36555Y511233D01*
G01Y513417D02*
X36013Y513500D01*
X35555Y513625D01*
X35138Y513792D01*
X34680Y514000D01*
X34055Y514333D01*
Y512667D01*
G01X36555Y516517D02*
X36013Y516600D01*
X35555Y516725D01*
X35138Y516892D01*
X34680Y517100D01*
X34055Y517433D01*
Y515767D01*
G01X36555Y519700D02*
X34055D01*
X34555Y519200D01*
G01X36555D02*
Y520200D01*
G01X36222Y522875D02*
X36430Y523208D01*
X36555Y523583D01*
Y523917D01*
X36430Y524250D01*
X36222Y524500D01*
X35930Y524625D01*
X35638Y524542D01*
X35388Y524333D01*
X35222Y523958D01*
X35138Y523458D01*
X34972Y523167D01*
X34680Y523042D01*
X34388Y523125D01*
X34180Y523333D01*
X34055Y523625D01*
Y523917D01*
X34138Y524208D01*
X34347Y524458D01*
G01X34055Y526850D02*
X36555D01*
G01X34055Y525892D02*
Y527808D01*
G01X36555Y529117D02*
X34055D01*
Y530117D01*
X34180Y530450D01*
X34472Y530700D01*
X34805Y530783D01*
X35138Y530700D01*
X35388Y530492D01*
X35513Y530117D01*
Y529117D01*
G01X36555Y533050D02*
X34055D01*
X34555Y532550D01*
G01X36555D02*
Y533550D01*
G01Y536650D02*
X34055D01*
X35847Y535108D01*
Y537192D01*
G01X36180Y538333D02*
X36388Y538583D01*
X36513Y538875D01*
X36555Y539250D01*
X36472Y539625D01*
X36305Y539917D01*
X36013Y540125D01*
X35680Y540167D01*
X35347Y540083D01*
X35138Y539875D01*
X34972Y539583D01*
X34930Y539292D01*
X34972Y539000D01*
X35138Y538625D01*
X34055Y538750D01*
Y539875D01*
G01X35000Y823900D02*
X34958Y823567D01*
X34792Y823275D01*
X34542Y823025D01*
X34250Y822858D01*
X33917Y822775D01*
X33583D01*
X33250Y822858D01*
X32958Y823025D01*
X32708Y823275D01*
X32542Y823567D01*
X32500Y823900D01*
X32542Y824233D01*
X32708Y824525D01*
X32958Y824775D01*
X33250Y824942D01*
X33583Y825025D01*
X33917D01*
X34250Y824942D01*
X34542Y824775D01*
X34792Y824525D01*
X34958Y824233D01*
X35000Y823900D01*
G01X34333Y824233D02*
X35000Y824733D01*
G01X34708Y826292D02*
X34917Y826583D01*
X35000Y826917D01*
X34917Y827250D01*
X34667Y827542D01*
X34292Y827750D01*
X33917Y827833D01*
X33458D01*
X33083Y827750D01*
X32750Y827542D01*
X32583Y827292D01*
X32500Y827000D01*
X32583Y826667D01*
X32750Y826417D01*
X33000Y826250D01*
X33333Y826167D01*
X33625Y826250D01*
X33917Y826458D01*
X34083Y826708D01*
X34125Y827000D01*
X34042Y827333D01*
X33833Y827583D01*
X33458Y827833D01*
G01X32917Y829308D02*
X32667Y829558D01*
X32542Y829850D01*
X32500Y830183D01*
X32583Y830600D01*
X32792Y830892D01*
X33042Y830975D01*
X33292Y830933D01*
X33500Y830767D01*
X33917Y829933D01*
X34208Y829558D01*
X34625Y829308D01*
X35000Y829225D01*
Y830975D01*
G01X43504Y842220D02*
X30104D01*
G01D02*
Y852220D01*
G01X21104Y842720D02*
Y838720D01*
X28504D01*
G01Y843220D02*
Y847220D01*
X21104D01*
G01X30104Y852220D02*
X43504D01*
G01X21100Y856200D02*
Y852200D01*
X28500D01*
G01X28504Y847720D02*
Y851720D01*
X21104D01*
G01X32304Y888520D02*
X36304D01*
Y895920D01*
G01X27804Y888520D02*
X31804D01*
Y895920D01*
G01X23304Y888520D02*
X27304D01*
Y895920D01*
G01X35504Y883720D02*
Y887720D01*
X28104D01*
G01X20804Y889737D02*
X18304D01*
Y890778D01*
X18429Y891112D01*
X18596Y891320D01*
X18929Y891403D01*
X19262Y891320D01*
X19471Y891070D01*
X19596Y890778D01*
Y889737D01*
G01Y890778D02*
X20804Y891403D01*
G01X20429Y892753D02*
X20637Y893003D01*
X20762Y893295D01*
X20804Y893670D01*
X20721Y894045D01*
X20554Y894337D01*
X20262Y894545D01*
X19929Y894587D01*
X19596Y894503D01*
X19387Y894295D01*
X19221Y894003D01*
X19179Y893712D01*
X19221Y893420D01*
X19387Y893045D01*
X18304Y893170D01*
Y894295D01*
G01X20804Y896770D02*
X18304D01*
X18804Y896270D01*
G01X20804D02*
Y897270D01*
G01Y899870D02*
X20762Y900162D01*
X20637Y900495D01*
X20429Y900703D01*
X20137Y900787D01*
X19846Y900703D01*
X19596Y900453D01*
X19471Y900078D01*
Y899662D01*
X19387Y899412D01*
X19179Y899203D01*
X18887Y899120D01*
X18596Y899245D01*
X18387Y899537D01*
X18304Y899870D01*
X18387Y900203D01*
X18596Y900495D01*
X18887Y900620D01*
X19179Y900537D01*
X19387Y900328D01*
X19471Y900078D01*
Y899662D01*
X19596Y899287D01*
X19846Y899037D01*
X20137Y898953D01*
X20429Y899037D01*
X20637Y899245D01*
X20762Y899578D01*
X20804Y899870D01*
G01X19425Y934833D02*
X19758Y934625D01*
X20133Y934500D01*
X20467D01*
X20800Y934625D01*
X21050Y934833D01*
X21175Y935125D01*
X21092Y935417D01*
X20883Y935667D01*
X20508Y935833D01*
X20008Y935917D01*
X19717Y936083D01*
X19592Y936375D01*
X19675Y936667D01*
X19883Y936875D01*
X20175Y937000D01*
X20467D01*
X20758Y936917D01*
X21008Y936708D01*
G01X24317Y936792D02*
X24067Y936917D01*
X23775Y937000D01*
X23442D01*
X23067Y936875D01*
X22775Y936667D01*
X22567Y936417D01*
X22400Y936000D01*
X22358Y935625D01*
X22442Y935250D01*
X22567Y935000D01*
X22817Y934750D01*
X23108Y934583D01*
X23400Y934500D01*
X23692D01*
X23983Y934583D01*
X24233Y934708D01*
X24442Y934875D01*
G01X27000Y934500D02*
Y937000D01*
X25458Y935208D01*
X27542D01*
G01X28683Y935000D02*
X28933Y934708D01*
X29267Y934542D01*
X29642Y934500D01*
X29975Y934542D01*
X30308Y934750D01*
X30517Y935000D01*
X30558Y935250D01*
X30475Y935542D01*
X30183Y935750D01*
X29892Y935833D01*
X29517D01*
G01X29892D02*
X30142Y935958D01*
X30350Y936167D01*
X30433Y936417D01*
X30350Y936667D01*
X30142Y936875D01*
X29767Y937000D01*
X29392Y936958D01*
X29017Y936792D01*
G01X32700Y937000D02*
X32367Y936917D01*
X32117Y936708D01*
X31950Y936458D01*
X31825Y936125D01*
X31783Y935750D01*
X31825Y935375D01*
X31950Y935042D01*
X32117Y934792D01*
X32367Y934583D01*
X32700Y934500D01*
X33033Y934583D01*
X33283Y934792D01*
X33450Y935042D01*
X33575Y935375D01*
X33617Y935750D01*
X33575Y936125D01*
X33450Y936458D01*
X33283Y936708D01*
X33033Y936917D01*
X32700Y937000D01*
G01X43372Y438520D02*
X43122Y438645D01*
X42830Y438728D01*
X42497D01*
X42122Y438603D01*
X41830Y438395D01*
X41622Y438145D01*
X41455Y437728D01*
X41413Y437353D01*
X41497Y436978D01*
X41622Y436728D01*
X41872Y436478D01*
X42163Y436311D01*
X42455Y436228D01*
X42747D01*
X43038Y436311D01*
X43288Y436436D01*
X43497Y436603D01*
G01X44597Y436228D02*
Y438728D01*
X46513Y436228D01*
Y438728D01*
G01X49155Y436228D02*
Y438728D01*
X47613Y436936D01*
X49697D01*
G01X45722Y506425D02*
X45930Y506758D01*
X46055Y507133D01*
Y507467D01*
X45930Y507800D01*
X45722Y508050D01*
X45430Y508175D01*
X45138Y508092D01*
X44888Y507883D01*
X44722Y507508D01*
X44638Y507008D01*
X44472Y506717D01*
X44180Y506592D01*
X43888Y506675D01*
X43680Y506883D01*
X43555Y507175D01*
Y507467D01*
X43638Y507758D01*
X43847Y508008D01*
G01X46055Y509567D02*
X43555D01*
Y510608D01*
X43680Y510942D01*
X43847Y511150D01*
X44180Y511233D01*
X44513Y511150D01*
X44722Y510900D01*
X44847Y510608D01*
Y509567D01*
G01Y510608D02*
X46055Y511233D01*
G01X45763Y512792D02*
X45972Y513083D01*
X46055Y513417D01*
X45972Y513750D01*
X45722Y514042D01*
X45347Y514250D01*
X44972Y514333D01*
X44513D01*
X44138Y514250D01*
X43805Y514042D01*
X43638Y513792D01*
X43555Y513500D01*
X43638Y513167D01*
X43805Y512917D01*
X44055Y512750D01*
X44388Y512667D01*
X44680Y512750D01*
X44972Y512958D01*
X45138Y513208D01*
X45180Y513500D01*
X45097Y513833D01*
X44888Y514083D01*
X44513Y514333D01*
G01X43972Y515808D02*
X43722Y516058D01*
X43597Y516350D01*
X43555Y516683D01*
X43638Y517100D01*
X43847Y517392D01*
X44097Y517475D01*
X44347Y517433D01*
X44555Y517267D01*
X44972Y516433D01*
X45263Y516058D01*
X45680Y515808D01*
X46055Y515725D01*
Y517475D01*
G01X45555Y518783D02*
X45847Y519033D01*
X46013Y519367D01*
X46055Y519742D01*
X46013Y520075D01*
X45805Y520408D01*
X45555Y520617D01*
X45305Y520658D01*
X45013Y520575D01*
X44805Y520283D01*
X44722Y519992D01*
Y519617D01*
G01Y519992D02*
X44597Y520242D01*
X44388Y520450D01*
X44138Y520533D01*
X43888Y520450D01*
X43680Y520242D01*
X43555Y519867D01*
X43597Y519492D01*
X43763Y519117D01*
G01X50722Y506425D02*
X50930Y506758D01*
X51055Y507133D01*
Y507467D01*
X50930Y507800D01*
X50722Y508050D01*
X50430Y508175D01*
X50138Y508092D01*
X49888Y507883D01*
X49722Y507508D01*
X49638Y507008D01*
X49472Y506717D01*
X49180Y506592D01*
X48888Y506675D01*
X48680Y506883D01*
X48555Y507175D01*
Y507467D01*
X48638Y507758D01*
X48847Y508008D01*
G01X51055Y509567D02*
X48555D01*
Y510608D01*
X48680Y510942D01*
X48847Y511150D01*
X49180Y511233D01*
X49513Y511150D01*
X49722Y510900D01*
X49847Y510608D01*
Y509567D01*
G01Y510608D02*
X51055Y511233D01*
G01Y513500D02*
X51013Y513792D01*
X50888Y514125D01*
X50680Y514333D01*
X50388Y514417D01*
X50097Y514333D01*
X49847Y514083D01*
X49722Y513708D01*
Y513292D01*
X49638Y513042D01*
X49430Y512833D01*
X49138Y512750D01*
X48847Y512875D01*
X48638Y513167D01*
X48555Y513500D01*
X48638Y513833D01*
X48847Y514125D01*
X49138Y514250D01*
X49430Y514167D01*
X49638Y513958D01*
X49722Y513708D01*
Y513292D01*
X49847Y512917D01*
X50097Y512667D01*
X50388Y512583D01*
X50680Y512667D01*
X50888Y512875D01*
X51013Y513208D01*
X51055Y513500D01*
G01X50680Y515683D02*
X50888Y515933D01*
X51013Y516225D01*
X51055Y516600D01*
X50972Y516975D01*
X50805Y517267D01*
X50513Y517475D01*
X50180Y517517D01*
X49847Y517433D01*
X49638Y517225D01*
X49472Y516933D01*
X49430Y516642D01*
X49472Y516350D01*
X49638Y515975D01*
X48555Y516100D01*
Y517225D01*
G01X50763Y518992D02*
X50972Y519283D01*
X51055Y519617D01*
X50972Y519950D01*
X50722Y520242D01*
X50347Y520450D01*
X49972Y520533D01*
X49513D01*
X49138Y520450D01*
X48805Y520242D01*
X48638Y519992D01*
X48555Y519700D01*
X48638Y519367D01*
X48805Y519117D01*
X49055Y518950D01*
X49388Y518867D01*
X49680Y518950D01*
X49972Y519158D01*
X50138Y519408D01*
X50180Y519700D01*
X50097Y520033D01*
X49888Y520283D01*
X49513Y520533D01*
G01X40722Y506425D02*
X40930Y506758D01*
X41055Y507133D01*
Y507467D01*
X40930Y507800D01*
X40722Y508050D01*
X40430Y508175D01*
X40138Y508092D01*
X39888Y507883D01*
X39722Y507508D01*
X39638Y507008D01*
X39472Y506717D01*
X39180Y506592D01*
X38888Y506675D01*
X38680Y506883D01*
X38555Y507175D01*
Y507467D01*
X38638Y507758D01*
X38847Y508008D01*
G01X41055Y509567D02*
X38555D01*
Y510608D01*
X38680Y510942D01*
X38847Y511150D01*
X39180Y511233D01*
X39513Y511150D01*
X39722Y510900D01*
X39847Y510608D01*
Y509567D01*
G01Y510608D02*
X41055Y511233D01*
G01Y513500D02*
X41013Y513792D01*
X40888Y514125D01*
X40680Y514333D01*
X40388Y514417D01*
X40097Y514333D01*
X39847Y514083D01*
X39722Y513708D01*
Y513292D01*
X39638Y513042D01*
X39430Y512833D01*
X39138Y512750D01*
X38847Y512875D01*
X38638Y513167D01*
X38555Y513500D01*
X38638Y513833D01*
X38847Y514125D01*
X39138Y514250D01*
X39430Y514167D01*
X39638Y513958D01*
X39722Y513708D01*
Y513292D01*
X39847Y512917D01*
X40097Y512667D01*
X40388Y512583D01*
X40680Y512667D01*
X40888Y512875D01*
X41013Y513208D01*
X41055Y513500D01*
G01X38555Y516600D02*
X38638Y516267D01*
X38847Y516017D01*
X39097Y515850D01*
X39430Y515725D01*
X39805Y515683D01*
X40180Y515725D01*
X40513Y515850D01*
X40763Y516017D01*
X40972Y516267D01*
X41055Y516600D01*
X40972Y516933D01*
X40763Y517183D01*
X40513Y517350D01*
X40180Y517475D01*
X39805Y517517D01*
X39430Y517475D01*
X39097Y517350D01*
X38847Y517183D01*
X38638Y516933D01*
X38555Y516600D01*
G01X40680Y518783D02*
X40888Y519033D01*
X41013Y519325D01*
X41055Y519700D01*
X40972Y520075D01*
X40805Y520367D01*
X40513Y520575D01*
X40180Y520617D01*
X39847Y520533D01*
X39638Y520325D01*
X39472Y520033D01*
X39430Y519742D01*
X39472Y519450D01*
X39638Y519075D01*
X38555Y519200D01*
Y520325D01*
G01X49722Y525875D02*
X49930Y526208D01*
X50055Y526583D01*
Y526917D01*
X49930Y527250D01*
X49722Y527500D01*
X49430Y527625D01*
X49138Y527542D01*
X48888Y527333D01*
X48722Y526958D01*
X48638Y526458D01*
X48472Y526167D01*
X48180Y526042D01*
X47888Y526125D01*
X47680Y526333D01*
X47555Y526625D01*
Y526917D01*
X47638Y527208D01*
X47847Y527458D01*
G01X47555Y529850D02*
X50055D01*
G01X47555Y528892D02*
Y530808D01*
G01X50055Y532117D02*
X47555D01*
Y533117D01*
X47680Y533450D01*
X47972Y533700D01*
X48305Y533783D01*
X48638Y533700D01*
X48888Y533492D01*
X49013Y533117D01*
Y532117D01*
G01X50055Y536050D02*
X47555D01*
X48055Y535550D01*
G01X50055D02*
Y536550D01*
G01Y539650D02*
X47555D01*
X49347Y538108D01*
Y540192D01*
G01X49013Y541458D02*
X48722Y541750D01*
X48555Y542000D01*
X48472Y542333D01*
X48555Y542625D01*
X48722Y542833D01*
X48972Y543000D01*
X49263Y543042D01*
X49513Y543000D01*
X49763Y542833D01*
X49972Y542583D01*
X50055Y542292D01*
X49972Y541958D01*
X49722Y541667D01*
X49347Y541500D01*
X48930Y541458D01*
X48388Y541542D01*
X48097Y541667D01*
X47805Y541875D01*
X47597Y542167D01*
X47555Y542458D01*
X47638Y542750D01*
X47847Y542958D01*
G01X40722Y525925D02*
X40930Y526258D01*
X41055Y526633D01*
Y526967D01*
X40930Y527300D01*
X40722Y527550D01*
X40430Y527675D01*
X40138Y527592D01*
X39888Y527383D01*
X39722Y527008D01*
X39638Y526508D01*
X39472Y526217D01*
X39180Y526092D01*
X38888Y526175D01*
X38680Y526383D01*
X38555Y526675D01*
Y526967D01*
X38638Y527258D01*
X38847Y527508D01*
G01X38555Y529900D02*
X41055D01*
G01X38555Y528942D02*
Y530858D01*
G01X41055Y532167D02*
X38555D01*
Y533167D01*
X38680Y533500D01*
X38972Y533750D01*
X39305Y533833D01*
X39638Y533750D01*
X39888Y533542D01*
X40013Y533167D01*
Y532167D01*
G01X40763Y535392D02*
X40972Y535683D01*
X41055Y536017D01*
X40972Y536350D01*
X40722Y536642D01*
X40347Y536850D01*
X39972Y536933D01*
X39513D01*
X39138Y536850D01*
X38805Y536642D01*
X38638Y536392D01*
X38555Y536100D01*
X38638Y535767D01*
X38805Y535517D01*
X39055Y535350D01*
X39388Y535267D01*
X39680Y535350D01*
X39972Y535558D01*
X40138Y535808D01*
X40180Y536100D01*
X40097Y536433D01*
X39888Y536683D01*
X39513Y536933D01*
G01X41055Y539117D02*
X40513Y539200D01*
X40055Y539325D01*
X39638Y539492D01*
X39180Y539700D01*
X38555Y540033D01*
Y538367D01*
G01X45167Y525925D02*
X45375Y526258D01*
X45500Y526633D01*
Y526967D01*
X45375Y527300D01*
X45167Y527550D01*
X44875Y527675D01*
X44583Y527592D01*
X44333Y527383D01*
X44167Y527008D01*
X44083Y526508D01*
X43917Y526217D01*
X43625Y526092D01*
X43333Y526175D01*
X43125Y526383D01*
X43000Y526675D01*
Y526967D01*
X43083Y527258D01*
X43292Y527508D01*
G01X43000Y529900D02*
X45500D01*
G01X43000Y528942D02*
Y530858D01*
G01X45500Y532167D02*
X43000D01*
Y533167D01*
X43125Y533500D01*
X43417Y533750D01*
X43750Y533833D01*
X44083Y533750D01*
X44333Y533542D01*
X44458Y533167D01*
Y532167D01*
G01X45208Y535392D02*
X45417Y535683D01*
X45500Y536017D01*
X45417Y536350D01*
X45167Y536642D01*
X44792Y536850D01*
X44417Y536933D01*
X43958D01*
X43583Y536850D01*
X43250Y536642D01*
X43083Y536392D01*
X43000Y536100D01*
X43083Y535767D01*
X43250Y535517D01*
X43500Y535350D01*
X43833Y535267D01*
X44125Y535350D01*
X44417Y535558D01*
X44583Y535808D01*
X44625Y536100D01*
X44542Y536433D01*
X44333Y536683D01*
X43958Y536933D01*
G01X45500Y539200D02*
X45458Y539492D01*
X45333Y539825D01*
X45125Y540033D01*
X44833Y540117D01*
X44542Y540033D01*
X44292Y539783D01*
X44167Y539408D01*
Y538992D01*
X44083Y538742D01*
X43875Y538533D01*
X43583Y538450D01*
X43292Y538575D01*
X43083Y538867D01*
X43000Y539200D01*
X43083Y539533D01*
X43292Y539825D01*
X43583Y539950D01*
X43875Y539867D01*
X44083Y539658D01*
X44167Y539408D01*
Y538992D01*
X44292Y538617D01*
X44542Y538367D01*
X44833Y538283D01*
X45125Y538367D01*
X45333Y538575D01*
X45458Y538908D01*
X45500Y539200D01*
G01X51471Y745145D02*
X51679Y745478D01*
X51804Y745853D01*
Y746187D01*
X51679Y746520D01*
X51471Y746770D01*
X51179Y746895D01*
X50887Y746812D01*
X50637Y746603D01*
X50471Y746228D01*
X50387Y745728D01*
X50221Y745437D01*
X49929Y745312D01*
X49637Y745395D01*
X49429Y745603D01*
X49304Y745895D01*
Y746187D01*
X49387Y746478D01*
X49596Y746728D01*
G01X51804Y748287D02*
X49304D01*
Y749328D01*
X49429Y749662D01*
X49596Y749870D01*
X49929Y749953D01*
X50262Y749870D01*
X50471Y749620D01*
X50596Y749328D01*
Y748287D01*
G01Y749328D02*
X51804Y749953D01*
G01X49721Y751428D02*
X49471Y751678D01*
X49346Y751970D01*
X49304Y752303D01*
X49387Y752720D01*
X49596Y753012D01*
X49846Y753095D01*
X50096Y753053D01*
X50304Y752887D01*
X50721Y752053D01*
X51012Y751678D01*
X51429Y751428D01*
X51804Y751345D01*
Y753095D01*
G01Y755237D02*
X51262Y755320D01*
X50804Y755445D01*
X50387Y755612D01*
X49929Y755820D01*
X49304Y756153D01*
Y754487D01*
G01X51804Y758420D02*
X49304D01*
X49804Y757920D01*
G01X51804D02*
Y758920D01*
G01X44439Y787429D02*
X44647Y787762D01*
X44772Y788137D01*
Y788471D01*
X44647Y788804D01*
X44439Y789054D01*
X44147Y789179D01*
X43855Y789096D01*
X43605Y788887D01*
X43439Y788512D01*
X43355Y788012D01*
X43189Y787721D01*
X42897Y787596D01*
X42605Y787679D01*
X42397Y787887D01*
X42272Y788179D01*
Y788471D01*
X42355Y788762D01*
X42564Y789012D01*
G01X44772Y790571D02*
X42272D01*
Y791612D01*
X42397Y791946D01*
X42564Y792154D01*
X42897Y792237D01*
X43230Y792154D01*
X43439Y791904D01*
X43564Y791612D01*
Y790571D01*
G01Y791612D02*
X44772Y792237D01*
G01X44397Y793587D02*
X44605Y793837D01*
X44730Y794129D01*
X44772Y794504D01*
X44689Y794879D01*
X44522Y795171D01*
X44230Y795379D01*
X43897Y795421D01*
X43564Y795337D01*
X43355Y795129D01*
X43189Y794837D01*
X43147Y794546D01*
X43189Y794254D01*
X43355Y793879D01*
X42272Y794004D01*
Y795129D01*
G01X44772Y797521D02*
X44230Y797604D01*
X43772Y797729D01*
X43355Y797896D01*
X42897Y798104D01*
X42272Y798437D01*
Y796771D01*
G01X44772Y800704D02*
X44730Y800996D01*
X44605Y801329D01*
X44397Y801537D01*
X44105Y801621D01*
X43814Y801537D01*
X43564Y801287D01*
X43439Y800912D01*
Y800496D01*
X43355Y800246D01*
X43147Y800037D01*
X42855Y799954D01*
X42564Y800079D01*
X42355Y800371D01*
X42272Y800704D01*
X42355Y801037D01*
X42564Y801329D01*
X42855Y801454D01*
X43147Y801371D01*
X43355Y801162D01*
X43439Y800912D01*
Y800496D01*
X43564Y800121D01*
X43814Y799871D01*
X44105Y799787D01*
X44397Y799871D01*
X44605Y800079D01*
X44730Y800412D01*
X44772Y800704D01*
G01X39939Y787429D02*
X40147Y787762D01*
X40272Y788137D01*
Y788471D01*
X40147Y788804D01*
X39939Y789054D01*
X39647Y789179D01*
X39355Y789096D01*
X39105Y788887D01*
X38939Y788512D01*
X38855Y788012D01*
X38689Y787721D01*
X38397Y787596D01*
X38105Y787679D01*
X37897Y787887D01*
X37772Y788179D01*
Y788471D01*
X37855Y788762D01*
X38064Y789012D01*
G01X40272Y790571D02*
X37772D01*
Y791612D01*
X37897Y791946D01*
X38064Y792154D01*
X38397Y792237D01*
X38730Y792154D01*
X38939Y791904D01*
X39064Y791612D01*
Y790571D01*
G01Y791612D02*
X40272Y792237D01*
G01X39897Y793587D02*
X40105Y793837D01*
X40230Y794129D01*
X40272Y794504D01*
X40189Y794879D01*
X40022Y795171D01*
X39730Y795379D01*
X39397Y795421D01*
X39064Y795337D01*
X38855Y795129D01*
X38689Y794837D01*
X38647Y794546D01*
X38689Y794254D01*
X38855Y793879D01*
X37772Y794004D01*
Y795129D01*
G01X40272Y797521D02*
X39730Y797604D01*
X39272Y797729D01*
X38855Y797896D01*
X38397Y798104D01*
X37772Y798437D01*
Y796771D01*
G01X39980Y799996D02*
X40189Y800287D01*
X40272Y800621D01*
X40189Y800954D01*
X39939Y801246D01*
X39564Y801454D01*
X39189Y801537D01*
X38730D01*
X38355Y801454D01*
X38022Y801246D01*
X37855Y800996D01*
X37772Y800704D01*
X37855Y800371D01*
X38022Y800121D01*
X38272Y799954D01*
X38605Y799871D01*
X38897Y799954D01*
X39189Y800162D01*
X39355Y800412D01*
X39397Y800704D01*
X39314Y801037D01*
X39105Y801287D01*
X38730Y801537D01*
G01X48939Y787429D02*
X49147Y787762D01*
X49272Y788137D01*
Y788471D01*
X49147Y788804D01*
X48939Y789054D01*
X48647Y789179D01*
X48355Y789096D01*
X48105Y788887D01*
X47939Y788512D01*
X47855Y788012D01*
X47689Y787721D01*
X47397Y787596D01*
X47105Y787679D01*
X46897Y787887D01*
X46772Y788179D01*
Y788471D01*
X46855Y788762D01*
X47064Y789012D01*
G01X49272Y790571D02*
X46772D01*
Y791612D01*
X46897Y791946D01*
X47064Y792154D01*
X47397Y792237D01*
X47730Y792154D01*
X47939Y791904D01*
X48064Y791612D01*
Y790571D01*
G01Y791612D02*
X49272Y792237D01*
G01X48897Y793587D02*
X49105Y793837D01*
X49230Y794129D01*
X49272Y794504D01*
X49189Y794879D01*
X49022Y795171D01*
X48730Y795379D01*
X48397Y795421D01*
X48064Y795337D01*
X47855Y795129D01*
X47689Y794837D01*
X47647Y794546D01*
X47689Y794254D01*
X47855Y793879D01*
X46772Y794004D01*
Y795129D01*
G01X49272Y797604D02*
X49230Y797896D01*
X49105Y798229D01*
X48897Y798437D01*
X48605Y798521D01*
X48314Y798437D01*
X48064Y798187D01*
X47939Y797812D01*
Y797396D01*
X47855Y797146D01*
X47647Y796937D01*
X47355Y796854D01*
X47064Y796979D01*
X46855Y797271D01*
X46772Y797604D01*
X46855Y797937D01*
X47064Y798229D01*
X47355Y798354D01*
X47647Y798271D01*
X47855Y798062D01*
X47939Y797812D01*
Y797396D01*
X48064Y797021D01*
X48314Y796771D01*
X48605Y796687D01*
X48897Y796771D01*
X49105Y796979D01*
X49230Y797312D01*
X49272Y797604D01*
G01X46772Y800704D02*
X46855Y800371D01*
X47064Y800121D01*
X47314Y799954D01*
X47647Y799829D01*
X48022Y799787D01*
X48397Y799829D01*
X48730Y799954D01*
X48980Y800121D01*
X49189Y800371D01*
X49272Y800704D01*
X49189Y801037D01*
X48980Y801287D01*
X48730Y801454D01*
X48397Y801579D01*
X48022Y801621D01*
X47647Y801579D01*
X47314Y801454D01*
X47064Y801287D01*
X46855Y801037D01*
X46772Y800704D01*
G01X52971Y787145D02*
X53179Y787478D01*
X53304Y787853D01*
Y788187D01*
X53179Y788520D01*
X52971Y788770D01*
X52679Y788895D01*
X52387Y788812D01*
X52137Y788603D01*
X51971Y788228D01*
X51887Y787728D01*
X51721Y787437D01*
X51429Y787312D01*
X51137Y787395D01*
X50929Y787603D01*
X50804Y787895D01*
Y788187D01*
X50887Y788478D01*
X51096Y788728D01*
G01X51012Y792037D02*
X50887Y791787D01*
X50804Y791495D01*
Y791162D01*
X50929Y790787D01*
X51137Y790495D01*
X51387Y790287D01*
X51804Y790120D01*
X52179Y790078D01*
X52554Y790162D01*
X52804Y790287D01*
X53054Y790537D01*
X53221Y790828D01*
X53304Y791120D01*
Y791412D01*
X53221Y791703D01*
X53096Y791953D01*
X52929Y792162D01*
G01X53304Y794220D02*
X53262Y794512D01*
X53137Y794845D01*
X52929Y795053D01*
X52637Y795137D01*
X52346Y795053D01*
X52096Y794803D01*
X51971Y794428D01*
Y794012D01*
X51887Y793762D01*
X51679Y793553D01*
X51387Y793470D01*
X51096Y793595D01*
X50887Y793887D01*
X50804Y794220D01*
X50887Y794553D01*
X51096Y794845D01*
X51387Y794970D01*
X51679Y794887D01*
X51887Y794678D01*
X51971Y794428D01*
Y794012D01*
X52096Y793637D01*
X52346Y793387D01*
X52637Y793303D01*
X52929Y793387D01*
X53137Y793595D01*
X53262Y793928D01*
X53304Y794220D01*
G01X52262Y796528D02*
X51971Y796820D01*
X51804Y797070D01*
X51721Y797403D01*
X51804Y797695D01*
X51971Y797903D01*
X52221Y798070D01*
X52512Y798112D01*
X52762Y798070D01*
X53012Y797903D01*
X53221Y797653D01*
X53304Y797362D01*
X53221Y797028D01*
X52971Y796737D01*
X52596Y796570D01*
X52179Y796528D01*
X51637Y796612D01*
X51346Y796737D01*
X51054Y796945D01*
X50846Y797237D01*
X50804Y797528D01*
X50887Y797820D01*
X51096Y798028D01*
G01X53304Y800337D02*
X52762Y800420D01*
X52304Y800545D01*
X51887Y800712D01*
X51429Y800920D01*
X50804Y801253D01*
Y799587D01*
G01X42975Y806333D02*
X43308Y806125D01*
X43683Y806000D01*
X44017D01*
X44350Y806125D01*
X44600Y806333D01*
X44725Y806625D01*
X44642Y806917D01*
X44433Y807167D01*
X44058Y807333D01*
X43558Y807417D01*
X43267Y807583D01*
X43142Y807875D01*
X43225Y808167D01*
X43433Y808375D01*
X43725Y808500D01*
X44017D01*
X44308Y808417D01*
X44558Y808208D01*
G01X46033Y808500D02*
Y806708D01*
X46200Y806333D01*
X46533Y806083D01*
X46950Y806000D01*
X47367Y806083D01*
X47700Y806333D01*
X47867Y806708D01*
Y808500D01*
G01X49133Y806375D02*
X49383Y806167D01*
X49675Y806042D01*
X50050Y806000D01*
X50425Y806083D01*
X50717Y806250D01*
X50925Y806542D01*
X50967Y806875D01*
X50883Y807208D01*
X50675Y807417D01*
X50383Y807583D01*
X50092Y807625D01*
X49800Y807583D01*
X49425Y807417D01*
X49550Y808500D01*
X50675D01*
G01X52358Y808083D02*
X52608Y808333D01*
X52900Y808458D01*
X53233Y808500D01*
X53650Y808417D01*
X53942Y808208D01*
X54025Y807958D01*
X53983Y807708D01*
X53817Y807500D01*
X52983Y807083D01*
X52608Y806792D01*
X52358Y806375D01*
X52275Y806000D01*
X54025D01*
G01X45471Y811145D02*
X45679Y811478D01*
X45804Y811853D01*
Y812187D01*
X45679Y812520D01*
X45471Y812770D01*
X45179Y812895D01*
X44887Y812812D01*
X44637Y812603D01*
X44471Y812228D01*
X44387Y811728D01*
X44221Y811437D01*
X43929Y811312D01*
X43637Y811395D01*
X43429Y811603D01*
X43304Y811895D01*
Y812187D01*
X43387Y812478D01*
X43596Y812728D01*
G01X45804Y814287D02*
X43304D01*
Y815328D01*
X43429Y815662D01*
X43596Y815870D01*
X43929Y815953D01*
X44262Y815870D01*
X44471Y815620D01*
X44596Y815328D01*
Y814287D01*
G01Y815328D02*
X45804Y815953D01*
G01X45429Y817303D02*
X45637Y817553D01*
X45762Y817845D01*
X45804Y818220D01*
X45721Y818595D01*
X45554Y818887D01*
X45262Y819095D01*
X44929Y819137D01*
X44596Y819053D01*
X44387Y818845D01*
X44221Y818553D01*
X44179Y818262D01*
X44221Y817970D01*
X44387Y817595D01*
X43304Y817720D01*
Y818845D01*
G01X45804Y821320D02*
X45762Y821612D01*
X45637Y821945D01*
X45429Y822153D01*
X45137Y822237D01*
X44846Y822153D01*
X44596Y821903D01*
X44471Y821528D01*
Y821112D01*
X44387Y820862D01*
X44179Y820653D01*
X43887Y820570D01*
X43596Y820695D01*
X43387Y820987D01*
X43304Y821320D01*
X43387Y821653D01*
X43596Y821945D01*
X43887Y822070D01*
X44179Y821987D01*
X44387Y821778D01*
X44471Y821528D01*
Y821112D01*
X44596Y820737D01*
X44846Y820487D01*
X45137Y820403D01*
X45429Y820487D01*
X45637Y820695D01*
X45762Y821028D01*
X45804Y821320D01*
G01X45512Y823712D02*
X45721Y824003D01*
X45804Y824337D01*
X45721Y824670D01*
X45471Y824962D01*
X45096Y825170D01*
X44721Y825253D01*
X44262D01*
X43887Y825170D01*
X43554Y824962D01*
X43387Y824712D01*
X43304Y824420D01*
X43387Y824087D01*
X43554Y823837D01*
X43804Y823670D01*
X44137Y823587D01*
X44429Y823670D01*
X44721Y823878D01*
X44887Y824128D01*
X44929Y824420D01*
X44846Y824753D01*
X44637Y825003D01*
X44262Y825253D01*
G01X49971Y811145D02*
X50179Y811478D01*
X50304Y811853D01*
Y812187D01*
X50179Y812520D01*
X49971Y812770D01*
X49679Y812895D01*
X49387Y812812D01*
X49137Y812603D01*
X48971Y812228D01*
X48887Y811728D01*
X48721Y811437D01*
X48429Y811312D01*
X48137Y811395D01*
X47929Y811603D01*
X47804Y811895D01*
Y812187D01*
X47887Y812478D01*
X48096Y812728D01*
G01X50304Y814287D02*
X47804D01*
Y815328D01*
X47929Y815662D01*
X48096Y815870D01*
X48429Y815953D01*
X48762Y815870D01*
X48971Y815620D01*
X49096Y815328D01*
Y814287D01*
G01Y815328D02*
X50304Y815953D01*
G01X49929Y817303D02*
X50137Y817553D01*
X50262Y817845D01*
X50304Y818220D01*
X50221Y818595D01*
X50054Y818887D01*
X49762Y819095D01*
X49429Y819137D01*
X49096Y819053D01*
X48887Y818845D01*
X48721Y818553D01*
X48679Y818262D01*
X48721Y817970D01*
X48887Y817595D01*
X47804Y817720D01*
Y818845D01*
G01X50012Y820612D02*
X50221Y820903D01*
X50304Y821237D01*
X50221Y821570D01*
X49971Y821862D01*
X49596Y822070D01*
X49221Y822153D01*
X48762D01*
X48387Y822070D01*
X48054Y821862D01*
X47887Y821612D01*
X47804Y821320D01*
X47887Y820987D01*
X48054Y820737D01*
X48304Y820570D01*
X48637Y820487D01*
X48929Y820570D01*
X49221Y820778D01*
X49387Y821028D01*
X49429Y821320D01*
X49346Y821653D01*
X49137Y821903D01*
X48762Y822153D01*
G01X47804Y824420D02*
X47887Y824087D01*
X48096Y823837D01*
X48346Y823670D01*
X48679Y823545D01*
X49054Y823503D01*
X49429Y823545D01*
X49762Y823670D01*
X50012Y823837D01*
X50221Y824087D01*
X50304Y824420D01*
X50221Y824753D01*
X50012Y825003D01*
X49762Y825170D01*
X49429Y825295D01*
X49054Y825337D01*
X48679Y825295D01*
X48346Y825170D01*
X48096Y825003D01*
X47887Y824753D01*
X47804Y824420D01*
G01X50804Y826720D02*
Y839720D01*
G01X36804Y826720D02*
X50804D01*
G01X36804Y839720D02*
Y826720D01*
G01X43504Y852220D02*
Y842220D01*
G01X50804Y839720D02*
X36804D01*
G01X46104Y844720D02*
Y840720D01*
X53504D01*
G01X36804Y888520D02*
X40804D01*
Y895920D01*
G01X41320Y909988D02*
Y913388D01*
G01Y909988D02*
Y905488D01*
G01X43020Y911688D02*
X41320Y909988D01*
G01X73120Y905488D02*
X41320D01*
G01X36804Y896520D02*
X40804D01*
Y903920D01*
G01X41320Y913388D02*
X43020Y911688D01*
G01X41320Y917888D02*
X73120D01*
G01X41320Y913388D02*
Y917888D01*
G01X38804Y915237D02*
X36304D01*
Y916278D01*
X36429Y916612D01*
X36596Y916820D01*
X36929Y916903D01*
X37262Y916820D01*
X37471Y916570D01*
X37596Y916278D01*
Y915237D01*
G01Y916278D02*
X38804Y916903D01*
G01X38429Y918253D02*
X38637Y918503D01*
X38762Y918795D01*
X38804Y919170D01*
X38721Y919545D01*
X38554Y919837D01*
X38262Y920045D01*
X37929Y920087D01*
X37596Y920003D01*
X37387Y919795D01*
X37221Y919503D01*
X37179Y919212D01*
X37221Y918920D01*
X37387Y918545D01*
X36304Y918670D01*
Y919795D01*
G01X38804Y922270D02*
X36304D01*
X36804Y921770D01*
G01X38804D02*
Y922770D01*
G01X38512Y924662D02*
X38721Y924953D01*
X38804Y925287D01*
X38721Y925620D01*
X38471Y925912D01*
X38096Y926120D01*
X37721Y926203D01*
X37262D01*
X36887Y926120D01*
X36554Y925912D01*
X36387Y925662D01*
X36304Y925370D01*
X36387Y925037D01*
X36554Y924787D01*
X36804Y924620D01*
X37137Y924537D01*
X37429Y924620D01*
X37721Y924828D01*
X37887Y925078D01*
X37929Y925370D01*
X37846Y925703D01*
X37637Y925953D01*
X37262Y926203D01*
G01X48571Y940845D02*
X48779Y941178D01*
X48904Y941553D01*
Y941887D01*
X48779Y942220D01*
X48571Y942470D01*
X48279Y942595D01*
X47987Y942512D01*
X47737Y942303D01*
X47571Y941928D01*
X47487Y941428D01*
X47321Y941137D01*
X47029Y941012D01*
X46737Y941095D01*
X46529Y941303D01*
X46404Y941595D01*
Y941887D01*
X46487Y942178D01*
X46696Y942428D01*
G01X48904Y943987D02*
X46404D01*
Y945028D01*
X46529Y945362D01*
X46696Y945570D01*
X47029Y945653D01*
X47362Y945570D01*
X47571Y945320D01*
X47696Y945028D01*
Y943987D01*
G01Y945028D02*
X48904Y945653D01*
G01X46821Y947128D02*
X46571Y947378D01*
X46446Y947670D01*
X46404Y948003D01*
X46487Y948420D01*
X46696Y948712D01*
X46946Y948795D01*
X47196Y948753D01*
X47404Y948587D01*
X47821Y947753D01*
X48112Y947378D01*
X48529Y947128D01*
X48904Y947045D01*
Y948795D01*
G01X47862Y950228D02*
X47571Y950520D01*
X47404Y950770D01*
X47321Y951103D01*
X47404Y951395D01*
X47571Y951603D01*
X47821Y951770D01*
X48112Y951812D01*
X48362Y951770D01*
X48612Y951603D01*
X48821Y951353D01*
X48904Y951062D01*
X48821Y950728D01*
X48571Y950437D01*
X48196Y950270D01*
X47779Y950228D01*
X47237Y950312D01*
X46946Y950437D01*
X46654Y950645D01*
X46446Y950937D01*
X46404Y951228D01*
X46487Y951520D01*
X46696Y951728D01*
G01X46821Y953328D02*
X46571Y953578D01*
X46446Y953870D01*
X46404Y954203D01*
X46487Y954620D01*
X46696Y954912D01*
X46946Y954995D01*
X47196Y954953D01*
X47404Y954787D01*
X47821Y953953D01*
X48112Y953578D01*
X48529Y953328D01*
X48904Y953245D01*
Y954995D01*
G01X45804Y930520D02*
X49804D01*
Y937920D01*
G01X44571Y940845D02*
X44779Y941178D01*
X44904Y941553D01*
Y941887D01*
X44779Y942220D01*
X44571Y942470D01*
X44279Y942595D01*
X43987Y942512D01*
X43737Y942303D01*
X43571Y941928D01*
X43487Y941428D01*
X43321Y941137D01*
X43029Y941012D01*
X42737Y941095D01*
X42529Y941303D01*
X42404Y941595D01*
Y941887D01*
X42487Y942178D01*
X42696Y942428D01*
G01X42612Y945737D02*
X42487Y945487D01*
X42404Y945195D01*
Y944862D01*
X42529Y944487D01*
X42737Y944195D01*
X42987Y943987D01*
X43404Y943820D01*
X43779Y943778D01*
X44154Y943862D01*
X44404Y943987D01*
X44654Y944237D01*
X44821Y944528D01*
X44904Y944820D01*
Y945112D01*
X44821Y945403D01*
X44696Y945653D01*
X44529Y945862D01*
G01X44904Y948420D02*
X42404D01*
X44196Y946878D01*
Y948962D01*
G01X44404Y950103D02*
X44696Y950353D01*
X44862Y950687D01*
X44904Y951062D01*
X44862Y951395D01*
X44654Y951728D01*
X44404Y951937D01*
X44154Y951978D01*
X43862Y951895D01*
X43654Y951603D01*
X43571Y951312D01*
Y950937D01*
G01Y951312D02*
X43446Y951562D01*
X43237Y951770D01*
X42987Y951853D01*
X42737Y951770D01*
X42529Y951562D01*
X42404Y951187D01*
X42446Y950812D01*
X42612Y950437D01*
G01X44904Y954120D02*
X42404D01*
X42904Y953620D01*
G01X44904D02*
Y954620D01*
G01X56829Y438674D02*
X56579Y438799D01*
X56287Y438882D01*
X55954D01*
X55579Y438757D01*
X55287Y438549D01*
X55079Y438299D01*
X54912Y437882D01*
X54870Y437507D01*
X54954Y437132D01*
X55079Y436882D01*
X55329Y436632D01*
X55620Y436465D01*
X55912Y436382D01*
X56204D01*
X56495Y436465D01*
X56745Y436590D01*
X56954Y436757D01*
G01X58054Y436382D02*
Y438882D01*
X59970Y436382D01*
Y438882D01*
G01X62112Y436382D02*
Y438882D01*
X61612Y438382D01*
G01Y436382D02*
X62612D01*
G01X66272Y481700D02*
Y484200D01*
X67313D01*
X67647Y484075D01*
X67855Y483908D01*
X67938Y483575D01*
X67855Y483242D01*
X67605Y483033D01*
X67313Y482908D01*
X66272D01*
G01X67313D02*
X67938Y481700D01*
G01X69288Y482075D02*
X69538Y481867D01*
X69830Y481742D01*
X70205Y481700D01*
X70580Y481783D01*
X70872Y481950D01*
X71080Y482242D01*
X71122Y482575D01*
X71038Y482908D01*
X70830Y483117D01*
X70538Y483283D01*
X70247Y483325D01*
X69955Y483283D01*
X69580Y483117D01*
X69705Y484200D01*
X70830D01*
G01X73305Y481700D02*
X73597Y481742D01*
X73930Y481867D01*
X74138Y482075D01*
X74222Y482367D01*
X74138Y482658D01*
X73888Y482908D01*
X73513Y483033D01*
X73097D01*
X72847Y483117D01*
X72638Y483325D01*
X72555Y483617D01*
X72680Y483908D01*
X72972Y484117D01*
X73305Y484200D01*
X73638Y484117D01*
X73930Y483908D01*
X74055Y483617D01*
X73972Y483325D01*
X73763Y483117D01*
X73513Y483033D01*
X73097D01*
X72722Y482908D01*
X72472Y482658D01*
X72388Y482367D01*
X72472Y482075D01*
X72680Y481867D01*
X73013Y481742D01*
X73305Y481700D01*
G01X75488Y482075D02*
X75738Y481867D01*
X76030Y481742D01*
X76405Y481700D01*
X76780Y481783D01*
X77072Y481950D01*
X77280Y482242D01*
X77322Y482575D01*
X77238Y482908D01*
X77030Y483117D01*
X76738Y483283D01*
X76447Y483325D01*
X76155Y483283D01*
X75780Y483117D01*
X75905Y484200D01*
X77030D01*
G01X66272Y493700D02*
Y496200D01*
X67313D01*
X67647Y496075D01*
X67855Y495908D01*
X67938Y495575D01*
X67855Y495242D01*
X67605Y495033D01*
X67313Y494908D01*
X66272D01*
G01X67313D02*
X67938Y493700D01*
G01X70205D02*
Y496200D01*
X69705Y495700D01*
G01Y493700D02*
X70705D01*
G01X73222D02*
X73305Y494242D01*
X73430Y494700D01*
X73597Y495117D01*
X73805Y495575D01*
X74138Y496200D01*
X72472D01*
G01X76322Y493700D02*
X76405Y494242D01*
X76530Y494700D01*
X76697Y495117D01*
X76905Y495575D01*
X77238Y496200D01*
X75572D01*
G01X66272Y489700D02*
Y492200D01*
X67313D01*
X67647Y492075D01*
X67855Y491908D01*
X67938Y491575D01*
X67855Y491242D01*
X67605Y491033D01*
X67313Y490908D01*
X66272D01*
G01X67313D02*
X67938Y489700D01*
G01X69288Y490075D02*
X69538Y489867D01*
X69830Y489742D01*
X70205Y489700D01*
X70580Y489783D01*
X70872Y489950D01*
X71080Y490242D01*
X71122Y490575D01*
X71038Y490908D01*
X70830Y491117D01*
X70538Y491283D01*
X70247Y491325D01*
X69955Y491283D01*
X69580Y491117D01*
X69705Y492200D01*
X70830D01*
G01X73305Y489700D02*
X73597Y489742D01*
X73930Y489867D01*
X74138Y490075D01*
X74222Y490367D01*
X74138Y490658D01*
X73888Y490908D01*
X73513Y491033D01*
X73097D01*
X72847Y491117D01*
X72638Y491325D01*
X72555Y491617D01*
X72680Y491908D01*
X72972Y492117D01*
X73305Y492200D01*
X73638Y492117D01*
X73930Y491908D01*
X74055Y491617D01*
X73972Y491325D01*
X73763Y491117D01*
X73513Y491033D01*
X73097D01*
X72722Y490908D01*
X72472Y490658D01*
X72388Y490367D01*
X72472Y490075D01*
X72680Y489867D01*
X73013Y489742D01*
X73305Y489700D01*
G01X75613Y490742D02*
X75905Y491033D01*
X76155Y491200D01*
X76488Y491283D01*
X76780Y491200D01*
X76988Y491033D01*
X77155Y490783D01*
X77197Y490492D01*
X77155Y490242D01*
X76988Y489992D01*
X76738Y489783D01*
X76447Y489700D01*
X76113Y489783D01*
X75822Y490033D01*
X75655Y490408D01*
X75613Y490825D01*
X75697Y491367D01*
X75822Y491658D01*
X76030Y491950D01*
X76322Y492158D01*
X76613Y492200D01*
X76905Y492117D01*
X77113Y491908D01*
G01X66272Y485700D02*
Y488200D01*
X67313D01*
X67647Y488075D01*
X67855Y487908D01*
X67938Y487575D01*
X67855Y487242D01*
X67605Y487033D01*
X67313Y486908D01*
X66272D01*
G01X67313D02*
X67938Y485700D01*
G01X69288Y486075D02*
X69538Y485867D01*
X69830Y485742D01*
X70205Y485700D01*
X70580Y485783D01*
X70872Y485950D01*
X71080Y486242D01*
X71122Y486575D01*
X71038Y486908D01*
X70830Y487117D01*
X70538Y487283D01*
X70247Y487325D01*
X69955Y487283D01*
X69580Y487117D01*
X69705Y488200D01*
X70830D01*
G01X72597Y485992D02*
X72888Y485783D01*
X73222Y485700D01*
X73555Y485783D01*
X73847Y486033D01*
X74055Y486408D01*
X74138Y486783D01*
Y487242D01*
X74055Y487617D01*
X73847Y487950D01*
X73597Y488117D01*
X73305Y488200D01*
X72972Y488117D01*
X72722Y487950D01*
X72555Y487700D01*
X72472Y487367D01*
X72555Y487075D01*
X72763Y486783D01*
X73013Y486617D01*
X73305Y486575D01*
X73638Y486658D01*
X73888Y486867D01*
X74138Y487242D01*
G01X75613Y487783D02*
X75863Y488033D01*
X76155Y488158D01*
X76488Y488200D01*
X76905Y488117D01*
X77197Y487908D01*
X77280Y487658D01*
X77238Y487408D01*
X77072Y487200D01*
X76238Y486783D01*
X75863Y486492D01*
X75613Y486075D01*
X75530Y485700D01*
X77280D01*
G01X68055Y501017D02*
X65555D01*
Y502058D01*
X65680Y502392D01*
X65847Y502600D01*
X66180Y502683D01*
X66513Y502600D01*
X66722Y502350D01*
X66847Y502058D01*
Y501017D01*
G01Y502058D02*
X68055Y502683D01*
G01Y504950D02*
X65555D01*
X66055Y504450D01*
G01X68055D02*
Y505450D01*
G01Y507967D02*
X67513Y508050D01*
X67055Y508175D01*
X66638Y508342D01*
X66180Y508550D01*
X65555Y508883D01*
Y507217D01*
G01X68055Y511150D02*
X68013Y511442D01*
X67888Y511775D01*
X67680Y511983D01*
X67388Y512067D01*
X67097Y511983D01*
X66847Y511733D01*
X66722Y511358D01*
Y510942D01*
X66638Y510692D01*
X66430Y510483D01*
X66138Y510400D01*
X65847Y510525D01*
X65638Y510817D01*
X65555Y511150D01*
X65638Y511483D01*
X65847Y511775D01*
X66138Y511900D01*
X66430Y511817D01*
X66638Y511608D01*
X66722Y511358D01*
Y510942D01*
X66847Y510567D01*
X67097Y510317D01*
X67388Y510233D01*
X67680Y510317D01*
X67888Y510525D01*
X68013Y510858D01*
X68055Y511150D01*
G01X54722Y506425D02*
X54930Y506758D01*
X55055Y507133D01*
Y507467D01*
X54930Y507800D01*
X54722Y508050D01*
X54430Y508175D01*
X54138Y508092D01*
X53888Y507883D01*
X53722Y507508D01*
X53638Y507008D01*
X53472Y506717D01*
X53180Y506592D01*
X52888Y506675D01*
X52680Y506883D01*
X52555Y507175D01*
Y507467D01*
X52638Y507758D01*
X52847Y508008D01*
G01X55055Y509567D02*
X52555D01*
Y510608D01*
X52680Y510942D01*
X52847Y511150D01*
X53180Y511233D01*
X53513Y511150D01*
X53722Y510900D01*
X53847Y510608D01*
Y509567D01*
G01Y510608D02*
X55055Y511233D01*
G01Y513500D02*
X55013Y513792D01*
X54888Y514125D01*
X54680Y514333D01*
X54388Y514417D01*
X54097Y514333D01*
X53847Y514083D01*
X53722Y513708D01*
Y513292D01*
X53638Y513042D01*
X53430Y512833D01*
X53138Y512750D01*
X52847Y512875D01*
X52638Y513167D01*
X52555Y513500D01*
X52638Y513833D01*
X52847Y514125D01*
X53138Y514250D01*
X53430Y514167D01*
X53638Y513958D01*
X53722Y513708D01*
Y513292D01*
X53847Y512917D01*
X54097Y512667D01*
X54388Y512583D01*
X54680Y512667D01*
X54888Y512875D01*
X55013Y513208D01*
X55055Y513500D01*
G01X54013Y515808D02*
X53722Y516100D01*
X53555Y516350D01*
X53472Y516683D01*
X53555Y516975D01*
X53722Y517183D01*
X53972Y517350D01*
X54263Y517392D01*
X54513Y517350D01*
X54763Y517183D01*
X54972Y516933D01*
X55055Y516642D01*
X54972Y516308D01*
X54722Y516017D01*
X54347Y515850D01*
X53930Y515808D01*
X53388Y515892D01*
X53097Y516017D01*
X52805Y516225D01*
X52597Y516517D01*
X52555Y516808D01*
X52638Y517100D01*
X52847Y517308D01*
G01X55055Y519700D02*
X52555D01*
X53055Y519200D01*
G01X55055D02*
Y520200D01*
G01X63722Y506425D02*
X63930Y506758D01*
X64055Y507133D01*
Y507467D01*
X63930Y507800D01*
X63722Y508050D01*
X63430Y508175D01*
X63138Y508092D01*
X62888Y507883D01*
X62722Y507508D01*
X62638Y507008D01*
X62472Y506717D01*
X62180Y506592D01*
X61888Y506675D01*
X61680Y506883D01*
X61555Y507175D01*
Y507467D01*
X61638Y507758D01*
X61847Y508008D01*
G01X64055Y509567D02*
X61555D01*
Y510608D01*
X61680Y510942D01*
X61847Y511150D01*
X62180Y511233D01*
X62513Y511150D01*
X62722Y510900D01*
X62847Y510608D01*
Y509567D01*
G01Y510608D02*
X64055Y511233D01*
G01Y513500D02*
X64013Y513792D01*
X63888Y514125D01*
X63680Y514333D01*
X63388Y514417D01*
X63097Y514333D01*
X62847Y514083D01*
X62722Y513708D01*
Y513292D01*
X62638Y513042D01*
X62430Y512833D01*
X62138Y512750D01*
X61847Y512875D01*
X61638Y513167D01*
X61555Y513500D01*
X61638Y513833D01*
X61847Y514125D01*
X62138Y514250D01*
X62430Y514167D01*
X62638Y513958D01*
X62722Y513708D01*
Y513292D01*
X62847Y512917D01*
X63097Y512667D01*
X63388Y512583D01*
X63680Y512667D01*
X63888Y512875D01*
X64013Y513208D01*
X64055Y513500D01*
G01X63013Y515808D02*
X62722Y516100D01*
X62555Y516350D01*
X62472Y516683D01*
X62555Y516975D01*
X62722Y517183D01*
X62972Y517350D01*
X63263Y517392D01*
X63513Y517350D01*
X63763Y517183D01*
X63972Y516933D01*
X64055Y516642D01*
X63972Y516308D01*
X63722Y516017D01*
X63347Y515850D01*
X62930Y515808D01*
X62388Y515892D01*
X62097Y516017D01*
X61805Y516225D01*
X61597Y516517D01*
X61555Y516808D01*
X61638Y517100D01*
X61847Y517308D01*
G01X64055Y519617D02*
X63513Y519700D01*
X63055Y519825D01*
X62638Y519992D01*
X62180Y520200D01*
X61555Y520533D01*
Y518867D01*
G01X59222Y506425D02*
X59430Y506758D01*
X59555Y507133D01*
Y507467D01*
X59430Y507800D01*
X59222Y508050D01*
X58930Y508175D01*
X58638Y508092D01*
X58388Y507883D01*
X58222Y507508D01*
X58138Y507008D01*
X57972Y506717D01*
X57680Y506592D01*
X57388Y506675D01*
X57180Y506883D01*
X57055Y507175D01*
Y507467D01*
X57138Y507758D01*
X57347Y508008D01*
G01X59555Y509567D02*
X57055D01*
Y510608D01*
X57180Y510942D01*
X57347Y511150D01*
X57680Y511233D01*
X58013Y511150D01*
X58222Y510900D01*
X58347Y510608D01*
Y509567D01*
G01Y510608D02*
X59555Y511233D01*
G01Y513500D02*
X59513Y513792D01*
X59388Y514125D01*
X59180Y514333D01*
X58888Y514417D01*
X58597Y514333D01*
X58347Y514083D01*
X58222Y513708D01*
Y513292D01*
X58138Y513042D01*
X57930Y512833D01*
X57638Y512750D01*
X57347Y512875D01*
X57138Y513167D01*
X57055Y513500D01*
X57138Y513833D01*
X57347Y514125D01*
X57638Y514250D01*
X57930Y514167D01*
X58138Y513958D01*
X58222Y513708D01*
Y513292D01*
X58347Y512917D01*
X58597Y512667D01*
X58888Y512583D01*
X59180Y512667D01*
X59388Y512875D01*
X59513Y513208D01*
X59555Y513500D01*
G01X57055Y516600D02*
X57138Y516267D01*
X57347Y516017D01*
X57597Y515850D01*
X57930Y515725D01*
X58305Y515683D01*
X58680Y515725D01*
X59013Y515850D01*
X59263Y516017D01*
X59472Y516267D01*
X59555Y516600D01*
X59472Y516933D01*
X59263Y517183D01*
X59013Y517350D01*
X58680Y517475D01*
X58305Y517517D01*
X57930Y517475D01*
X57597Y517350D01*
X57347Y517183D01*
X57138Y516933D01*
X57055Y516600D01*
G01X59055Y518783D02*
X59347Y519033D01*
X59513Y519367D01*
X59555Y519742D01*
X59513Y520075D01*
X59305Y520408D01*
X59055Y520617D01*
X58805Y520658D01*
X58513Y520575D01*
X58305Y520283D01*
X58222Y519992D01*
Y519617D01*
G01Y519992D02*
X58097Y520242D01*
X57888Y520450D01*
X57638Y520533D01*
X57388Y520450D01*
X57180Y520242D01*
X57055Y519867D01*
X57097Y519492D01*
X57263Y519117D01*
G01X54222Y522875D02*
X54430Y523208D01*
X54555Y523583D01*
Y523917D01*
X54430Y524250D01*
X54222Y524500D01*
X53930Y524625D01*
X53638Y524542D01*
X53388Y524333D01*
X53222Y523958D01*
X53138Y523458D01*
X52972Y523167D01*
X52680Y523042D01*
X52388Y523125D01*
X52180Y523333D01*
X52055Y523625D01*
Y523917D01*
X52138Y524208D01*
X52347Y524458D01*
G01X52055Y526850D02*
X54555D01*
G01X52055Y525892D02*
Y527808D01*
G01X54555Y529117D02*
X52055D01*
Y530117D01*
X52180Y530450D01*
X52472Y530700D01*
X52805Y530783D01*
X53138Y530700D01*
X53388Y530492D01*
X53513Y530117D01*
Y529117D01*
G01X54555Y533050D02*
X52055D01*
X52555Y532550D01*
G01X54555D02*
Y533550D01*
G01Y536650D02*
X52055D01*
X53847Y535108D01*
Y537192D01*
G01X54263Y538542D02*
X54472Y538833D01*
X54555Y539167D01*
X54472Y539500D01*
X54222Y539792D01*
X53847Y540000D01*
X53472Y540083D01*
X53013D01*
X52638Y540000D01*
X52305Y539792D01*
X52138Y539542D01*
X52055Y539250D01*
X52138Y538917D01*
X52305Y538667D01*
X52555Y538500D01*
X52888Y538417D01*
X53180Y538500D01*
X53472Y538708D01*
X53638Y538958D01*
X53680Y539250D01*
X53597Y539583D01*
X53388Y539833D01*
X53013Y540083D01*
G01X62222Y522875D02*
X62430Y523208D01*
X62555Y523583D01*
Y523917D01*
X62430Y524250D01*
X62222Y524500D01*
X61930Y524625D01*
X61638Y524542D01*
X61388Y524333D01*
X61222Y523958D01*
X61138Y523458D01*
X60972Y523167D01*
X60680Y523042D01*
X60388Y523125D01*
X60180Y523333D01*
X60055Y523625D01*
Y523917D01*
X60138Y524208D01*
X60347Y524458D01*
G01X60055Y526850D02*
X62555D01*
G01X60055Y525892D02*
Y527808D01*
G01X62555Y529117D02*
X60055D01*
Y530117D01*
X60180Y530450D01*
X60472Y530700D01*
X60805Y530783D01*
X61138Y530700D01*
X61388Y530492D01*
X61513Y530117D01*
Y529117D01*
G01X62555Y533050D02*
X60055D01*
X60555Y532550D01*
G01X62555D02*
Y533550D01*
G01Y536650D02*
X60055D01*
X61847Y535108D01*
Y537192D01*
G01X62555Y539167D02*
X62013Y539250D01*
X61555Y539375D01*
X61138Y539542D01*
X60680Y539750D01*
X60055Y540083D01*
Y538417D01*
G01X58222Y525875D02*
X58430Y526208D01*
X58555Y526583D01*
Y526917D01*
X58430Y527250D01*
X58222Y527500D01*
X57930Y527625D01*
X57638Y527542D01*
X57388Y527333D01*
X57222Y526958D01*
X57138Y526458D01*
X56972Y526167D01*
X56680Y526042D01*
X56388Y526125D01*
X56180Y526333D01*
X56055Y526625D01*
Y526917D01*
X56138Y527208D01*
X56347Y527458D01*
G01X56055Y529850D02*
X58555D01*
G01X56055Y528892D02*
Y530808D01*
G01X58555Y532117D02*
X56055D01*
Y533117D01*
X56180Y533450D01*
X56472Y533700D01*
X56805Y533783D01*
X57138Y533700D01*
X57388Y533492D01*
X57513Y533117D01*
Y532117D01*
G01X58555Y536050D02*
X56055D01*
X56555Y535550D01*
G01X58555D02*
Y536550D01*
G01Y539650D02*
X56055D01*
X57847Y538108D01*
Y540192D01*
G01X58555Y542250D02*
X58513Y542542D01*
X58388Y542875D01*
X58180Y543083D01*
X57888Y543167D01*
X57597Y543083D01*
X57347Y542833D01*
X57222Y542458D01*
Y542042D01*
X57138Y541792D01*
X56930Y541583D01*
X56638Y541500D01*
X56347Y541625D01*
X56138Y541917D01*
X56055Y542250D01*
X56138Y542583D01*
X56347Y542875D01*
X56638Y543000D01*
X56930Y542917D01*
X57138Y542708D01*
X57222Y542458D01*
Y542042D01*
X57347Y541667D01*
X57597Y541417D01*
X57888Y541333D01*
X58180Y541417D01*
X58388Y541625D01*
X58513Y541958D01*
X58555Y542250D01*
G01X54114Y675289D02*
X54322Y675622D01*
X54447Y675997D01*
Y676331D01*
X54322Y676664D01*
X54114Y676914D01*
X53822Y677039D01*
X53530Y676956D01*
X53280Y676747D01*
X53114Y676372D01*
X53030Y675872D01*
X52864Y675581D01*
X52572Y675456D01*
X52280Y675539D01*
X52072Y675747D01*
X51947Y676039D01*
Y676331D01*
X52030Y676622D01*
X52239Y676872D01*
G01X51947Y678347D02*
X53739D01*
X54114Y678514D01*
X54364Y678847D01*
X54447Y679264D01*
X54364Y679681D01*
X54114Y680014D01*
X53739Y680181D01*
X51947D01*
G01X54447Y682281D02*
X53905Y682364D01*
X53447Y682489D01*
X53030Y682656D01*
X52572Y682864D01*
X51947Y683197D01*
Y681531D01*
G01Y685464D02*
X52030Y685131D01*
X52239Y684881D01*
X52489Y684714D01*
X52822Y684589D01*
X53197Y684547D01*
X53572Y684589D01*
X53905Y684714D01*
X54155Y684881D01*
X54364Y685131D01*
X54447Y685464D01*
X54364Y685797D01*
X54155Y686047D01*
X53905Y686214D01*
X53572Y686339D01*
X53197Y686381D01*
X52822Y686339D01*
X52489Y686214D01*
X52239Y686047D01*
X52030Y685797D01*
X51947Y685464D01*
G01X58347Y680814D02*
X56897Y679364D01*
G01Y686314D02*
Y675314D01*
G01D02*
X77497D01*
G01X56897Y682264D02*
X58347Y680814D01*
G01X77497Y686314D02*
X56897D01*
G01X64804Y698737D02*
X62304D01*
Y699778D01*
X62429Y700112D01*
X62596Y700320D01*
X62929Y700403D01*
X63262Y700320D01*
X63471Y700070D01*
X63596Y699778D01*
Y698737D01*
G01Y699778D02*
X64804Y700403D01*
G01X63762Y701878D02*
X63471Y702170D01*
X63304Y702420D01*
X63221Y702753D01*
X63304Y703045D01*
X63471Y703253D01*
X63721Y703420D01*
X64012Y703462D01*
X64262Y703420D01*
X64512Y703253D01*
X64721Y703003D01*
X64804Y702712D01*
X64721Y702378D01*
X64471Y702087D01*
X64096Y701920D01*
X63679Y701878D01*
X63137Y701962D01*
X62846Y702087D01*
X62554Y702295D01*
X62346Y702587D01*
X62304Y702878D01*
X62387Y703170D01*
X62596Y703378D01*
G01X64804Y706270D02*
X62304D01*
X64096Y704728D01*
Y706812D01*
G01X64804Y708870D02*
X64762Y709162D01*
X64637Y709495D01*
X64429Y709703D01*
X64137Y709787D01*
X63846Y709703D01*
X63596Y709453D01*
X63471Y709078D01*
Y708662D01*
X63387Y708412D01*
X63179Y708203D01*
X62887Y708120D01*
X62596Y708245D01*
X62387Y708537D01*
X62304Y708870D01*
X62387Y709203D01*
X62596Y709495D01*
X62887Y709620D01*
X63179Y709537D01*
X63387Y709328D01*
X63471Y709078D01*
Y708662D01*
X63596Y708287D01*
X63846Y708037D01*
X64137Y707953D01*
X64429Y708037D01*
X64637Y708245D01*
X64762Y708578D01*
X64804Y708870D01*
G01X65304Y719920D02*
X61304D01*
Y712520D01*
G01X60304Y698737D02*
X57804D01*
Y699778D01*
X57929Y700112D01*
X58096Y700320D01*
X58429Y700403D01*
X58762Y700320D01*
X58971Y700070D01*
X59096Y699778D01*
Y698737D01*
G01Y699778D02*
X60304Y700403D01*
G01X59262Y701878D02*
X58971Y702170D01*
X58804Y702420D01*
X58721Y702753D01*
X58804Y703045D01*
X58971Y703253D01*
X59221Y703420D01*
X59512Y703462D01*
X59762Y703420D01*
X60012Y703253D01*
X60221Y703003D01*
X60304Y702712D01*
X60221Y702378D01*
X59971Y702087D01*
X59596Y701920D01*
X59179Y701878D01*
X58637Y701962D01*
X58346Y702087D01*
X58054Y702295D01*
X57846Y702587D01*
X57804Y702878D01*
X57887Y703170D01*
X58096Y703378D01*
G01X59929Y704853D02*
X60137Y705103D01*
X60262Y705395D01*
X60304Y705770D01*
X60221Y706145D01*
X60054Y706437D01*
X59762Y706645D01*
X59429Y706687D01*
X59096Y706603D01*
X58887Y706395D01*
X58721Y706103D01*
X58679Y705812D01*
X58721Y705520D01*
X58887Y705145D01*
X57804Y705270D01*
Y706395D01*
G01X60304Y709370D02*
X57804D01*
X59596Y707828D01*
Y709912D01*
G01X56804Y712520D02*
X60804D01*
Y719920D01*
G01X55471Y727695D02*
X55679Y728028D01*
X55804Y728403D01*
Y728737D01*
X55679Y729070D01*
X55471Y729320D01*
X55179Y729445D01*
X54887Y729362D01*
X54637Y729153D01*
X54471Y728778D01*
X54387Y728278D01*
X54221Y727987D01*
X53929Y727862D01*
X53637Y727945D01*
X53429Y728153D01*
X53304Y728445D01*
Y728737D01*
X53387Y729028D01*
X53596Y729278D01*
G01X53304Y730753D02*
X55096D01*
X55471Y730920D01*
X55721Y731253D01*
X55804Y731670D01*
X55721Y732087D01*
X55471Y732420D01*
X55096Y732587D01*
X53304D01*
G01X55804Y734770D02*
X53304D01*
X53804Y734270D01*
G01X55804D02*
Y735270D01*
G01Y737787D02*
X55262Y737870D01*
X54804Y737995D01*
X54387Y738162D01*
X53929Y738370D01*
X53304Y738703D01*
Y737037D01*
G01X100322Y759004D02*
Y735604D01*
X61672D01*
Y746404D01*
X100322D01*
G01X69804Y762237D02*
X67304D01*
Y763278D01*
X67429Y763612D01*
X67596Y763820D01*
X67929Y763903D01*
X68262Y763820D01*
X68471Y763570D01*
X68596Y763278D01*
Y762237D01*
G01Y763278D02*
X69804Y763903D01*
G01X68762Y765378D02*
X68471Y765670D01*
X68304Y765920D01*
X68221Y766253D01*
X68304Y766545D01*
X68471Y766753D01*
X68721Y766920D01*
X69012Y766962D01*
X69262Y766920D01*
X69512Y766753D01*
X69721Y766503D01*
X69804Y766212D01*
X69721Y765878D01*
X69471Y765587D01*
X69096Y765420D01*
X68679Y765378D01*
X68137Y765462D01*
X67846Y765587D01*
X67554Y765795D01*
X67346Y766087D01*
X67304Y766378D01*
X67387Y766670D01*
X67596Y766878D01*
G01X69804Y769770D02*
X67304D01*
X69096Y768228D01*
Y770312D01*
G01X67721Y771578D02*
X67471Y771828D01*
X67346Y772120D01*
X67304Y772453D01*
X67387Y772870D01*
X67596Y773162D01*
X67846Y773245D01*
X68096Y773203D01*
X68304Y773037D01*
X68721Y772203D01*
X69012Y771828D01*
X69429Y771578D01*
X69804Y771495D01*
Y773245D01*
G01X65804Y762237D02*
X63304D01*
Y763278D01*
X63429Y763612D01*
X63596Y763820D01*
X63929Y763903D01*
X64262Y763820D01*
X64471Y763570D01*
X64596Y763278D01*
Y762237D01*
G01Y763278D02*
X65804Y763903D01*
G01X64762Y765378D02*
X64471Y765670D01*
X64304Y765920D01*
X64221Y766253D01*
X64304Y766545D01*
X64471Y766753D01*
X64721Y766920D01*
X65012Y766962D01*
X65262Y766920D01*
X65512Y766753D01*
X65721Y766503D01*
X65804Y766212D01*
X65721Y765878D01*
X65471Y765587D01*
X65096Y765420D01*
X64679Y765378D01*
X64137Y765462D01*
X63846Y765587D01*
X63554Y765795D01*
X63346Y766087D01*
X63304Y766378D01*
X63387Y766670D01*
X63596Y766878D01*
G01X65429Y768353D02*
X65637Y768603D01*
X65762Y768895D01*
X65804Y769270D01*
X65721Y769645D01*
X65554Y769937D01*
X65262Y770145D01*
X64929Y770187D01*
X64596Y770103D01*
X64387Y769895D01*
X64221Y769603D01*
X64179Y769312D01*
X64221Y769020D01*
X64387Y768645D01*
X63304Y768770D01*
Y769895D01*
G01X65304Y771453D02*
X65596Y771703D01*
X65762Y772037D01*
X65804Y772412D01*
X65762Y772745D01*
X65554Y773078D01*
X65304Y773287D01*
X65054Y773328D01*
X64762Y773245D01*
X64554Y772953D01*
X64471Y772662D01*
Y772287D01*
G01Y772662D02*
X64346Y772912D01*
X64137Y773120D01*
X63887Y773203D01*
X63637Y773120D01*
X63429Y772912D01*
X63304Y772537D01*
X63346Y772162D01*
X63512Y771787D01*
G01X57304Y755920D02*
X53304D01*
Y748520D01*
G01X65272Y799704D02*
X61272D01*
Y792304D01*
G01X60772Y799704D02*
X56772D01*
Y792304D01*
G01X69772Y799704D02*
X65772D01*
Y792304D01*
G01X58572Y816804D02*
X68772D01*
G01X58572Y812204D02*
Y816804D01*
G01X69472Y812204D02*
X58572D01*
G01X60504Y828720D02*
Y832720D01*
X53104D01*
G01X60604D02*
Y828720D01*
X68004D01*
G01X63804Y838020D02*
X67804D01*
Y845420D01*
G01X53017Y834500D02*
Y837000D01*
X54058D01*
X54392Y836875D01*
X54600Y836708D01*
X54683Y836375D01*
X54600Y836042D01*
X54350Y835833D01*
X54058Y835708D01*
X53017D01*
G01X54058D02*
X54683Y834500D01*
G01X56158Y835542D02*
X56450Y835833D01*
X56700Y836000D01*
X57033Y836083D01*
X57325Y836000D01*
X57533Y835833D01*
X57700Y835583D01*
X57742Y835292D01*
X57700Y835042D01*
X57533Y834792D01*
X57283Y834583D01*
X56992Y834500D01*
X56658Y834583D01*
X56367Y834833D01*
X56200Y835208D01*
X56158Y835625D01*
X56242Y836167D01*
X56367Y836458D01*
X56575Y836750D01*
X56867Y836958D01*
X57158Y837000D01*
X57450Y836917D01*
X57658Y836708D01*
G01X59258Y836583D02*
X59508Y836833D01*
X59800Y836958D01*
X60133Y837000D01*
X60550Y836917D01*
X60842Y836708D01*
X60925Y836458D01*
X60883Y836208D01*
X60717Y836000D01*
X59883Y835583D01*
X59508Y835292D01*
X59258Y834875D01*
X59175Y834500D01*
X60925D01*
G01X63650D02*
Y837000D01*
X62108Y835208D01*
X64192D01*
G01X57167Y843425D02*
X57375Y843758D01*
X57500Y844133D01*
Y844467D01*
X57375Y844800D01*
X57167Y845050D01*
X56875Y845175D01*
X56583Y845092D01*
X56333Y844883D01*
X56167Y844508D01*
X56083Y844008D01*
X55917Y843717D01*
X55625Y843592D01*
X55333Y843675D01*
X55125Y843883D01*
X55000Y844175D01*
Y844467D01*
X55083Y844758D01*
X55292Y845008D01*
G01X55208Y848317D02*
X55083Y848067D01*
X55000Y847775D01*
Y847442D01*
X55125Y847067D01*
X55333Y846775D01*
X55583Y846567D01*
X56000Y846400D01*
X56375Y846358D01*
X56750Y846442D01*
X57000Y846567D01*
X57250Y846817D01*
X57417Y847108D01*
X57500Y847400D01*
Y847692D01*
X57417Y847983D01*
X57292Y848233D01*
X57125Y848442D01*
G01Y849583D02*
X57333Y849833D01*
X57458Y850125D01*
X57500Y850500D01*
X57417Y850875D01*
X57250Y851167D01*
X56958Y851375D01*
X56625Y851417D01*
X56292Y851333D01*
X56083Y851125D01*
X55917Y850833D01*
X55875Y850542D01*
X55917Y850250D01*
X56083Y849875D01*
X55000Y850000D01*
Y851125D01*
G01X56458Y852808D02*
X56167Y853100D01*
X56000Y853350D01*
X55917Y853683D01*
X56000Y853975D01*
X56167Y854183D01*
X56417Y854350D01*
X56708Y854392D01*
X56958Y854350D01*
X57208Y854183D01*
X57417Y853933D01*
X57500Y853642D01*
X57417Y853308D01*
X57167Y853017D01*
X56792Y852850D01*
X56375Y852808D01*
X55833Y852892D01*
X55542Y853017D01*
X55250Y853225D01*
X55042Y853517D01*
X55000Y853808D01*
X55083Y854100D01*
X55292Y854308D01*
G01X57500Y857200D02*
X55000D01*
X56792Y855658D01*
Y857742D01*
G01X63038Y846252D02*
Y869652D01*
X101688D01*
Y858852D01*
X63038D01*
G01Y866232D02*
Y866222D01*
X65008Y864252D01*
Y864242D01*
X63038Y862272D01*
G01X61504Y870720D02*
Y874720D01*
X54104D01*
G01X61504Y875720D02*
Y879720D01*
X54104D01*
G01X61504Y866220D02*
Y870220D01*
X54104D01*
G01X61504Y880220D02*
Y884220D01*
X54104D01*
G01X57279Y929553D02*
X57612Y929345D01*
X57987Y929220D01*
X58321D01*
X58654Y929345D01*
X58904Y929553D01*
X59029Y929845D01*
X58946Y930137D01*
X58737Y930387D01*
X58362Y930553D01*
X57862Y930637D01*
X57571Y930803D01*
X57446Y931095D01*
X57529Y931387D01*
X57737Y931595D01*
X58029Y931720D01*
X58321D01*
X58612Y931637D01*
X58862Y931428D01*
G01X60337Y931720D02*
Y929928D01*
X60504Y929553D01*
X60837Y929303D01*
X61254Y929220D01*
X61671Y929303D01*
X62004Y929553D01*
X62171Y929928D01*
Y931720D01*
G01X64354Y929220D02*
Y931720D01*
X63854Y931220D01*
G01Y929220D02*
X64854D01*
G01X66537Y929595D02*
X66787Y929387D01*
X67079Y929262D01*
X67454Y929220D01*
X67829Y929303D01*
X68121Y929470D01*
X68329Y929762D01*
X68371Y930095D01*
X68287Y930428D01*
X68079Y930637D01*
X67787Y930803D01*
X67496Y930845D01*
X67204Y930803D01*
X66829Y930637D01*
X66954Y931720D01*
X68079D01*
G01X74662Y-21799D02*
X70662D01*
X71462Y-22599D01*
G01X74662D02*
Y-20999D01*
G01X74430Y500333D02*
X74763Y500125D01*
X75138Y500000D01*
X75472D01*
X75805Y500125D01*
X76055Y500333D01*
X76180Y500625D01*
X76097Y500917D01*
X75888Y501167D01*
X75513Y501333D01*
X75013Y501417D01*
X74722Y501583D01*
X74597Y501875D01*
X74680Y502167D01*
X74888Y502375D01*
X75180Y502500D01*
X75472D01*
X75763Y502417D01*
X76013Y502208D01*
G01X77572Y502500D02*
Y500000D01*
X79238D01*
G01X82338D02*
X80672D01*
Y502500D01*
X82338D01*
G01X81672Y501292D02*
X80672D01*
G01X83688Y500000D02*
Y502500D01*
X84522D01*
X84855Y502375D01*
X85105Y502208D01*
X85313Y501958D01*
X85480Y501667D01*
X85522Y501250D01*
X85480Y500833D01*
X85313Y500542D01*
X85105Y500292D01*
X84855Y500125D01*
X84522Y500000D01*
X83688D01*
G01X86913Y502083D02*
X87163Y502333D01*
X87455Y502458D01*
X87788Y502500D01*
X88205Y502417D01*
X88497Y502208D01*
X88580Y501958D01*
X88538Y501708D01*
X88372Y501500D01*
X87538Y501083D01*
X87163Y500792D01*
X86913Y500375D01*
X86830Y500000D01*
X88580D01*
G01X90722D02*
X90805Y500542D01*
X90930Y501000D01*
X91097Y501417D01*
X91305Y501875D01*
X91638Y502500D01*
X89972D01*
G01X72555Y499017D02*
X70055D01*
Y500058D01*
X70180Y500392D01*
X70347Y500600D01*
X70680Y500683D01*
X71013Y500600D01*
X71222Y500350D01*
X71347Y500058D01*
Y499017D01*
G01Y500058D02*
X72555Y500683D01*
G01X72180Y502033D02*
X72388Y502283D01*
X72513Y502575D01*
X72555Y502950D01*
X72472Y503325D01*
X72305Y503617D01*
X72013Y503825D01*
X71680Y503867D01*
X71347Y503783D01*
X71138Y503575D01*
X70972Y503283D01*
X70930Y502992D01*
X70972Y502700D01*
X71138Y502325D01*
X70055Y502450D01*
Y503575D01*
G01X72263Y505342D02*
X72472Y505633D01*
X72555Y505967D01*
X72472Y506300D01*
X72222Y506592D01*
X71847Y506800D01*
X71472Y506883D01*
X71013D01*
X70638Y506800D01*
X70305Y506592D01*
X70138Y506342D01*
X70055Y506050D01*
X70138Y505717D01*
X70305Y505467D01*
X70555Y505300D01*
X70888Y505217D01*
X71180Y505300D01*
X71472Y505508D01*
X71638Y505758D01*
X71680Y506050D01*
X71597Y506383D01*
X71388Y506633D01*
X71013Y506883D01*
G01X72555Y509150D02*
X70055D01*
X70555Y508650D01*
G01X72555D02*
Y509650D01*
G01X84467Y505925D02*
X84675Y506258D01*
X84800Y506633D01*
Y506967D01*
X84675Y507300D01*
X84467Y507550D01*
X84175Y507675D01*
X83883Y507592D01*
X83633Y507383D01*
X83467Y507008D01*
X83383Y506508D01*
X83217Y506217D01*
X82925Y506092D01*
X82633Y506175D01*
X82425Y506383D01*
X82300Y506675D01*
Y506967D01*
X82383Y507258D01*
X82592Y507508D01*
G01X82300Y509900D02*
X84800D01*
G01X82300Y508942D02*
Y510858D01*
G01X84800Y512167D02*
X82300D01*
Y513167D01*
X82425Y513500D01*
X82717Y513750D01*
X83050Y513833D01*
X83383Y513750D01*
X83633Y513542D01*
X83758Y513167D01*
Y512167D01*
G01Y515308D02*
X83467Y515600D01*
X83300Y515850D01*
X83217Y516183D01*
X83300Y516475D01*
X83467Y516683D01*
X83717Y516850D01*
X84008Y516892D01*
X84258Y516850D01*
X84508Y516683D01*
X84717Y516433D01*
X84800Y516142D01*
X84717Y515808D01*
X84467Y515517D01*
X84092Y515350D01*
X83675Y515308D01*
X83133Y515392D01*
X82842Y515517D01*
X82550Y515725D01*
X82342Y516017D01*
X82300Y516308D01*
X82383Y516600D01*
X82592Y516808D01*
G01X84425Y518283D02*
X84633Y518533D01*
X84758Y518825D01*
X84800Y519200D01*
X84717Y519575D01*
X84550Y519867D01*
X84258Y520075D01*
X83925Y520117D01*
X83592Y520033D01*
X83383Y519825D01*
X83217Y519533D01*
X83175Y519242D01*
X83217Y518950D01*
X83383Y518575D01*
X82300Y518700D01*
Y519825D01*
G01X74722Y525875D02*
X74930Y526208D01*
X75055Y526583D01*
Y526917D01*
X74930Y527250D01*
X74722Y527500D01*
X74430Y527625D01*
X74138Y527542D01*
X73888Y527333D01*
X73722Y526958D01*
X73638Y526458D01*
X73472Y526167D01*
X73180Y526042D01*
X72888Y526125D01*
X72680Y526333D01*
X72555Y526625D01*
Y526917D01*
X72638Y527208D01*
X72847Y527458D01*
G01X72555Y529850D02*
X75055D01*
G01X72555Y528892D02*
Y530808D01*
G01X75055Y532117D02*
X72555D01*
Y533117D01*
X72680Y533450D01*
X72972Y533700D01*
X73305Y533783D01*
X73638Y533700D01*
X73888Y533492D01*
X74013Y533117D01*
Y532117D01*
G01X75055Y536050D02*
X72555D01*
X73055Y535550D01*
G01X75055D02*
Y536550D01*
G01X74680Y538233D02*
X74888Y538483D01*
X75013Y538775D01*
X75055Y539150D01*
X74972Y539525D01*
X74805Y539817D01*
X74513Y540025D01*
X74180Y540067D01*
X73847Y539983D01*
X73638Y539775D01*
X73472Y539483D01*
X73430Y539192D01*
X73472Y538900D01*
X73638Y538525D01*
X72555Y538650D01*
Y539775D01*
G01X74013Y541458D02*
X73722Y541750D01*
X73555Y542000D01*
X73472Y542333D01*
X73555Y542625D01*
X73722Y542833D01*
X73972Y543000D01*
X74263Y543042D01*
X74513Y543000D01*
X74763Y542833D01*
X74972Y542583D01*
X75055Y542292D01*
X74972Y541958D01*
X74722Y541667D01*
X74347Y541500D01*
X73930Y541458D01*
X73388Y541542D01*
X73097Y541667D01*
X72805Y541875D01*
X72597Y542167D01*
X72555Y542458D01*
X72638Y542750D01*
X72847Y542958D01*
G01X83222Y526425D02*
X83430Y526758D01*
X83555Y527133D01*
Y527467D01*
X83430Y527800D01*
X83222Y528050D01*
X82930Y528175D01*
X82638Y528092D01*
X82388Y527883D01*
X82222Y527508D01*
X82138Y527008D01*
X81972Y526717D01*
X81680Y526592D01*
X81388Y526675D01*
X81180Y526883D01*
X81055Y527175D01*
Y527467D01*
X81138Y527758D01*
X81347Y528008D01*
G01X81055Y530400D02*
X83555D01*
G01X81055Y529442D02*
Y531358D01*
G01X83555Y532667D02*
X81055D01*
Y533667D01*
X81180Y534000D01*
X81472Y534250D01*
X81805Y534333D01*
X82138Y534250D01*
X82388Y534042D01*
X82513Y533667D01*
Y532667D01*
G01Y535808D02*
X82222Y536100D01*
X82055Y536350D01*
X81972Y536683D01*
X82055Y536975D01*
X82222Y537183D01*
X82472Y537350D01*
X82763Y537392D01*
X83013Y537350D01*
X83263Y537183D01*
X83472Y536933D01*
X83555Y536642D01*
X83472Y536308D01*
X83222Y536017D01*
X82847Y535850D01*
X82430Y535808D01*
X81888Y535892D01*
X81597Y536017D01*
X81305Y536225D01*
X81097Y536517D01*
X81055Y536808D01*
X81138Y537100D01*
X81347Y537308D01*
G01X83055Y538783D02*
X83347Y539033D01*
X83513Y539367D01*
X83555Y539742D01*
X83513Y540075D01*
X83305Y540408D01*
X83055Y540617D01*
X82805Y540658D01*
X82513Y540575D01*
X82305Y540283D01*
X82222Y539992D01*
Y539617D01*
G01Y539992D02*
X82097Y540242D01*
X81888Y540450D01*
X81638Y540533D01*
X81388Y540450D01*
X81180Y540242D01*
X81055Y539867D01*
X81097Y539492D01*
X81263Y539117D01*
G01X79222Y523425D02*
X79430Y523758D01*
X79555Y524133D01*
Y524467D01*
X79430Y524800D01*
X79222Y525050D01*
X78930Y525175D01*
X78638Y525092D01*
X78388Y524883D01*
X78222Y524508D01*
X78138Y524008D01*
X77972Y523717D01*
X77680Y523592D01*
X77388Y523675D01*
X77180Y523883D01*
X77055Y524175D01*
Y524467D01*
X77138Y524758D01*
X77347Y525008D01*
G01X77055Y527400D02*
X79555D01*
G01X77055Y526442D02*
Y528358D01*
G01X79555Y529667D02*
X77055D01*
Y530667D01*
X77180Y531000D01*
X77472Y531250D01*
X77805Y531333D01*
X78138Y531250D01*
X78388Y531042D01*
X78513Y530667D01*
Y529667D01*
G01Y532808D02*
X78222Y533100D01*
X78055Y533350D01*
X77972Y533683D01*
X78055Y533975D01*
X78222Y534183D01*
X78472Y534350D01*
X78763Y534392D01*
X79013Y534350D01*
X79263Y534183D01*
X79472Y533933D01*
X79555Y533642D01*
X79472Y533308D01*
X79222Y533017D01*
X78847Y532850D01*
X78430Y532808D01*
X77888Y532892D01*
X77597Y533017D01*
X77305Y533225D01*
X77097Y533517D01*
X77055Y533808D01*
X77138Y534100D01*
X77347Y534308D01*
G01X78513Y535908D02*
X78222Y536200D01*
X78055Y536450D01*
X77972Y536783D01*
X78055Y537075D01*
X78222Y537283D01*
X78472Y537450D01*
X78763Y537492D01*
X79013Y537450D01*
X79263Y537283D01*
X79472Y537033D01*
X79555Y536742D01*
X79472Y536408D01*
X79222Y536117D01*
X78847Y535950D01*
X78430Y535908D01*
X77888Y535992D01*
X77597Y536117D01*
X77305Y536325D01*
X77097Y536617D01*
X77055Y536908D01*
X77138Y537200D01*
X77347Y537408D01*
G01X77497Y675314D02*
Y686314D01*
G01X82804Y698237D02*
X80304D01*
Y699278D01*
X80429Y699612D01*
X80596Y699820D01*
X80929Y699903D01*
X81262Y699820D01*
X81471Y699570D01*
X81596Y699278D01*
Y698237D01*
G01Y699278D02*
X82804Y699903D01*
G01X81762Y701378D02*
X81471Y701670D01*
X81304Y701920D01*
X81221Y702253D01*
X81304Y702545D01*
X81471Y702753D01*
X81721Y702920D01*
X82012Y702962D01*
X82262Y702920D01*
X82512Y702753D01*
X82721Y702503D01*
X82804Y702212D01*
X82721Y701878D01*
X82471Y701587D01*
X82096Y701420D01*
X81679Y701378D01*
X81137Y701462D01*
X80846Y701587D01*
X80554Y701795D01*
X80346Y702087D01*
X80304Y702378D01*
X80387Y702670D01*
X80596Y702878D01*
G01X82804Y705770D02*
X80304D01*
X82096Y704228D01*
Y706312D01*
G01X82512Y707662D02*
X82721Y707953D01*
X82804Y708287D01*
X82721Y708620D01*
X82471Y708912D01*
X82096Y709120D01*
X81721Y709203D01*
X81262D01*
X80887Y709120D01*
X80554Y708912D01*
X80387Y708662D01*
X80304Y708370D01*
X80387Y708037D01*
X80554Y707787D01*
X80804Y707620D01*
X81137Y707537D01*
X81429Y707620D01*
X81721Y707828D01*
X81887Y708078D01*
X81929Y708370D01*
X81846Y708703D01*
X81637Y708953D01*
X81262Y709203D01*
G01X83304Y719920D02*
X79304D01*
Y712520D01*
G01X78304Y698237D02*
X75804D01*
Y699278D01*
X75929Y699612D01*
X76096Y699820D01*
X76429Y699903D01*
X76762Y699820D01*
X76971Y699570D01*
X77096Y699278D01*
Y698237D01*
G01Y699278D02*
X78304Y699903D01*
G01X77262Y701378D02*
X76971Y701670D01*
X76804Y701920D01*
X76721Y702253D01*
X76804Y702545D01*
X76971Y702753D01*
X77221Y702920D01*
X77512Y702962D01*
X77762Y702920D01*
X78012Y702753D01*
X78221Y702503D01*
X78304Y702212D01*
X78221Y701878D01*
X77971Y701587D01*
X77596Y701420D01*
X77179Y701378D01*
X76637Y701462D01*
X76346Y701587D01*
X76054Y701795D01*
X75846Y702087D01*
X75804Y702378D01*
X75887Y702670D01*
X76096Y702878D01*
G01X77929Y704353D02*
X78137Y704603D01*
X78262Y704895D01*
X78304Y705270D01*
X78221Y705645D01*
X78054Y705937D01*
X77762Y706145D01*
X77429Y706187D01*
X77096Y706103D01*
X76887Y705895D01*
X76721Y705603D01*
X76679Y705312D01*
X76721Y705020D01*
X76887Y704645D01*
X75804Y704770D01*
Y705895D01*
G01Y708370D02*
X75887Y708037D01*
X76096Y707787D01*
X76346Y707620D01*
X76679Y707495D01*
X77054Y707453D01*
X77429Y707495D01*
X77762Y707620D01*
X78012Y707787D01*
X78221Y708037D01*
X78304Y708370D01*
X78221Y708703D01*
X78012Y708953D01*
X77762Y709120D01*
X77429Y709245D01*
X77054Y709287D01*
X76679Y709245D01*
X76346Y709120D01*
X76096Y708953D01*
X75887Y708703D01*
X75804Y708370D01*
G01X74804Y712520D02*
X78804D01*
Y719920D01*
G01X75804Y764520D02*
X79804D01*
Y771920D01*
G01X71804Y764520D02*
X75804D01*
Y771920D01*
G01X83804Y792737D02*
X81304D01*
Y793778D01*
X81429Y794112D01*
X81596Y794320D01*
X81929Y794403D01*
X82262Y794320D01*
X82471Y794070D01*
X82596Y793778D01*
Y792737D01*
G01Y793778D02*
X83804Y794403D01*
G01X83429Y795753D02*
X83637Y796003D01*
X83762Y796295D01*
X83804Y796670D01*
X83721Y797045D01*
X83554Y797337D01*
X83262Y797545D01*
X82929Y797587D01*
X82596Y797503D01*
X82387Y797295D01*
X82221Y797003D01*
X82179Y796712D01*
X82221Y796420D01*
X82387Y796045D01*
X81304Y796170D01*
Y797295D01*
G01X83804Y799687D02*
X83262Y799770D01*
X82804Y799895D01*
X82387Y800062D01*
X81929Y800270D01*
X81304Y800603D01*
Y798937D01*
G01Y802870D02*
X81387Y802537D01*
X81596Y802287D01*
X81846Y802120D01*
X82179Y801995D01*
X82554Y801953D01*
X82929Y801995D01*
X83262Y802120D01*
X83512Y802287D01*
X83721Y802537D01*
X83804Y802870D01*
X83721Y803203D01*
X83512Y803453D01*
X83262Y803620D01*
X82929Y803745D01*
X82554Y803787D01*
X82179Y803745D01*
X81846Y803620D01*
X81596Y803453D01*
X81387Y803203D01*
X81304Y802870D01*
G01X73821Y808220D02*
Y810720D01*
X74862D01*
X75196Y810595D01*
X75404Y810428D01*
X75487Y810095D01*
X75404Y809762D01*
X75154Y809553D01*
X74862Y809428D01*
X73821D01*
G01X74862D02*
X75487Y808220D01*
G01X76837Y808595D02*
X77087Y808387D01*
X77379Y808262D01*
X77754Y808220D01*
X78129Y808303D01*
X78421Y808470D01*
X78629Y808762D01*
X78671Y809095D01*
X78587Y809428D01*
X78379Y809637D01*
X78087Y809803D01*
X77796Y809845D01*
X77504Y809803D01*
X77129Y809637D01*
X77254Y810720D01*
X78379D01*
G01X80062Y809262D02*
X80354Y809553D01*
X80604Y809720D01*
X80937Y809803D01*
X81229Y809720D01*
X81437Y809553D01*
X81604Y809303D01*
X81646Y809012D01*
X81604Y808762D01*
X81437Y808512D01*
X81187Y808303D01*
X80896Y808220D01*
X80562Y808303D01*
X80271Y808553D01*
X80104Y808928D01*
X80062Y809345D01*
X80146Y809887D01*
X80271Y810178D01*
X80479Y810470D01*
X80771Y810678D01*
X81062Y810720D01*
X81354Y810637D01*
X81562Y810428D01*
G01X83871Y808220D02*
X83954Y808762D01*
X84079Y809220D01*
X84246Y809637D01*
X84454Y810095D01*
X84787Y810720D01*
X83121D01*
G01X73821Y812720D02*
Y815220D01*
X74862D01*
X75196Y815095D01*
X75404Y814928D01*
X75487Y814595D01*
X75404Y814262D01*
X75154Y814053D01*
X74862Y813928D01*
X73821D01*
G01X74862D02*
X75487Y812720D01*
G01X76837Y813095D02*
X77087Y812887D01*
X77379Y812762D01*
X77754Y812720D01*
X78129Y812803D01*
X78421Y812970D01*
X78629Y813262D01*
X78671Y813595D01*
X78587Y813928D01*
X78379Y814137D01*
X78087Y814303D01*
X77796Y814345D01*
X77504Y814303D01*
X77129Y814137D01*
X77254Y815220D01*
X78379D01*
G01X80062Y813762D02*
X80354Y814053D01*
X80604Y814220D01*
X80937Y814303D01*
X81229Y814220D01*
X81437Y814053D01*
X81604Y813803D01*
X81646Y813512D01*
X81604Y813262D01*
X81437Y813012D01*
X81187Y812803D01*
X80896Y812720D01*
X80562Y812803D01*
X80271Y813053D01*
X80104Y813428D01*
X80062Y813845D01*
X80146Y814387D01*
X80271Y814678D01*
X80479Y814970D01*
X80771Y815178D01*
X81062Y815220D01*
X81354Y815137D01*
X81562Y814928D01*
G01X83246Y813012D02*
X83537Y812803D01*
X83871Y812720D01*
X84204Y812803D01*
X84496Y813053D01*
X84704Y813428D01*
X84787Y813803D01*
Y814262D01*
X84704Y814637D01*
X84496Y814970D01*
X84246Y815137D01*
X83954Y815220D01*
X83621Y815137D01*
X83371Y814970D01*
X83204Y814720D01*
X83121Y814387D01*
X83204Y814095D01*
X83412Y813803D01*
X83662Y813637D01*
X83954Y813595D01*
X84287Y813678D01*
X84537Y813887D01*
X84787Y814262D01*
G01X69472Y812204D02*
Y823504D01*
G01X68272Y814504D02*
X69472Y813304D01*
G01X68272Y814504D02*
X69472Y815704D01*
G01X73821Y816720D02*
Y819220D01*
X74862D01*
X75196Y819095D01*
X75404Y818928D01*
X75487Y818595D01*
X75404Y818262D01*
X75154Y818053D01*
X74862Y817928D01*
X73821D01*
G01X74862D02*
X75487Y816720D01*
G01X76837Y817095D02*
X77087Y816887D01*
X77379Y816762D01*
X77754Y816720D01*
X78129Y816803D01*
X78421Y816970D01*
X78629Y817262D01*
X78671Y817595D01*
X78587Y817928D01*
X78379Y818137D01*
X78087Y818303D01*
X77796Y818345D01*
X77504Y818303D01*
X77129Y818137D01*
X77254Y819220D01*
X78379D01*
G01X80771Y816720D02*
X80854Y817262D01*
X80979Y817720D01*
X81146Y818137D01*
X81354Y818595D01*
X81687Y819220D01*
X80021D01*
G01X83954Y816720D02*
Y819220D01*
X83454Y818720D01*
G01Y816720D02*
X84454D01*
G01X81971Y821645D02*
X82179Y821978D01*
X82304Y822353D01*
Y822687D01*
X82179Y823020D01*
X81971Y823270D01*
X81679Y823395D01*
X81387Y823312D01*
X81137Y823103D01*
X80971Y822728D01*
X80887Y822228D01*
X80721Y821937D01*
X80429Y821812D01*
X80137Y821895D01*
X79929Y822103D01*
X79804Y822395D01*
Y822687D01*
X79887Y822978D01*
X80096Y823228D01*
G01X82304Y824787D02*
X79804D01*
Y825828D01*
X79929Y826162D01*
X80096Y826370D01*
X80429Y826453D01*
X80762Y826370D01*
X80971Y826120D01*
X81096Y825828D01*
Y824787D01*
G01Y825828D02*
X82304Y826453D01*
G01X81804Y827803D02*
X82096Y828053D01*
X82262Y828387D01*
X82304Y828762D01*
X82262Y829095D01*
X82054Y829428D01*
X81804Y829637D01*
X81554Y829678D01*
X81262Y829595D01*
X81054Y829303D01*
X80971Y829012D01*
Y828637D01*
G01Y829012D02*
X80846Y829262D01*
X80637Y829470D01*
X80387Y829553D01*
X80137Y829470D01*
X79929Y829262D01*
X79804Y828887D01*
X79846Y828512D01*
X80012Y828137D01*
G01X79804Y831820D02*
X79887Y831487D01*
X80096Y831237D01*
X80346Y831070D01*
X80679Y830945D01*
X81054Y830903D01*
X81429Y830945D01*
X81762Y831070D01*
X82012Y831237D01*
X82221Y831487D01*
X82304Y831820D01*
X82221Y832153D01*
X82012Y832403D01*
X81762Y832570D01*
X81429Y832695D01*
X81054Y832737D01*
X80679Y832695D01*
X80346Y832570D01*
X80096Y832403D01*
X79887Y832153D01*
X79804Y831820D01*
G01X81929Y834003D02*
X82137Y834253D01*
X82262Y834545D01*
X82304Y834920D01*
X82221Y835295D01*
X82054Y835587D01*
X81762Y835795D01*
X81429Y835837D01*
X81096Y835753D01*
X80887Y835545D01*
X80721Y835253D01*
X80679Y834962D01*
X80721Y834670D01*
X80887Y834295D01*
X79804Y834420D01*
Y835545D01*
G01X74304Y822237D02*
X71804D01*
Y823278D01*
X71929Y823612D01*
X72096Y823820D01*
X72429Y823903D01*
X72762Y823820D01*
X72971Y823570D01*
X73096Y823278D01*
Y822237D01*
G01Y823278D02*
X74304Y823903D01*
G01X73262Y825378D02*
X72971Y825670D01*
X72804Y825920D01*
X72721Y826253D01*
X72804Y826545D01*
X72971Y826753D01*
X73221Y826920D01*
X73512Y826962D01*
X73762Y826920D01*
X74012Y826753D01*
X74221Y826503D01*
X74304Y826212D01*
X74221Y825878D01*
X73971Y825587D01*
X73596Y825420D01*
X73179Y825378D01*
X72637Y825462D01*
X72346Y825587D01*
X72054Y825795D01*
X71846Y826087D01*
X71804Y826378D01*
X71887Y826670D01*
X72096Y826878D01*
G01X73804Y828353D02*
X74096Y828603D01*
X74262Y828937D01*
X74304Y829312D01*
X74262Y829645D01*
X74054Y829978D01*
X73804Y830187D01*
X73554Y830228D01*
X73262Y830145D01*
X73054Y829853D01*
X72971Y829562D01*
Y829187D01*
G01Y829562D02*
X72846Y829812D01*
X72637Y830020D01*
X72387Y830103D01*
X72137Y830020D01*
X71929Y829812D01*
X71804Y829437D01*
X71846Y829062D01*
X72012Y828687D01*
G01X71804Y832370D02*
X71887Y832037D01*
X72096Y831787D01*
X72346Y831620D01*
X72679Y831495D01*
X73054Y831453D01*
X73429Y831495D01*
X73762Y831620D01*
X74012Y831787D01*
X74221Y832037D01*
X74304Y832370D01*
X74221Y832703D01*
X74012Y832953D01*
X73762Y833120D01*
X73429Y833245D01*
X73054Y833287D01*
X72679Y833245D01*
X72346Y833120D01*
X72096Y832953D01*
X71887Y832703D01*
X71804Y832370D01*
G01X78304Y822237D02*
X75804D01*
Y823278D01*
X75929Y823612D01*
X76096Y823820D01*
X76429Y823903D01*
X76762Y823820D01*
X76971Y823570D01*
X77096Y823278D01*
Y822237D01*
G01Y823278D02*
X78304Y823903D01*
G01X77262Y825378D02*
X76971Y825670D01*
X76804Y825920D01*
X76721Y826253D01*
X76804Y826545D01*
X76971Y826753D01*
X77221Y826920D01*
X77512Y826962D01*
X77762Y826920D01*
X78012Y826753D01*
X78221Y826503D01*
X78304Y826212D01*
X78221Y825878D01*
X77971Y825587D01*
X77596Y825420D01*
X77179Y825378D01*
X76637Y825462D01*
X76346Y825587D01*
X76054Y825795D01*
X75846Y826087D01*
X75804Y826378D01*
X75887Y826670D01*
X76096Y826878D01*
G01X77804Y828353D02*
X78096Y828603D01*
X78262Y828937D01*
X78304Y829312D01*
X78262Y829645D01*
X78054Y829978D01*
X77804Y830187D01*
X77554Y830228D01*
X77262Y830145D01*
X77054Y829853D01*
X76971Y829562D01*
Y829187D01*
G01Y829562D02*
X76846Y829812D01*
X76637Y830020D01*
X76387Y830103D01*
X76137Y830020D01*
X75929Y829812D01*
X75804Y829437D01*
X75846Y829062D01*
X76012Y828687D01*
G01X78304Y832370D02*
X75804D01*
X76304Y831870D01*
G01X78304D02*
Y832870D01*
G01X72304Y838020D02*
X76304D01*
Y845420D01*
G01X81304Y838020D02*
X85304D01*
Y845420D01*
G01X76804Y838020D02*
X80804D01*
Y845420D01*
G01X71804D02*
X67804D01*
Y838020D01*
G01X72604Y891720D02*
Y887720D01*
X80004D01*
G01Y883720D02*
Y887720D01*
X72604D01*
G01X73120Y905488D02*
Y917888D01*
G01D02*
Y905488D01*
G01X80304Y896237D02*
X77804D01*
Y897278D01*
X77929Y897612D01*
X78096Y897820D01*
X78429Y897903D01*
X78762Y897820D01*
X78971Y897570D01*
X79096Y897278D01*
Y896237D01*
G01Y897278D02*
X80304Y897903D01*
G01X79262Y899378D02*
X78971Y899670D01*
X78804Y899920D01*
X78721Y900253D01*
X78804Y900545D01*
X78971Y900753D01*
X79221Y900920D01*
X79512Y900962D01*
X79762Y900920D01*
X80012Y900753D01*
X80221Y900503D01*
X80304Y900212D01*
X80221Y899878D01*
X79971Y899587D01*
X79596Y899420D01*
X79179Y899378D01*
X78637Y899462D01*
X78346Y899587D01*
X78054Y899795D01*
X77846Y900087D01*
X77804Y900378D01*
X77887Y900670D01*
X78096Y900878D01*
G01X79804Y902353D02*
X80096Y902603D01*
X80262Y902937D01*
X80304Y903312D01*
X80262Y903645D01*
X80054Y903978D01*
X79804Y904187D01*
X79554Y904228D01*
X79262Y904145D01*
X79054Y903853D01*
X78971Y903562D01*
Y903187D01*
G01Y903562D02*
X78846Y903812D01*
X78637Y904020D01*
X78387Y904103D01*
X78137Y904020D01*
X77929Y903812D01*
X77804Y903437D01*
X77846Y903062D01*
X78012Y902687D01*
G01X80304Y906870D02*
X77804D01*
X79596Y905328D01*
Y907412D01*
G01X84304Y894737D02*
X81804D01*
Y895778D01*
X81929Y896112D01*
X82096Y896320D01*
X82429Y896403D01*
X82762Y896320D01*
X82971Y896070D01*
X83096Y895778D01*
Y894737D01*
G01Y895778D02*
X84304Y896403D01*
G01X83262Y897878D02*
X82971Y898170D01*
X82804Y898420D01*
X82721Y898753D01*
X82804Y899045D01*
X82971Y899253D01*
X83221Y899420D01*
X83512Y899462D01*
X83762Y899420D01*
X84012Y899253D01*
X84221Y899003D01*
X84304Y898712D01*
X84221Y898378D01*
X83971Y898087D01*
X83596Y897920D01*
X83179Y897878D01*
X82637Y897962D01*
X82346Y898087D01*
X82054Y898295D01*
X81846Y898587D01*
X81804Y898878D01*
X81887Y899170D01*
X82096Y899378D01*
G01X83804Y900853D02*
X84096Y901103D01*
X84262Y901437D01*
X84304Y901812D01*
X84262Y902145D01*
X84054Y902478D01*
X83804Y902687D01*
X83554Y902728D01*
X83262Y902645D01*
X83054Y902353D01*
X82971Y902062D01*
Y901687D01*
G01Y902062D02*
X82846Y902312D01*
X82637Y902520D01*
X82387Y902603D01*
X82137Y902520D01*
X81929Y902312D01*
X81804Y901937D01*
X81846Y901562D01*
X82012Y901187D01*
G01X83262Y904078D02*
X82971Y904370D01*
X82804Y904620D01*
X82721Y904953D01*
X82804Y905245D01*
X82971Y905453D01*
X83221Y905620D01*
X83512Y905662D01*
X83762Y905620D01*
X84012Y905453D01*
X84221Y905203D01*
X84304Y904912D01*
X84221Y904578D01*
X83971Y904287D01*
X83596Y904120D01*
X83179Y904078D01*
X82637Y904162D01*
X82346Y904287D01*
X82054Y904495D01*
X81846Y904787D01*
X81804Y905078D01*
X81887Y905370D01*
X82096Y905578D01*
G01X77925Y934833D02*
X78258Y934625D01*
X78633Y934500D01*
X78967D01*
X79300Y934625D01*
X79550Y934833D01*
X79675Y935125D01*
X79592Y935417D01*
X79383Y935667D01*
X79008Y935833D01*
X78508Y935917D01*
X78217Y936083D01*
X78092Y936375D01*
X78175Y936667D01*
X78383Y936875D01*
X78675Y937000D01*
X78967D01*
X79258Y936917D01*
X79508Y936708D01*
G01X82817Y936792D02*
X82567Y936917D01*
X82275Y937000D01*
X81942D01*
X81567Y936875D01*
X81275Y936667D01*
X81067Y936417D01*
X80900Y936000D01*
X80858Y935625D01*
X80942Y935250D01*
X81067Y935000D01*
X81317Y934750D01*
X81608Y934583D01*
X81900Y934500D01*
X82192D01*
X82483Y934583D01*
X82733Y934708D01*
X82942Y934875D01*
G01X85500Y934500D02*
Y937000D01*
X83958Y935208D01*
X86042D01*
G01X87308Y936583D02*
X87558Y936833D01*
X87850Y936958D01*
X88183Y937000D01*
X88600Y936917D01*
X88892Y936708D01*
X88975Y936458D01*
X88933Y936208D01*
X88767Y936000D01*
X87933Y935583D01*
X87558Y935292D01*
X87308Y934875D01*
X87225Y934500D01*
X88975D01*
G01X90408Y935542D02*
X90700Y935833D01*
X90950Y936000D01*
X91283Y936083D01*
X91575Y936000D01*
X91783Y935833D01*
X91950Y935583D01*
X91992Y935292D01*
X91950Y935042D01*
X91783Y934792D01*
X91533Y934583D01*
X91242Y934500D01*
X90908Y934583D01*
X90617Y934833D01*
X90450Y935208D01*
X90408Y935625D01*
X90492Y936167D01*
X90617Y936458D01*
X90825Y936750D01*
X91117Y936958D01*
X91408Y937000D01*
X91700Y936917D01*
X91908Y936708D01*
G01X86755Y408128D02*
Y360828D01*
G01X85555Y484933D02*
X87347D01*
X87722Y485100D01*
X87972Y485433D01*
X88055Y485850D01*
X87972Y486267D01*
X87722Y486600D01*
X87347Y486767D01*
X85555D01*
G01X88055Y488950D02*
X85555D01*
X86055Y488450D01*
G01X88055D02*
Y489450D01*
G01X87555Y491133D02*
X87847Y491383D01*
X88013Y491717D01*
X88055Y492092D01*
X88013Y492425D01*
X87805Y492758D01*
X87555Y492967D01*
X87305Y493008D01*
X87013Y492925D01*
X86805Y492633D01*
X86722Y492342D01*
Y491967D01*
G01Y492342D02*
X86597Y492592D01*
X86388Y492800D01*
X86138Y492883D01*
X85888Y492800D01*
X85680Y492592D01*
X85555Y492217D01*
X85597Y491842D01*
X85763Y491467D01*
G01X87013Y494358D02*
X86722Y494650D01*
X86555Y494900D01*
X86472Y495233D01*
X86555Y495525D01*
X86722Y495733D01*
X86972Y495900D01*
X87263Y495942D01*
X87513Y495900D01*
X87763Y495733D01*
X87972Y495483D01*
X88055Y495192D01*
X87972Y494858D01*
X87722Y494567D01*
X87347Y494400D01*
X86930Y494358D01*
X86388Y494442D01*
X86097Y494567D01*
X85805Y494775D01*
X85597Y495067D01*
X85555Y495358D01*
X85638Y495650D01*
X85847Y495858D01*
G01X97167Y494025D02*
X97375Y494358D01*
X97500Y494733D01*
Y495067D01*
X97375Y495400D01*
X97167Y495650D01*
X96875Y495775D01*
X96583Y495692D01*
X96333Y495483D01*
X96167Y495108D01*
X96083Y494608D01*
X95917Y494317D01*
X95625Y494192D01*
X95333Y494275D01*
X95125Y494483D01*
X95000Y494775D01*
Y495067D01*
X95083Y495358D01*
X95292Y495608D01*
G01X97500Y498000D02*
X97458Y497667D01*
X97292Y497375D01*
X97042Y497125D01*
X96750Y496958D01*
X96417Y496875D01*
X96083D01*
X95750Y496958D01*
X95458Y497125D01*
X95208Y497375D01*
X95042Y497667D01*
X95000Y498000D01*
X95042Y498333D01*
X95208Y498625D01*
X95458Y498875D01*
X95750Y499042D01*
X96083Y499125D01*
X96417D01*
X96750Y499042D01*
X97042Y498875D01*
X97292Y498625D01*
X97458Y498333D01*
X97500Y498000D01*
G01X96833Y498333D02*
X97500Y498833D01*
G01X97125Y500183D02*
X97333Y500433D01*
X97458Y500725D01*
X97500Y501100D01*
X97417Y501475D01*
X97250Y501767D01*
X96958Y501975D01*
X96625Y502017D01*
X96292Y501933D01*
X96083Y501725D01*
X95917Y501433D01*
X95875Y501142D01*
X95917Y500850D01*
X96083Y500475D01*
X95000Y500600D01*
Y501725D01*
G01X97167Y503925D02*
X97375Y504258D01*
X97500Y504633D01*
Y504967D01*
X97375Y505300D01*
X97167Y505550D01*
X96875Y505675D01*
X96583Y505592D01*
X96333Y505383D01*
X96167Y505008D01*
X96083Y504508D01*
X95917Y504217D01*
X95625Y504092D01*
X95333Y504175D01*
X95125Y504383D01*
X95000Y504675D01*
Y504967D01*
X95083Y505258D01*
X95292Y505508D01*
G01X95000Y507900D02*
X97500D01*
G01X95000Y506942D02*
Y508858D01*
G01X97500Y510167D02*
X95000D01*
Y511167D01*
X95125Y511500D01*
X95417Y511750D01*
X95750Y511833D01*
X96083Y511750D01*
X96333Y511542D01*
X96458Y511167D01*
Y510167D01*
G01X97500Y514017D02*
X96958Y514100D01*
X96500Y514225D01*
X96083Y514392D01*
X95625Y514600D01*
X95000Y514933D01*
Y513267D01*
G01X97000Y516283D02*
X97292Y516533D01*
X97458Y516867D01*
X97500Y517242D01*
X97458Y517575D01*
X97250Y517908D01*
X97000Y518117D01*
X96750Y518158D01*
X96458Y518075D01*
X96250Y517783D01*
X96167Y517492D01*
Y517117D01*
G01Y517492D02*
X96042Y517742D01*
X95833Y517950D01*
X95583Y518033D01*
X95333Y517950D01*
X95125Y517742D01*
X95000Y517367D01*
X95042Y516992D01*
X95208Y516617D01*
G01X91722Y526425D02*
X91930Y526758D01*
X92055Y527133D01*
Y527467D01*
X91930Y527800D01*
X91722Y528050D01*
X91430Y528175D01*
X91138Y528092D01*
X90888Y527883D01*
X90722Y527508D01*
X90638Y527008D01*
X90472Y526717D01*
X90180Y526592D01*
X89888Y526675D01*
X89680Y526883D01*
X89555Y527175D01*
Y527467D01*
X89638Y527758D01*
X89847Y528008D01*
G01X89555Y530400D02*
X92055D01*
G01X89555Y529442D02*
Y531358D01*
G01X92055Y532667D02*
X89555D01*
Y533667D01*
X89680Y534000D01*
X89972Y534250D01*
X90305Y534333D01*
X90638Y534250D01*
X90888Y534042D01*
X91013Y533667D01*
Y532667D01*
G01Y535808D02*
X90722Y536100D01*
X90555Y536350D01*
X90472Y536683D01*
X90555Y536975D01*
X90722Y537183D01*
X90972Y537350D01*
X91263Y537392D01*
X91513Y537350D01*
X91763Y537183D01*
X91972Y536933D01*
X92055Y536642D01*
X91972Y536308D01*
X91722Y536017D01*
X91347Y535850D01*
X90930Y535808D01*
X90388Y535892D01*
X90097Y536017D01*
X89805Y536225D01*
X89597Y536517D01*
X89555Y536808D01*
X89638Y537100D01*
X89847Y537308D01*
G01X92055Y539617D02*
X91513Y539700D01*
X91055Y539825D01*
X90638Y539992D01*
X90180Y540200D01*
X89555Y540533D01*
Y538867D01*
G01X99522Y526625D02*
X99730Y526958D01*
X99855Y527333D01*
Y527667D01*
X99730Y528000D01*
X99522Y528250D01*
X99230Y528375D01*
X98938Y528292D01*
X98688Y528083D01*
X98522Y527708D01*
X98438Y527208D01*
X98272Y526917D01*
X97980Y526792D01*
X97688Y526875D01*
X97480Y527083D01*
X97355Y527375D01*
Y527667D01*
X97438Y527958D01*
X97647Y528208D01*
G01X97355Y530600D02*
X99855D01*
G01X97355Y529642D02*
Y531558D01*
G01X99855Y532867D02*
X97355D01*
Y533867D01*
X97480Y534200D01*
X97772Y534450D01*
X98105Y534533D01*
X98438Y534450D01*
X98688Y534242D01*
X98813Y533867D01*
Y532867D01*
G01X99855Y536717D02*
X99313Y536800D01*
X98855Y536925D01*
X98438Y537092D01*
X97980Y537300D01*
X97355Y537633D01*
Y535967D01*
G01Y539900D02*
X97438Y539567D01*
X97647Y539317D01*
X97897Y539150D01*
X98230Y539025D01*
X98605Y538983D01*
X98980Y539025D01*
X99313Y539150D01*
X99563Y539317D01*
X99772Y539567D01*
X99855Y539900D01*
X99772Y540233D01*
X99563Y540483D01*
X99313Y540650D01*
X98980Y540775D01*
X98605Y540817D01*
X98230Y540775D01*
X97897Y540650D01*
X97647Y540483D01*
X97438Y540233D01*
X97355Y539900D01*
G01X87222Y523425D02*
X87430Y523758D01*
X87555Y524133D01*
Y524467D01*
X87430Y524800D01*
X87222Y525050D01*
X86930Y525175D01*
X86638Y525092D01*
X86388Y524883D01*
X86222Y524508D01*
X86138Y524008D01*
X85972Y523717D01*
X85680Y523592D01*
X85388Y523675D01*
X85180Y523883D01*
X85055Y524175D01*
Y524467D01*
X85138Y524758D01*
X85347Y525008D01*
G01X85055Y527400D02*
X87555D01*
G01X85055Y526442D02*
Y528358D01*
G01X87555Y529667D02*
X85055D01*
Y530667D01*
X85180Y531000D01*
X85472Y531250D01*
X85805Y531333D01*
X86138Y531250D01*
X86388Y531042D01*
X86513Y530667D01*
Y529667D01*
G01X87555Y533517D02*
X87013Y533600D01*
X86555Y533725D01*
X86138Y533892D01*
X85680Y534100D01*
X85055Y534433D01*
Y532767D01*
G01X87555Y536700D02*
X85055D01*
X85555Y536200D01*
G01X87555D02*
Y537200D01*
G01X95822Y523425D02*
X96030Y523758D01*
X96155Y524133D01*
Y524467D01*
X96030Y524800D01*
X95822Y525050D01*
X95530Y525175D01*
X95238Y525092D01*
X94988Y524883D01*
X94822Y524508D01*
X94738Y524008D01*
X94572Y523717D01*
X94280Y523592D01*
X93988Y523675D01*
X93780Y523883D01*
X93655Y524175D01*
Y524467D01*
X93738Y524758D01*
X93947Y525008D01*
G01X93655Y527400D02*
X96155D01*
G01X93655Y526442D02*
Y528358D01*
G01X96155Y529667D02*
X93655D01*
Y530667D01*
X93780Y531000D01*
X94072Y531250D01*
X94405Y531333D01*
X94738Y531250D01*
X94988Y531042D01*
X95113Y530667D01*
Y529667D01*
G01X96155Y533517D02*
X95613Y533600D01*
X95155Y533725D01*
X94738Y533892D01*
X94280Y534100D01*
X93655Y534433D01*
Y532767D01*
G01X95780Y535783D02*
X95988Y536033D01*
X96113Y536325D01*
X96155Y536700D01*
X96072Y537075D01*
X95905Y537367D01*
X95613Y537575D01*
X95280Y537617D01*
X94947Y537533D01*
X94738Y537325D01*
X94572Y537033D01*
X94530Y536742D01*
X94572Y536450D01*
X94738Y536075D01*
X93655Y536200D01*
Y537325D01*
G01X88914Y675289D02*
X89122Y675622D01*
X89247Y675997D01*
Y676331D01*
X89122Y676664D01*
X88914Y676914D01*
X88622Y677039D01*
X88330Y676956D01*
X88080Y676747D01*
X87914Y676372D01*
X87830Y675872D01*
X87664Y675581D01*
X87372Y675456D01*
X87080Y675539D01*
X86872Y675747D01*
X86747Y676039D01*
Y676331D01*
X86830Y676622D01*
X87039Y676872D01*
G01X86747Y678347D02*
X88539D01*
X88914Y678514D01*
X89164Y678847D01*
X89247Y679264D01*
X89164Y679681D01*
X88914Y680014D01*
X88539Y680181D01*
X86747D01*
G01X88205Y681572D02*
X87914Y681864D01*
X87747Y682114D01*
X87664Y682447D01*
X87747Y682739D01*
X87914Y682947D01*
X88164Y683114D01*
X88455Y683156D01*
X88705Y683114D01*
X88955Y682947D01*
X89164Y682697D01*
X89247Y682406D01*
X89164Y682072D01*
X88914Y681781D01*
X88539Y681614D01*
X88122Y681572D01*
X87580Y681656D01*
X87289Y681781D01*
X86997Y681989D01*
X86789Y682281D01*
X86747Y682572D01*
X86830Y682864D01*
X87039Y683072D01*
G01X88955Y684756D02*
X89164Y685047D01*
X89247Y685381D01*
X89164Y685714D01*
X88914Y686006D01*
X88539Y686214D01*
X88164Y686297D01*
X87705D01*
X87330Y686214D01*
X86997Y686006D01*
X86830Y685756D01*
X86747Y685464D01*
X86830Y685131D01*
X86997Y684881D01*
X87247Y684714D01*
X87580Y684631D01*
X87872Y684714D01*
X88164Y684922D01*
X88330Y685172D01*
X88372Y685464D01*
X88289Y685797D01*
X88080Y686047D01*
X87705Y686297D01*
G01X93147Y680814D02*
X91697Y679364D01*
G01Y686314D02*
Y675314D01*
G01D02*
X112297D01*
G01X91697Y682264D02*
X93147Y680814D01*
G01X112297Y686314D02*
X91697D01*
G01X98772Y719704D02*
X94772D01*
Y712304D01*
G01Y719704D02*
X90772D01*
Y712304D01*
G01X100322Y739024D02*
Y739034D01*
X98352Y741004D01*
Y741014D01*
X100322Y742984D01*
G01X97536Y757526D02*
X101536D01*
Y764926D01*
G01X87072Y772504D02*
Y768504D01*
X94472D01*
G01X94772Y765804D02*
X98772D01*
Y773204D01*
G01X84321Y783220D02*
Y785720D01*
X85362D01*
X85696Y785595D01*
X85904Y785428D01*
X85987Y785095D01*
X85904Y784762D01*
X85654Y784553D01*
X85362Y784428D01*
X84321D01*
G01X85362D02*
X85987Y783220D01*
G01X87337Y783595D02*
X87587Y783387D01*
X87879Y783262D01*
X88254Y783220D01*
X88629Y783303D01*
X88921Y783470D01*
X89129Y783762D01*
X89171Y784095D01*
X89087Y784428D01*
X88879Y784637D01*
X88587Y784803D01*
X88296Y784845D01*
X88004Y784803D01*
X87629Y784637D01*
X87754Y785720D01*
X88879D01*
G01X90562Y784262D02*
X90854Y784553D01*
X91104Y784720D01*
X91437Y784803D01*
X91729Y784720D01*
X91937Y784553D01*
X92104Y784303D01*
X92146Y784012D01*
X92104Y783762D01*
X91937Y783512D01*
X91687Y783303D01*
X91396Y783220D01*
X91062Y783303D01*
X90771Y783553D01*
X90604Y783928D01*
X90562Y784345D01*
X90646Y784887D01*
X90771Y785178D01*
X90979Y785470D01*
X91271Y785678D01*
X91562Y785720D01*
X91854Y785637D01*
X92062Y785428D01*
G01X94954Y783220D02*
Y785720D01*
X93412Y783928D01*
X95496D01*
G01X87104Y792220D02*
Y788220D01*
X94504D01*
G01X87104Y800220D02*
Y796220D01*
X94504D01*
G01X87104Y808720D02*
Y804720D01*
X94504D01*
G01X87104Y813220D02*
Y809220D01*
X94504D01*
G01X99104Y815720D02*
Y813220D01*
G01X98146Y815720D02*
X100062D01*
G01X101371Y813220D02*
Y815720D01*
X102371D01*
X102704Y815595D01*
X102954Y815303D01*
X103037Y814970D01*
X102954Y814637D01*
X102746Y814387D01*
X102371Y814262D01*
X101371D01*
G01X105304Y813220D02*
Y815720D01*
X104804Y815220D01*
G01Y813220D02*
X105804D01*
G01X107612Y814262D02*
X107904Y814553D01*
X108154Y814720D01*
X108487Y814803D01*
X108779Y814720D01*
X108987Y814553D01*
X109154Y814303D01*
X109196Y814012D01*
X109154Y813762D01*
X108987Y813512D01*
X108737Y813303D01*
X108446Y813220D01*
X108112Y813303D01*
X107821Y813553D01*
X107654Y813928D01*
X107612Y814345D01*
X107696Y814887D01*
X107821Y815178D01*
X108029Y815470D01*
X108321Y815678D01*
X108612Y815720D01*
X108904Y815637D01*
X109112Y815428D01*
G01X111504Y813220D02*
X111796Y813262D01*
X112129Y813387D01*
X112337Y813595D01*
X112421Y813887D01*
X112337Y814178D01*
X112087Y814428D01*
X111712Y814553D01*
X111296D01*
X111046Y814637D01*
X110837Y814845D01*
X110754Y815137D01*
X110879Y815428D01*
X111171Y815637D01*
X111504Y815720D01*
X111837Y815637D01*
X112129Y815428D01*
X112254Y815137D01*
X112171Y814845D01*
X111962Y814637D01*
X111712Y814553D01*
X111296D01*
X110921Y814428D01*
X110671Y814178D01*
X110587Y813887D01*
X110671Y813595D01*
X110879Y813387D01*
X111212Y813262D01*
X111504Y813220D01*
G01X94504D02*
Y817220D01*
X87104D01*
G01X90971Y821645D02*
X91179Y821978D01*
X91304Y822353D01*
Y822687D01*
X91179Y823020D01*
X90971Y823270D01*
X90679Y823395D01*
X90387Y823312D01*
X90137Y823103D01*
X89971Y822728D01*
X89887Y822228D01*
X89721Y821937D01*
X89429Y821812D01*
X89137Y821895D01*
X88929Y822103D01*
X88804Y822395D01*
Y822687D01*
X88887Y822978D01*
X89096Y823228D01*
G01X91304Y824787D02*
X88804D01*
Y825828D01*
X88929Y826162D01*
X89096Y826370D01*
X89429Y826453D01*
X89762Y826370D01*
X89971Y826120D01*
X90096Y825828D01*
Y824787D01*
G01Y825828D02*
X91304Y826453D01*
G01X90804Y827803D02*
X91096Y828053D01*
X91262Y828387D01*
X91304Y828762D01*
X91262Y829095D01*
X91054Y829428D01*
X90804Y829637D01*
X90554Y829678D01*
X90262Y829595D01*
X90054Y829303D01*
X89971Y829012D01*
Y828637D01*
G01Y829012D02*
X89846Y829262D01*
X89637Y829470D01*
X89387Y829553D01*
X89137Y829470D01*
X88929Y829262D01*
X88804Y828887D01*
X88846Y828512D01*
X89012Y828137D01*
G01X88804Y831820D02*
X88887Y831487D01*
X89096Y831237D01*
X89346Y831070D01*
X89679Y830945D01*
X90054Y830903D01*
X90429Y830945D01*
X90762Y831070D01*
X91012Y831237D01*
X91221Y831487D01*
X91304Y831820D01*
X91221Y832153D01*
X91012Y832403D01*
X90762Y832570D01*
X90429Y832695D01*
X90054Y832737D01*
X89679Y832695D01*
X89346Y832570D01*
X89096Y832403D01*
X88887Y832153D01*
X88804Y831820D01*
G01X90262Y834128D02*
X89971Y834420D01*
X89804Y834670D01*
X89721Y835003D01*
X89804Y835295D01*
X89971Y835503D01*
X90221Y835670D01*
X90512Y835712D01*
X90762Y835670D01*
X91012Y835503D01*
X91221Y835253D01*
X91304Y834962D01*
X91221Y834628D01*
X90971Y834337D01*
X90596Y834170D01*
X90179Y834128D01*
X89637Y834212D01*
X89346Y834337D01*
X89054Y834545D01*
X88846Y834837D01*
X88804Y835128D01*
X88887Y835420D01*
X89096Y835628D01*
G01X86471Y821645D02*
X86679Y821978D01*
X86804Y822353D01*
Y822687D01*
X86679Y823020D01*
X86471Y823270D01*
X86179Y823395D01*
X85887Y823312D01*
X85637Y823103D01*
X85471Y822728D01*
X85387Y822228D01*
X85221Y821937D01*
X84929Y821812D01*
X84637Y821895D01*
X84429Y822103D01*
X84304Y822395D01*
Y822687D01*
X84387Y822978D01*
X84596Y823228D01*
G01X86804Y824787D02*
X84304D01*
Y825828D01*
X84429Y826162D01*
X84596Y826370D01*
X84929Y826453D01*
X85262Y826370D01*
X85471Y826120D01*
X85596Y825828D01*
Y824787D01*
G01Y825828D02*
X86804Y826453D01*
G01X84721Y827928D02*
X84471Y828178D01*
X84346Y828470D01*
X84304Y828803D01*
X84387Y829220D01*
X84596Y829512D01*
X84846Y829595D01*
X85096Y829553D01*
X85304Y829387D01*
X85721Y828553D01*
X86012Y828178D01*
X86429Y827928D01*
X86804Y827845D01*
Y829595D01*
G01X85762Y831028D02*
X85471Y831320D01*
X85304Y831570D01*
X85221Y831903D01*
X85304Y832195D01*
X85471Y832403D01*
X85721Y832570D01*
X86012Y832612D01*
X86262Y832570D01*
X86512Y832403D01*
X86721Y832153D01*
X86804Y831862D01*
X86721Y831528D01*
X86471Y831237D01*
X86096Y831070D01*
X85679Y831028D01*
X85137Y831112D01*
X84846Y831237D01*
X84554Y831445D01*
X84346Y831737D01*
X84304Y832028D01*
X84387Y832320D01*
X84596Y832528D01*
G01X86304Y834003D02*
X86596Y834253D01*
X86762Y834587D01*
X86804Y834962D01*
X86762Y835295D01*
X86554Y835628D01*
X86304Y835837D01*
X86054Y835878D01*
X85762Y835795D01*
X85554Y835503D01*
X85471Y835212D01*
Y834837D01*
G01Y835212D02*
X85346Y835462D01*
X85137Y835670D01*
X84887Y835753D01*
X84637Y835670D01*
X84429Y835462D01*
X84304Y835087D01*
X84346Y834712D01*
X84512Y834337D01*
G01X99804Y821737D02*
X97304D01*
Y822778D01*
X97429Y823112D01*
X97596Y823320D01*
X97929Y823403D01*
X98262Y823320D01*
X98471Y823070D01*
X98596Y822778D01*
Y821737D01*
G01Y822778D02*
X99804Y823403D01*
G01X98762Y824878D02*
X98471Y825170D01*
X98304Y825420D01*
X98221Y825753D01*
X98304Y826045D01*
X98471Y826253D01*
X98721Y826420D01*
X99012Y826462D01*
X99262Y826420D01*
X99512Y826253D01*
X99721Y826003D01*
X99804Y825712D01*
X99721Y825378D01*
X99471Y825087D01*
X99096Y824920D01*
X98679Y824878D01*
X98137Y824962D01*
X97846Y825087D01*
X97554Y825295D01*
X97346Y825587D01*
X97304Y825878D01*
X97387Y826170D01*
X97596Y826378D01*
G01X99304Y827853D02*
X99596Y828103D01*
X99762Y828437D01*
X99804Y828812D01*
X99762Y829145D01*
X99554Y829478D01*
X99304Y829687D01*
X99054Y829728D01*
X98762Y829645D01*
X98554Y829353D01*
X98471Y829062D01*
Y828687D01*
G01Y829062D02*
X98346Y829312D01*
X98137Y829520D01*
X97887Y829603D01*
X97637Y829520D01*
X97429Y829312D01*
X97304Y828937D01*
X97346Y828562D01*
X97512Y828187D01*
G01X97721Y831078D02*
X97471Y831328D01*
X97346Y831620D01*
X97304Y831953D01*
X97387Y832370D01*
X97596Y832662D01*
X97846Y832745D01*
X98096Y832703D01*
X98304Y832537D01*
X98721Y831703D01*
X99012Y831328D01*
X99429Y831078D01*
X99804Y830995D01*
Y832745D01*
G01X95304Y821737D02*
X92804D01*
Y822778D01*
X92929Y823112D01*
X93096Y823320D01*
X93429Y823403D01*
X93762Y823320D01*
X93971Y823070D01*
X94096Y822778D01*
Y821737D01*
G01Y822778D02*
X95304Y823403D01*
G01X94262Y824878D02*
X93971Y825170D01*
X93804Y825420D01*
X93721Y825753D01*
X93804Y826045D01*
X93971Y826253D01*
X94221Y826420D01*
X94512Y826462D01*
X94762Y826420D01*
X95012Y826253D01*
X95221Y826003D01*
X95304Y825712D01*
X95221Y825378D01*
X94971Y825087D01*
X94596Y824920D01*
X94179Y824878D01*
X93637Y824962D01*
X93346Y825087D01*
X93054Y825295D01*
X92846Y825587D01*
X92804Y825878D01*
X92887Y826170D01*
X93096Y826378D01*
G01X94804Y827853D02*
X95096Y828103D01*
X95262Y828437D01*
X95304Y828812D01*
X95262Y829145D01*
X95054Y829478D01*
X94804Y829687D01*
X94554Y829728D01*
X94262Y829645D01*
X94054Y829353D01*
X93971Y829062D01*
Y828687D01*
G01Y829062D02*
X93846Y829312D01*
X93637Y829520D01*
X93387Y829603D01*
X93137Y829520D01*
X92929Y829312D01*
X92804Y828937D01*
X92846Y828562D01*
X93012Y828187D01*
G01X94804Y830953D02*
X95096Y831203D01*
X95262Y831537D01*
X95304Y831912D01*
X95262Y832245D01*
X95054Y832578D01*
X94804Y832787D01*
X94554Y832828D01*
X94262Y832745D01*
X94054Y832453D01*
X93971Y832162D01*
Y831787D01*
G01Y832162D02*
X93846Y832412D01*
X93637Y832620D01*
X93387Y832703D01*
X93137Y832620D01*
X92929Y832412D01*
X92804Y832037D01*
X92846Y831662D01*
X93012Y831287D01*
G01X90304Y838020D02*
X94304D01*
Y845420D01*
G01X89804D02*
X85804D01*
Y838020D01*
G01X106504Y842220D02*
Y846220D01*
X99104D01*
G01X104504Y880720D02*
Y884720D01*
X97104D01*
G01X91971Y892645D02*
X92179Y892978D01*
X92304Y893353D01*
Y893687D01*
X92179Y894020D01*
X91971Y894270D01*
X91679Y894395D01*
X91387Y894312D01*
X91137Y894103D01*
X90971Y893728D01*
X90887Y893228D01*
X90721Y892937D01*
X90429Y892812D01*
X90137Y892895D01*
X89929Y893103D01*
X89804Y893395D01*
Y893687D01*
X89887Y893978D01*
X90096Y894228D01*
G01X90012Y897537D02*
X89887Y897287D01*
X89804Y896995D01*
Y896662D01*
X89929Y896287D01*
X90137Y895995D01*
X90387Y895787D01*
X90804Y895620D01*
X91179Y895578D01*
X91554Y895662D01*
X91804Y895787D01*
X92054Y896037D01*
X92221Y896328D01*
X92304Y896620D01*
Y896912D01*
X92221Y897203D01*
X92096Y897453D01*
X91929Y897662D01*
G01X92304Y900220D02*
X89804D01*
X91596Y898678D01*
Y900762D01*
G01X90221Y902028D02*
X89971Y902278D01*
X89846Y902570D01*
X89804Y902903D01*
X89887Y903320D01*
X90096Y903612D01*
X90346Y903695D01*
X90596Y903653D01*
X90804Y903487D01*
X91221Y902653D01*
X91512Y902278D01*
X91929Y902028D01*
X92304Y901945D01*
Y903695D01*
G01X92012Y905212D02*
X92221Y905503D01*
X92304Y905837D01*
X92221Y906170D01*
X91971Y906462D01*
X91596Y906670D01*
X91221Y906753D01*
X90762D01*
X90387Y906670D01*
X90054Y906462D01*
X89887Y906212D01*
X89804Y905920D01*
X89887Y905587D01*
X90054Y905337D01*
X90304Y905170D01*
X90637Y905087D01*
X90929Y905170D01*
X91221Y905378D01*
X91387Y905628D01*
X91429Y905920D01*
X91346Y906253D01*
X91137Y906503D01*
X90762Y906753D01*
G01X100104Y910020D02*
Y913420D01*
G01Y910020D02*
Y905520D01*
G01X101804Y911720D02*
X100104Y910020D01*
G01X131904Y905520D02*
X100104D01*
G01Y913420D02*
X101804Y911720D01*
G01X100104Y917920D02*
X131904D01*
G01X100104Y913420D02*
Y917920D01*
G01X102876Y-22428D02*
X102476Y-22028D01*
X102276Y-21561D01*
X102209Y-21028D01*
X102342Y-20361D01*
X102676Y-19894D01*
X103076Y-19761D01*
X103476Y-19828D01*
X103809Y-20094D01*
X104476Y-21428D01*
X104942Y-22028D01*
X105609Y-22428D01*
X106209Y-22561D01*
Y-19761D01*
G01X113154Y259470D02*
X115654D01*
Y261136D01*
G01Y264236D02*
Y262570D01*
X113154D01*
Y264236D01*
G01X114362Y263570D02*
Y262570D01*
G01X115654Y265586D02*
X113154D01*
Y266420D01*
X113279Y266753D01*
X113446Y267003D01*
X113696Y267211D01*
X113987Y267378D01*
X114404Y267420D01*
X114821Y267378D01*
X115112Y267211D01*
X115362Y267003D01*
X115529Y266753D01*
X115654Y266420D01*
Y265586D01*
G01Y269520D02*
X115112Y269603D01*
X114654Y269728D01*
X114237Y269895D01*
X113779Y270103D01*
X113154Y270436D01*
Y268770D01*
G01X107705Y273428D02*
Y307086D01*
G01X118154Y292403D02*
X118112Y292070D01*
X117946Y291778D01*
X117696Y291528D01*
X117404Y291361D01*
X117071Y291278D01*
X116737D01*
X116404Y291361D01*
X116112Y291528D01*
X115862Y291778D01*
X115696Y292070D01*
X115654Y292403D01*
X115696Y292736D01*
X115862Y293028D01*
X116112Y293278D01*
X116404Y293445D01*
X116737Y293528D01*
X117071D01*
X117404Y293445D01*
X117696Y293278D01*
X117946Y293028D01*
X118112Y292736D01*
X118154Y292403D01*
G01X117487Y292736D02*
X118154Y293236D01*
G01X117779Y294586D02*
X117987Y294836D01*
X118112Y295128D01*
X118154Y295503D01*
X118071Y295878D01*
X117904Y296170D01*
X117612Y296378D01*
X117279Y296420D01*
X116946Y296336D01*
X116737Y296128D01*
X116571Y295836D01*
X116529Y295545D01*
X116571Y295253D01*
X116737Y294878D01*
X115654Y295003D01*
Y296128D01*
G01X111154Y298453D02*
X124154D01*
G01X111154Y312453D02*
Y298453D01*
G01X124154Y312453D02*
X111154D01*
G01X121854Y314453D02*
Y318453D01*
X114454D01*
G01X112671Y332453D02*
Y334953D01*
X113712D01*
X114046Y334828D01*
X114254Y334661D01*
X114337Y334328D01*
X114254Y333995D01*
X114004Y333786D01*
X113712Y333661D01*
X112671D01*
G01X113712D02*
X114337Y332453D01*
G01X115812Y333495D02*
X116104Y333786D01*
X116354Y333953D01*
X116687Y334036D01*
X116979Y333953D01*
X117187Y333786D01*
X117354Y333536D01*
X117396Y333245D01*
X117354Y332995D01*
X117187Y332745D01*
X116937Y332536D01*
X116646Y332453D01*
X116312Y332536D01*
X116021Y332786D01*
X115854Y333161D01*
X115812Y333578D01*
X115896Y334120D01*
X116021Y334411D01*
X116229Y334703D01*
X116521Y334911D01*
X116812Y334953D01*
X117104Y334870D01*
X117312Y334661D01*
G01X119621Y332453D02*
X119704Y332995D01*
X119829Y333453D01*
X119996Y333870D01*
X120204Y334328D01*
X120537Y334953D01*
X118871D01*
G01X122804Y332453D02*
X123096Y332495D01*
X123429Y332620D01*
X123637Y332828D01*
X123721Y333120D01*
X123637Y333411D01*
X123387Y333661D01*
X123012Y333786D01*
X122596D01*
X122346Y333870D01*
X122137Y334078D01*
X122054Y334370D01*
X122179Y334661D01*
X122471Y334870D01*
X122804Y334953D01*
X123137Y334870D01*
X123429Y334661D01*
X123554Y334370D01*
X123471Y334078D01*
X123262Y333870D01*
X123012Y333786D01*
X122596D01*
X122221Y333661D01*
X121971Y333411D01*
X121887Y333120D01*
X121971Y332828D01*
X122179Y332620D01*
X122512Y332495D01*
X122804Y332453D01*
G01X121854Y318953D02*
Y322953D01*
X114454D01*
G01X112671Y336953D02*
Y339453D01*
X113712D01*
X114046Y339328D01*
X114254Y339161D01*
X114337Y338828D01*
X114254Y338495D01*
X114004Y338286D01*
X113712Y338161D01*
X112671D01*
G01X113712D02*
X114337Y336953D01*
G01X115812Y337995D02*
X116104Y338286D01*
X116354Y338453D01*
X116687Y338536D01*
X116979Y338453D01*
X117187Y338286D01*
X117354Y338036D01*
X117396Y337745D01*
X117354Y337495D01*
X117187Y337245D01*
X116937Y337036D01*
X116646Y336953D01*
X116312Y337036D01*
X116021Y337286D01*
X115854Y337661D01*
X115812Y338078D01*
X115896Y338620D01*
X116021Y338911D01*
X116229Y339203D01*
X116521Y339411D01*
X116812Y339453D01*
X117104Y339370D01*
X117312Y339161D01*
G01X119621Y336953D02*
X119704Y337495D01*
X119829Y337953D01*
X119996Y338370D01*
X120204Y338828D01*
X120537Y339453D01*
X118871D01*
G01X121887Y337328D02*
X122137Y337120D01*
X122429Y336995D01*
X122804Y336953D01*
X123179Y337036D01*
X123471Y337203D01*
X123679Y337495D01*
X123721Y337828D01*
X123637Y338161D01*
X123429Y338370D01*
X123137Y338536D01*
X122846Y338578D01*
X122554Y338536D01*
X122179Y338370D01*
X122304Y339453D01*
X123429D01*
G01X116725Y466133D02*
X117058Y465925D01*
X117433Y465800D01*
X117767D01*
X118100Y465925D01*
X118350Y466133D01*
X118475Y466425D01*
X118392Y466717D01*
X118183Y466967D01*
X117808Y467133D01*
X117308Y467217D01*
X117017Y467383D01*
X116892Y467675D01*
X116975Y467967D01*
X117183Y468175D01*
X117475Y468300D01*
X117767D01*
X118058Y468217D01*
X118308Y468008D01*
G01X119867Y465800D02*
Y468300D01*
X120908D01*
X121242Y468175D01*
X121450Y468008D01*
X121533Y467675D01*
X121450Y467342D01*
X121200Y467133D01*
X120908Y467008D01*
X119867D01*
G01X120908D02*
X121533Y465800D01*
G01X123092Y466092D02*
X123383Y465883D01*
X123717Y465800D01*
X124050Y465883D01*
X124342Y466133D01*
X124550Y466508D01*
X124633Y466883D01*
Y467342D01*
X124550Y467717D01*
X124342Y468050D01*
X124092Y468217D01*
X123800Y468300D01*
X123467Y468217D01*
X123217Y468050D01*
X123050Y467800D01*
X122967Y467467D01*
X123050Y467175D01*
X123258Y466883D01*
X123508Y466717D01*
X123800Y466675D01*
X124133Y466758D01*
X124383Y466967D01*
X124633Y467342D01*
G01X125983Y466300D02*
X126233Y466008D01*
X126567Y465842D01*
X126942Y465800D01*
X127275Y465842D01*
X127608Y466050D01*
X127817Y466300D01*
X127858Y466550D01*
X127775Y466842D01*
X127483Y467050D01*
X127192Y467133D01*
X126817D01*
G01X127192D02*
X127442Y467258D01*
X127650Y467467D01*
X127733Y467717D01*
X127650Y467967D01*
X127442Y468175D01*
X127067Y468300D01*
X126692Y468258D01*
X126317Y468092D01*
G01X130000Y465800D02*
X130292Y465842D01*
X130625Y465967D01*
X130833Y466175D01*
X130917Y466467D01*
X130833Y466758D01*
X130583Y467008D01*
X130208Y467133D01*
X129792D01*
X129542Y467217D01*
X129333Y467425D01*
X129250Y467717D01*
X129375Y468008D01*
X129667Y468217D01*
X130000Y468300D01*
X130333Y468217D01*
X130625Y468008D01*
X130750Y467717D01*
X130667Y467425D01*
X130458Y467217D01*
X130208Y467133D01*
X129792D01*
X129417Y467008D01*
X129167Y466758D01*
X129083Y466467D01*
X129167Y466175D01*
X129375Y465967D01*
X129708Y465842D01*
X130000Y465800D01*
G01X105167Y486500D02*
X108500Y493500D01*
X111833Y486500D01*
G01X110633Y488950D02*
X106367D01*
G01X107667Y501375D02*
X107875Y501708D01*
X108000Y502083D01*
Y502417D01*
X107875Y502750D01*
X107667Y503000D01*
X107375Y503125D01*
X107083Y503042D01*
X106833Y502833D01*
X106667Y502458D01*
X106583Y501958D01*
X106417Y501667D01*
X106125Y501542D01*
X105833Y501625D01*
X105625Y501833D01*
X105500Y502125D01*
Y502417D01*
X105583Y502708D01*
X105792Y502958D01*
G01X105500Y505350D02*
X108000D01*
G01X105500Y504392D02*
Y506308D01*
G01X108000Y507617D02*
X105500D01*
Y508617D01*
X105625Y508950D01*
X105917Y509200D01*
X106250Y509283D01*
X106583Y509200D01*
X106833Y508992D01*
X106958Y508617D01*
Y507617D01*
G01X108000Y511550D02*
X105500D01*
X106000Y511050D01*
G01X108000D02*
Y512050D01*
G01X105500Y514650D02*
X105583Y514317D01*
X105792Y514067D01*
X106042Y513900D01*
X106375Y513775D01*
X106750Y513733D01*
X107125Y513775D01*
X107458Y513900D01*
X107708Y514067D01*
X107917Y514317D01*
X108000Y514650D01*
X107917Y514983D01*
X107708Y515233D01*
X107458Y515400D01*
X107125Y515525D01*
X106750Y515567D01*
X106375Y515525D01*
X106042Y515400D01*
X105792Y515233D01*
X105583Y514983D01*
X105500Y514650D01*
G01X108000Y518250D02*
X105500D01*
X107292Y516708D01*
Y518792D01*
G01X104222Y524375D02*
X104430Y524708D01*
X104555Y525083D01*
Y525417D01*
X104430Y525750D01*
X104222Y526000D01*
X103930Y526125D01*
X103638Y526042D01*
X103388Y525833D01*
X103222Y525458D01*
X103138Y524958D01*
X102972Y524667D01*
X102680Y524542D01*
X102388Y524625D01*
X102180Y524833D01*
X102055Y525125D01*
Y525417D01*
X102138Y525708D01*
X102347Y525958D01*
G01X102055Y528350D02*
X104555D01*
G01X102055Y527392D02*
Y529308D01*
G01X104555Y530617D02*
X102055D01*
Y531617D01*
X102180Y531950D01*
X102472Y532200D01*
X102805Y532283D01*
X103138Y532200D01*
X103388Y531992D01*
X103513Y531617D01*
Y530617D01*
G01X104555Y534550D02*
X102055D01*
X102555Y534050D01*
G01X104555D02*
Y535050D01*
G01X102055Y537650D02*
X102138Y537317D01*
X102347Y537067D01*
X102597Y536900D01*
X102930Y536775D01*
X103305Y536733D01*
X103680Y536775D01*
X104013Y536900D01*
X104263Y537067D01*
X104472Y537317D01*
X104555Y537650D01*
X104472Y537983D01*
X104263Y538233D01*
X104013Y538400D01*
X103680Y538525D01*
X103305Y538567D01*
X102930Y538525D01*
X102597Y538400D01*
X102347Y538233D01*
X102138Y537983D01*
X102055Y537650D01*
G01X103513Y539958D02*
X103222Y540250D01*
X103055Y540500D01*
X102972Y540833D01*
X103055Y541125D01*
X103222Y541333D01*
X103472Y541500D01*
X103763Y541542D01*
X104013Y541500D01*
X104263Y541333D01*
X104472Y541083D01*
X104555Y540792D01*
X104472Y540458D01*
X104222Y540167D01*
X103847Y540000D01*
X103430Y539958D01*
X102888Y540042D01*
X102597Y540167D01*
X102305Y540375D01*
X102097Y540667D01*
X102055Y540958D01*
X102138Y541250D01*
X102347Y541458D01*
G01X109222Y523875D02*
X109430Y524208D01*
X109555Y524583D01*
Y524917D01*
X109430Y525250D01*
X109222Y525500D01*
X108930Y525625D01*
X108638Y525542D01*
X108388Y525333D01*
X108222Y524958D01*
X108138Y524458D01*
X107972Y524167D01*
X107680Y524042D01*
X107388Y524125D01*
X107180Y524333D01*
X107055Y524625D01*
Y524917D01*
X107138Y525208D01*
X107347Y525458D01*
G01X107055Y527850D02*
X109555D01*
G01X107055Y526892D02*
Y528808D01*
G01X109555Y530117D02*
X107055D01*
Y531117D01*
X107180Y531450D01*
X107472Y531700D01*
X107805Y531783D01*
X108138Y531700D01*
X108388Y531492D01*
X108513Y531117D01*
Y530117D01*
G01X109555Y534050D02*
X107055D01*
X107555Y533550D01*
G01X109555D02*
Y534550D01*
G01X107055Y537150D02*
X107138Y536817D01*
X107347Y536567D01*
X107597Y536400D01*
X107930Y536275D01*
X108305Y536233D01*
X108680Y536275D01*
X109013Y536400D01*
X109263Y536567D01*
X109472Y536817D01*
X109555Y537150D01*
X109472Y537483D01*
X109263Y537733D01*
X109013Y537900D01*
X108680Y538025D01*
X108305Y538067D01*
X107930Y538025D01*
X107597Y537900D01*
X107347Y537733D01*
X107138Y537483D01*
X107055Y537150D01*
G01X109263Y539542D02*
X109472Y539833D01*
X109555Y540167D01*
X109472Y540500D01*
X109222Y540792D01*
X108847Y541000D01*
X108472Y541083D01*
X108013D01*
X107638Y541000D01*
X107305Y540792D01*
X107138Y540542D01*
X107055Y540250D01*
X107138Y539917D01*
X107305Y539667D01*
X107555Y539500D01*
X107888Y539417D01*
X108180Y539500D01*
X108472Y539708D01*
X108638Y539958D01*
X108680Y540250D01*
X108597Y540583D01*
X108388Y540833D01*
X108013Y541083D01*
G01X113722Y526875D02*
X113930Y527208D01*
X114055Y527583D01*
Y527917D01*
X113930Y528250D01*
X113722Y528500D01*
X113430Y528625D01*
X113138Y528542D01*
X112888Y528333D01*
X112722Y527958D01*
X112638Y527458D01*
X112472Y527167D01*
X112180Y527042D01*
X111888Y527125D01*
X111680Y527333D01*
X111555Y527625D01*
Y527917D01*
X111638Y528208D01*
X111847Y528458D01*
G01X111555Y530850D02*
X114055D01*
G01X111555Y529892D02*
Y531808D01*
G01X114055Y533117D02*
X111555D01*
Y534117D01*
X111680Y534450D01*
X111972Y534700D01*
X112305Y534783D01*
X112638Y534700D01*
X112888Y534492D01*
X113013Y534117D01*
Y533117D01*
G01X114055Y537050D02*
X111555D01*
X112055Y536550D01*
G01X114055D02*
Y537550D01*
G01Y540150D02*
X111555D01*
X112055Y539650D01*
G01X114055D02*
Y540650D01*
G01X111555Y543250D02*
X111638Y542917D01*
X111847Y542667D01*
X112097Y542500D01*
X112430Y542375D01*
X112805Y542333D01*
X113180Y542375D01*
X113513Y542500D01*
X113763Y542667D01*
X113972Y542917D01*
X114055Y543250D01*
X113972Y543583D01*
X113763Y543833D01*
X113513Y544000D01*
X113180Y544125D01*
X112805Y544167D01*
X112430Y544125D01*
X112097Y544000D01*
X111847Y543833D01*
X111638Y543583D01*
X111555Y543250D01*
G01X118222Y523875D02*
X118430Y524208D01*
X118555Y524583D01*
Y524917D01*
X118430Y525250D01*
X118222Y525500D01*
X117930Y525625D01*
X117638Y525542D01*
X117388Y525333D01*
X117222Y524958D01*
X117138Y524458D01*
X116972Y524167D01*
X116680Y524042D01*
X116388Y524125D01*
X116180Y524333D01*
X116055Y524625D01*
Y524917D01*
X116138Y525208D01*
X116347Y525458D01*
G01X116055Y527850D02*
X118555D01*
G01X116055Y526892D02*
Y528808D01*
G01X118555Y530117D02*
X116055D01*
Y531117D01*
X116180Y531450D01*
X116472Y531700D01*
X116805Y531783D01*
X117138Y531700D01*
X117388Y531492D01*
X117513Y531117D01*
Y530117D01*
G01X118555Y534050D02*
X116055D01*
X116555Y533550D01*
G01X118555D02*
Y534550D01*
G01Y537150D02*
X116055D01*
X116555Y536650D01*
G01X118555D02*
Y537650D01*
G01X118055Y539333D02*
X118347Y539583D01*
X118513Y539917D01*
X118555Y540292D01*
X118513Y540625D01*
X118305Y540958D01*
X118055Y541167D01*
X117805Y541208D01*
X117513Y541125D01*
X117305Y540833D01*
X117222Y540542D01*
Y540167D01*
G01Y540542D02*
X117097Y540792D01*
X116888Y541000D01*
X116638Y541083D01*
X116388Y541000D01*
X116180Y540792D01*
X116055Y540417D01*
X116097Y540042D01*
X116263Y539667D01*
G01X112297Y675314D02*
Y686314D01*
G01X108971Y708645D02*
X109179Y708978D01*
X109304Y709353D01*
Y709687D01*
X109179Y710020D01*
X108971Y710270D01*
X108679Y710395D01*
X108387Y710312D01*
X108137Y710103D01*
X107971Y709728D01*
X107887Y709228D01*
X107721Y708937D01*
X107429Y708812D01*
X107137Y708895D01*
X106929Y709103D01*
X106804Y709395D01*
Y709687D01*
X106887Y709978D01*
X107096Y710228D01*
G01X109304Y711787D02*
X106804D01*
Y712828D01*
X106929Y713162D01*
X107096Y713370D01*
X107429Y713453D01*
X107762Y713370D01*
X107971Y713120D01*
X108096Y712828D01*
Y711787D01*
G01Y712828D02*
X109304Y713453D01*
G01X108804Y714803D02*
X109096Y715053D01*
X109262Y715387D01*
X109304Y715762D01*
X109262Y716095D01*
X109054Y716428D01*
X108804Y716637D01*
X108554Y716678D01*
X108262Y716595D01*
X108054Y716303D01*
X107971Y716012D01*
Y715637D01*
G01Y716012D02*
X107846Y716262D01*
X107637Y716470D01*
X107387Y716553D01*
X107137Y716470D01*
X106929Y716262D01*
X106804Y715887D01*
X106846Y715512D01*
X107012Y715137D01*
G01X106804Y718820D02*
X106887Y718487D01*
X107096Y718237D01*
X107346Y718070D01*
X107679Y717945D01*
X108054Y717903D01*
X108429Y717945D01*
X108762Y718070D01*
X109012Y718237D01*
X109221Y718487D01*
X109304Y718820D01*
X109221Y719153D01*
X109012Y719403D01*
X108762Y719570D01*
X108429Y719695D01*
X108054Y719737D01*
X107679Y719695D01*
X107346Y719570D01*
X107096Y719403D01*
X106887Y719153D01*
X106804Y718820D01*
G01X109304Y722420D02*
X106804D01*
X108596Y720878D01*
Y722962D01*
G01X104439Y708929D02*
X104647Y709262D01*
X104772Y709637D01*
Y709971D01*
X104647Y710304D01*
X104439Y710554D01*
X104147Y710679D01*
X103855Y710596D01*
X103605Y710387D01*
X103439Y710012D01*
X103355Y709512D01*
X103189Y709221D01*
X102897Y709096D01*
X102605Y709179D01*
X102397Y709387D01*
X102272Y709679D01*
Y709971D01*
X102355Y710262D01*
X102564Y710512D01*
G01X104772Y712071D02*
X102272D01*
Y713112D01*
X102397Y713446D01*
X102564Y713654D01*
X102897Y713737D01*
X103230Y713654D01*
X103439Y713404D01*
X103564Y713112D01*
Y712071D01*
G01Y713112D02*
X104772Y713737D01*
G01X104272Y715087D02*
X104564Y715337D01*
X104730Y715671D01*
X104772Y716046D01*
X104730Y716379D01*
X104522Y716712D01*
X104272Y716921D01*
X104022Y716962D01*
X103730Y716879D01*
X103522Y716587D01*
X103439Y716296D01*
Y715921D01*
G01Y716296D02*
X103314Y716546D01*
X103105Y716754D01*
X102855Y716837D01*
X102605Y716754D01*
X102397Y716546D01*
X102272Y716171D01*
X102314Y715796D01*
X102480Y715421D01*
G01X104772Y719104D02*
X102272D01*
X102772Y718604D01*
G01X104772D02*
Y719604D01*
G01X104272Y721287D02*
X104564Y721537D01*
X104730Y721871D01*
X104772Y722246D01*
X104730Y722579D01*
X104522Y722912D01*
X104272Y723121D01*
X104022Y723162D01*
X103730Y723079D01*
X103522Y722787D01*
X103439Y722496D01*
Y722121D01*
G01Y722496D02*
X103314Y722746D01*
X103105Y722954D01*
X102855Y723037D01*
X102605Y722954D01*
X102397Y722746D01*
X102272Y722371D01*
X102314Y721996D01*
X102480Y721621D01*
G01X115804Y752737D02*
X113304D01*
Y753778D01*
X113429Y754112D01*
X113596Y754320D01*
X113929Y754403D01*
X114262Y754320D01*
X114471Y754070D01*
X114596Y753778D01*
Y752737D01*
G01Y753778D02*
X115804Y754403D01*
G01X114762Y755878D02*
X114471Y756170D01*
X114304Y756420D01*
X114221Y756753D01*
X114304Y757045D01*
X114471Y757253D01*
X114721Y757420D01*
X115012Y757462D01*
X115262Y757420D01*
X115512Y757253D01*
X115721Y757003D01*
X115804Y756712D01*
X115721Y756378D01*
X115471Y756087D01*
X115096Y755920D01*
X114679Y755878D01*
X114137Y755962D01*
X113846Y756087D01*
X113554Y756295D01*
X113346Y756587D01*
X113304Y756878D01*
X113387Y757170D01*
X113596Y757378D01*
G01X115429Y758853D02*
X115637Y759103D01*
X115762Y759395D01*
X115804Y759770D01*
X115721Y760145D01*
X115554Y760437D01*
X115262Y760645D01*
X114929Y760687D01*
X114596Y760603D01*
X114387Y760395D01*
X114221Y760103D01*
X114179Y759812D01*
X114221Y759520D01*
X114387Y759145D01*
X113304Y759270D01*
Y760395D01*
G01X115804Y762870D02*
X113304D01*
X113804Y762370D01*
G01X115804D02*
Y763370D01*
G01X105804Y764920D02*
X101804D01*
Y757520D01*
G01X111536Y752743D02*
X109036D01*
Y753784D01*
X109161Y754118D01*
X109328Y754326D01*
X109661Y754409D01*
X109994Y754326D01*
X110203Y754076D01*
X110328Y753784D01*
Y752743D01*
G01Y753784D02*
X111536Y754409D01*
G01X110494Y755884D02*
X110203Y756176D01*
X110036Y756426D01*
X109953Y756759D01*
X110036Y757051D01*
X110203Y757259D01*
X110453Y757426D01*
X110744Y757468D01*
X110994Y757426D01*
X111244Y757259D01*
X111453Y757009D01*
X111536Y756718D01*
X111453Y756384D01*
X111203Y756093D01*
X110828Y755926D01*
X110411Y755884D01*
X109869Y755968D01*
X109578Y756093D01*
X109286Y756301D01*
X109078Y756593D01*
X109036Y756884D01*
X109119Y757176D01*
X109328Y757384D01*
G01X111161Y758859D02*
X111369Y759109D01*
X111494Y759401D01*
X111536Y759776D01*
X111453Y760151D01*
X111286Y760443D01*
X110994Y760651D01*
X110661Y760693D01*
X110328Y760609D01*
X110119Y760401D01*
X109953Y760109D01*
X109911Y759818D01*
X109953Y759526D01*
X110119Y759151D01*
X109036Y759276D01*
Y760401D01*
G01X109453Y762084D02*
X109203Y762334D01*
X109078Y762626D01*
X109036Y762959D01*
X109119Y763376D01*
X109328Y763668D01*
X109578Y763751D01*
X109828Y763709D01*
X110036Y763543D01*
X110453Y762709D01*
X110744Y762334D01*
X111161Y762084D01*
X111536Y762001D01*
Y763751D01*
G01X108471Y766645D02*
X108679Y766978D01*
X108804Y767353D01*
Y767687D01*
X108679Y768020D01*
X108471Y768270D01*
X108179Y768395D01*
X107887Y768312D01*
X107637Y768103D01*
X107471Y767728D01*
X107387Y767228D01*
X107221Y766937D01*
X106929Y766812D01*
X106637Y766895D01*
X106429Y767103D01*
X106304Y767395D01*
Y767687D01*
X106387Y767978D01*
X106596Y768228D01*
G01X108804Y769787D02*
X106304D01*
Y770828D01*
X106429Y771162D01*
X106596Y771370D01*
X106929Y771453D01*
X107262Y771370D01*
X107471Y771120D01*
X107596Y770828D01*
Y769787D01*
G01Y770828D02*
X108804Y771453D01*
G01X108304Y772803D02*
X108596Y773053D01*
X108762Y773387D01*
X108804Y773762D01*
X108762Y774095D01*
X108554Y774428D01*
X108304Y774637D01*
X108054Y774678D01*
X107762Y774595D01*
X107554Y774303D01*
X107471Y774012D01*
Y773637D01*
G01Y774012D02*
X107346Y774262D01*
X107137Y774470D01*
X106887Y774553D01*
X106637Y774470D01*
X106429Y774262D01*
X106304Y773887D01*
X106346Y773512D01*
X106512Y773137D01*
G01X106304Y776820D02*
X106387Y776487D01*
X106596Y776237D01*
X106846Y776070D01*
X107179Y775945D01*
X107554Y775903D01*
X107929Y775945D01*
X108262Y776070D01*
X108512Y776237D01*
X108721Y776487D01*
X108804Y776820D01*
X108721Y777153D01*
X108512Y777403D01*
X108262Y777570D01*
X107929Y777695D01*
X107554Y777737D01*
X107179Y777695D01*
X106846Y777570D01*
X106596Y777403D01*
X106387Y777153D01*
X106304Y776820D01*
G01X108512Y779212D02*
X108721Y779503D01*
X108804Y779837D01*
X108721Y780170D01*
X108471Y780462D01*
X108096Y780670D01*
X107721Y780753D01*
X107262D01*
X106887Y780670D01*
X106554Y780462D01*
X106387Y780212D01*
X106304Y779920D01*
X106387Y779587D01*
X106554Y779337D01*
X106804Y779170D01*
X107137Y779087D01*
X107429Y779170D01*
X107721Y779378D01*
X107887Y779628D01*
X107929Y779920D01*
X107846Y780253D01*
X107637Y780503D01*
X107262Y780753D01*
G01X112939Y766429D02*
X113147Y766762D01*
X113272Y767137D01*
Y767471D01*
X113147Y767804D01*
X112939Y768054D01*
X112647Y768179D01*
X112355Y768096D01*
X112105Y767887D01*
X111939Y767512D01*
X111855Y767012D01*
X111689Y766721D01*
X111397Y766596D01*
X111105Y766679D01*
X110897Y766887D01*
X110772Y767179D01*
Y767471D01*
X110855Y767762D01*
X111064Y768012D01*
G01X113272Y769571D02*
X110772D01*
Y770612D01*
X110897Y770946D01*
X111064Y771154D01*
X111397Y771237D01*
X111730Y771154D01*
X111939Y770904D01*
X112064Y770612D01*
Y769571D01*
G01Y770612D02*
X113272Y771237D01*
G01X111189Y772712D02*
X110939Y772962D01*
X110814Y773254D01*
X110772Y773587D01*
X110855Y774004D01*
X111064Y774296D01*
X111314Y774379D01*
X111564Y774337D01*
X111772Y774171D01*
X112189Y773337D01*
X112480Y772962D01*
X112897Y772712D01*
X113272Y772629D01*
Y774379D01*
G01X112230Y775812D02*
X111939Y776104D01*
X111772Y776354D01*
X111689Y776687D01*
X111772Y776979D01*
X111939Y777187D01*
X112189Y777354D01*
X112480Y777396D01*
X112730Y777354D01*
X112980Y777187D01*
X113189Y776937D01*
X113272Y776646D01*
X113189Y776312D01*
X112939Y776021D01*
X112564Y775854D01*
X112147Y775812D01*
X111605Y775896D01*
X111314Y776021D01*
X111022Y776229D01*
X110814Y776521D01*
X110772Y776812D01*
X110855Y777104D01*
X111064Y777312D01*
G01X112980Y778996D02*
X113189Y779287D01*
X113272Y779621D01*
X113189Y779954D01*
X112939Y780246D01*
X112564Y780454D01*
X112189Y780537D01*
X111730D01*
X111355Y780454D01*
X111022Y780246D01*
X110855Y779996D01*
X110772Y779704D01*
X110855Y779371D01*
X111022Y779121D01*
X111272Y778954D01*
X111605Y778871D01*
X111897Y778954D01*
X112189Y779162D01*
X112355Y779412D01*
X112397Y779704D01*
X112314Y780037D01*
X112105Y780287D01*
X111730Y780537D01*
G01X116939Y766429D02*
X117147Y766762D01*
X117272Y767137D01*
Y767471D01*
X117147Y767804D01*
X116939Y768054D01*
X116647Y768179D01*
X116355Y768096D01*
X116105Y767887D01*
X115939Y767512D01*
X115855Y767012D01*
X115689Y766721D01*
X115397Y766596D01*
X115105Y766679D01*
X114897Y766887D01*
X114772Y767179D01*
Y767471D01*
X114855Y767762D01*
X115064Y768012D01*
G01X114980Y771321D02*
X114855Y771071D01*
X114772Y770779D01*
Y770446D01*
X114897Y770071D01*
X115105Y769779D01*
X115355Y769571D01*
X115772Y769404D01*
X116147Y769362D01*
X116522Y769446D01*
X116772Y769571D01*
X117022Y769821D01*
X117189Y770112D01*
X117272Y770404D01*
Y770696D01*
X117189Y770987D01*
X117064Y771237D01*
X116897Y771446D01*
G01Y772587D02*
X117105Y772837D01*
X117230Y773129D01*
X117272Y773504D01*
X117189Y773879D01*
X117022Y774171D01*
X116730Y774379D01*
X116397Y774421D01*
X116064Y774337D01*
X115855Y774129D01*
X115689Y773837D01*
X115647Y773546D01*
X115689Y773254D01*
X115855Y772879D01*
X114772Y773004D01*
Y774129D01*
G01X117272Y777104D02*
X114772D01*
X116564Y775562D01*
Y777646D01*
G01X116230Y778912D02*
X115939Y779204D01*
X115772Y779454D01*
X115689Y779787D01*
X115772Y780079D01*
X115939Y780287D01*
X116189Y780454D01*
X116480Y780496D01*
X116730Y780454D01*
X116980Y780287D01*
X117189Y780037D01*
X117272Y779746D01*
X117189Y779412D01*
X116939Y779121D01*
X116564Y778954D01*
X116147Y778912D01*
X115605Y778996D01*
X115314Y779121D01*
X115022Y779329D01*
X114814Y779621D01*
X114772Y779912D01*
X114855Y780204D01*
X115064Y780412D01*
G01X110804Y806620D02*
X118804D01*
Y794220D01*
X110804D01*
Y806620D01*
G01X116287Y811720D02*
Y809928D01*
X116454Y809553D01*
X116787Y809303D01*
X117204Y809220D01*
X117621Y809303D01*
X117954Y809553D01*
X118121Y809928D01*
Y811720D01*
G01X120304Y809220D02*
Y811720D01*
X119804Y811220D01*
G01Y809220D02*
X120804D01*
G01X123321D02*
X123404Y809762D01*
X123529Y810220D01*
X123696Y810637D01*
X123904Y811095D01*
X124237Y811720D01*
X122571D01*
G01X114804Y804920D02*
X116304Y806420D01*
G01X114804Y804920D02*
X113304Y806420D01*
G01X104471Y821645D02*
X104679Y821978D01*
X104804Y822353D01*
Y822687D01*
X104679Y823020D01*
X104471Y823270D01*
X104179Y823395D01*
X103887Y823312D01*
X103637Y823103D01*
X103471Y822728D01*
X103387Y822228D01*
X103221Y821937D01*
X102929Y821812D01*
X102637Y821895D01*
X102429Y822103D01*
X102304Y822395D01*
Y822687D01*
X102387Y822978D01*
X102596Y823228D01*
G01X104804Y824787D02*
X102304D01*
Y825828D01*
X102429Y826162D01*
X102596Y826370D01*
X102929Y826453D01*
X103262Y826370D01*
X103471Y826120D01*
X103596Y825828D01*
Y824787D01*
G01Y825828D02*
X104804Y826453D01*
G01X102721Y827928D02*
X102471Y828178D01*
X102346Y828470D01*
X102304Y828803D01*
X102387Y829220D01*
X102596Y829512D01*
X102846Y829595D01*
X103096Y829553D01*
X103304Y829387D01*
X103721Y828553D01*
X104012Y828178D01*
X104429Y827928D01*
X104804Y827845D01*
Y829595D01*
G01Y831737D02*
X104262Y831820D01*
X103804Y831945D01*
X103387Y832112D01*
X102929Y832320D01*
X102304Y832653D01*
Y830987D01*
G01Y834920D02*
X102387Y834587D01*
X102596Y834337D01*
X102846Y834170D01*
X103179Y834045D01*
X103554Y834003D01*
X103929Y834045D01*
X104262Y834170D01*
X104512Y834337D01*
X104721Y834587D01*
X104804Y834920D01*
X104721Y835253D01*
X104512Y835503D01*
X104262Y835670D01*
X103929Y835795D01*
X103554Y835837D01*
X103179Y835795D01*
X102846Y835670D01*
X102596Y835503D01*
X102387Y835253D01*
X102304Y834920D01*
G01X106729Y862053D02*
X107062Y861845D01*
X107437Y861720D01*
X107771D01*
X108104Y861845D01*
X108354Y862053D01*
X108479Y862345D01*
X108396Y862637D01*
X108187Y862887D01*
X107812Y863053D01*
X107312Y863137D01*
X107021Y863303D01*
X106896Y863595D01*
X106979Y863887D01*
X107187Y864095D01*
X107479Y864220D01*
X107771D01*
X108062Y864137D01*
X108312Y863928D01*
G01X109871Y861720D02*
Y864220D01*
X110912D01*
X111246Y864095D01*
X111454Y863928D01*
X111537Y863595D01*
X111454Y863262D01*
X111204Y863053D01*
X110912Y862928D01*
X109871D01*
G01X110912D02*
X111537Y861720D01*
G01X113012Y863803D02*
X113262Y864053D01*
X113554Y864178D01*
X113887Y864220D01*
X114304Y864137D01*
X114596Y863928D01*
X114679Y863678D01*
X114637Y863428D01*
X114471Y863220D01*
X113637Y862803D01*
X113262Y862512D01*
X113012Y862095D01*
X112929Y861720D01*
X114679D01*
G01X116196Y862012D02*
X116487Y861803D01*
X116821Y861720D01*
X117154Y861803D01*
X117446Y862053D01*
X117654Y862428D01*
X117737Y862803D01*
Y863262D01*
X117654Y863637D01*
X117446Y863970D01*
X117196Y864137D01*
X116904Y864220D01*
X116571Y864137D01*
X116321Y863970D01*
X116154Y863720D01*
X116071Y863387D01*
X116154Y863095D01*
X116362Y862803D01*
X116612Y862637D01*
X116904Y862595D01*
X117237Y862678D01*
X117487Y862887D01*
X117737Y863262D01*
G01X119212Y862762D02*
X119504Y863053D01*
X119754Y863220D01*
X120087Y863303D01*
X120379Y863220D01*
X120587Y863053D01*
X120754Y862803D01*
X120796Y862512D01*
X120754Y862262D01*
X120587Y862012D01*
X120337Y861803D01*
X120046Y861720D01*
X119712Y861803D01*
X119421Y862053D01*
X119254Y862428D01*
X119212Y862845D01*
X119296Y863387D01*
X119421Y863678D01*
X119629Y863970D01*
X119921Y864178D01*
X120212Y864220D01*
X120504Y864137D01*
X120712Y863928D01*
G01X106729Y858053D02*
X107062Y857845D01*
X107437Y857720D01*
X107771D01*
X108104Y857845D01*
X108354Y858053D01*
X108479Y858345D01*
X108396Y858637D01*
X108187Y858887D01*
X107812Y859053D01*
X107312Y859137D01*
X107021Y859303D01*
X106896Y859595D01*
X106979Y859887D01*
X107187Y860095D01*
X107479Y860220D01*
X107771D01*
X108062Y860137D01*
X108312Y859928D01*
G01X109871Y857720D02*
Y860220D01*
X110912D01*
X111246Y860095D01*
X111454Y859928D01*
X111537Y859595D01*
X111454Y859262D01*
X111204Y859053D01*
X110912Y858928D01*
X109871D01*
G01X110912D02*
X111537Y857720D01*
G01X113012Y859803D02*
X113262Y860053D01*
X113554Y860178D01*
X113887Y860220D01*
X114304Y860137D01*
X114596Y859928D01*
X114679Y859678D01*
X114637Y859428D01*
X114471Y859220D01*
X113637Y858803D01*
X113262Y858512D01*
X113012Y858095D01*
X112929Y857720D01*
X114679D01*
G01X116196Y858012D02*
X116487Y857803D01*
X116821Y857720D01*
X117154Y857803D01*
X117446Y858053D01*
X117654Y858428D01*
X117737Y858803D01*
Y859262D01*
X117654Y859637D01*
X117446Y859970D01*
X117196Y860137D01*
X116904Y860220D01*
X116571Y860137D01*
X116321Y859970D01*
X116154Y859720D01*
X116071Y859387D01*
X116154Y859095D01*
X116362Y858803D01*
X116612Y858637D01*
X116904Y858595D01*
X117237Y858678D01*
X117487Y858887D01*
X117737Y859262D01*
G01X119296Y858012D02*
X119587Y857803D01*
X119921Y857720D01*
X120254Y857803D01*
X120546Y858053D01*
X120754Y858428D01*
X120837Y858803D01*
Y859262D01*
X120754Y859637D01*
X120546Y859970D01*
X120296Y860137D01*
X120004Y860220D01*
X119671Y860137D01*
X119421Y859970D01*
X119254Y859720D01*
X119171Y859387D01*
X119254Y859095D01*
X119462Y858803D01*
X119712Y858637D01*
X120004Y858595D01*
X120337Y858678D01*
X120587Y858887D01*
X120837Y859262D01*
G01X106729Y866053D02*
X107062Y865845D01*
X107437Y865720D01*
X107771D01*
X108104Y865845D01*
X108354Y866053D01*
X108479Y866345D01*
X108396Y866637D01*
X108187Y866887D01*
X107812Y867053D01*
X107312Y867137D01*
X107021Y867303D01*
X106896Y867595D01*
X106979Y867887D01*
X107187Y868095D01*
X107479Y868220D01*
X107771D01*
X108062Y868137D01*
X108312Y867928D01*
G01X109871Y865720D02*
Y868220D01*
X110912D01*
X111246Y868095D01*
X111454Y867928D01*
X111537Y867595D01*
X111454Y867262D01*
X111204Y867053D01*
X110912Y866928D01*
X109871D01*
G01X110912D02*
X111537Y865720D01*
G01X113012Y867803D02*
X113262Y868053D01*
X113554Y868178D01*
X113887Y868220D01*
X114304Y868137D01*
X114596Y867928D01*
X114679Y867678D01*
X114637Y867428D01*
X114471Y867220D01*
X113637Y866803D01*
X113262Y866512D01*
X113012Y866095D01*
X112929Y865720D01*
X114679D01*
G01X116196Y866012D02*
X116487Y865803D01*
X116821Y865720D01*
X117154Y865803D01*
X117446Y866053D01*
X117654Y866428D01*
X117737Y866803D01*
Y867262D01*
X117654Y867637D01*
X117446Y867970D01*
X117196Y868137D01*
X116904Y868220D01*
X116571Y868137D01*
X116321Y867970D01*
X116154Y867720D01*
X116071Y867387D01*
X116154Y867095D01*
X116362Y866803D01*
X116612Y866637D01*
X116904Y866595D01*
X117237Y866678D01*
X117487Y866887D01*
X117737Y867262D01*
G01X119921Y865720D02*
X120004Y866262D01*
X120129Y866720D01*
X120296Y867137D01*
X120504Y867595D01*
X120837Y868220D01*
X119171D01*
G01X106729Y870053D02*
X107062Y869845D01*
X107437Y869720D01*
X107771D01*
X108104Y869845D01*
X108354Y870053D01*
X108479Y870345D01*
X108396Y870637D01*
X108187Y870887D01*
X107812Y871053D01*
X107312Y871137D01*
X107021Y871303D01*
X106896Y871595D01*
X106979Y871887D01*
X107187Y872095D01*
X107479Y872220D01*
X107771D01*
X108062Y872137D01*
X108312Y871928D01*
G01X109871Y869720D02*
Y872220D01*
X110912D01*
X111246Y872095D01*
X111454Y871928D01*
X111537Y871595D01*
X111454Y871262D01*
X111204Y871053D01*
X110912Y870928D01*
X109871D01*
G01X110912D02*
X111537Y869720D01*
G01X113012Y871803D02*
X113262Y872053D01*
X113554Y872178D01*
X113887Y872220D01*
X114304Y872137D01*
X114596Y871928D01*
X114679Y871678D01*
X114637Y871428D01*
X114471Y871220D01*
X113637Y870803D01*
X113262Y870512D01*
X113012Y870095D01*
X112929Y869720D01*
X114679D01*
G01X116196Y870012D02*
X116487Y869803D01*
X116821Y869720D01*
X117154Y869803D01*
X117446Y870053D01*
X117654Y870428D01*
X117737Y870803D01*
Y871262D01*
X117654Y871637D01*
X117446Y871970D01*
X117196Y872137D01*
X116904Y872220D01*
X116571Y872137D01*
X116321Y871970D01*
X116154Y871720D01*
X116071Y871387D01*
X116154Y871095D01*
X116362Y870803D01*
X116612Y870637D01*
X116904Y870595D01*
X117237Y870678D01*
X117487Y870887D01*
X117737Y871262D01*
G01X120004Y869720D02*
X120296Y869762D01*
X120629Y869887D01*
X120837Y870095D01*
X120921Y870387D01*
X120837Y870678D01*
X120587Y870928D01*
X120212Y871053D01*
X119796D01*
X119546Y871137D01*
X119337Y871345D01*
X119254Y871637D01*
X119379Y871928D01*
X119671Y872137D01*
X120004Y872220D01*
X120337Y872137D01*
X120629Y871928D01*
X120754Y871637D01*
X120671Y871345D01*
X120462Y871137D01*
X120212Y871053D01*
X119796D01*
X119421Y870928D01*
X119171Y870678D01*
X119087Y870387D01*
X119171Y870095D01*
X119379Y869887D01*
X119712Y869762D01*
X120004Y869720D01*
G01X112804Y884237D02*
X110304D01*
Y885278D01*
X110429Y885612D01*
X110596Y885820D01*
X110929Y885903D01*
X111262Y885820D01*
X111471Y885570D01*
X111596Y885278D01*
Y884237D01*
G01Y885278D02*
X112804Y885903D01*
G01X111762Y887378D02*
X111471Y887670D01*
X111304Y887920D01*
X111221Y888253D01*
X111304Y888545D01*
X111471Y888753D01*
X111721Y888920D01*
X112012Y888962D01*
X112262Y888920D01*
X112512Y888753D01*
X112721Y888503D01*
X112804Y888212D01*
X112721Y887878D01*
X112471Y887587D01*
X112096Y887420D01*
X111679Y887378D01*
X111137Y887462D01*
X110846Y887587D01*
X110554Y887795D01*
X110346Y888087D01*
X110304Y888378D01*
X110387Y888670D01*
X110596Y888878D01*
G01X112304Y890353D02*
X112596Y890603D01*
X112762Y890937D01*
X112804Y891312D01*
X112762Y891645D01*
X112554Y891978D01*
X112304Y892187D01*
X112054Y892228D01*
X111762Y892145D01*
X111554Y891853D01*
X111471Y891562D01*
Y891187D01*
G01Y891562D02*
X111346Y891812D01*
X111137Y892020D01*
X110887Y892103D01*
X110637Y892020D01*
X110429Y891812D01*
X110304Y891437D01*
X110346Y891062D01*
X110512Y890687D01*
G01X112429Y893453D02*
X112637Y893703D01*
X112762Y893995D01*
X112804Y894370D01*
X112721Y894745D01*
X112554Y895037D01*
X112262Y895245D01*
X111929Y895287D01*
X111596Y895203D01*
X111387Y894995D01*
X111221Y894703D01*
X111179Y894412D01*
X111221Y894120D01*
X111387Y893745D01*
X110304Y893870D01*
Y894995D01*
G01X104304Y892420D02*
X100304D01*
Y885020D01*
G01X107321Y879720D02*
Y882220D01*
X108362D01*
X108696Y882095D01*
X108904Y881928D01*
X108987Y881595D01*
X108904Y881262D01*
X108654Y881053D01*
X108362Y880928D01*
X107321D01*
G01X108362D02*
X108987Y879720D01*
G01X110462Y880762D02*
X110754Y881053D01*
X111004Y881220D01*
X111337Y881303D01*
X111629Y881220D01*
X111837Y881053D01*
X112004Y880803D01*
X112046Y880512D01*
X112004Y880262D01*
X111837Y880012D01*
X111587Y879803D01*
X111296Y879720D01*
X110962Y879803D01*
X110671Y880053D01*
X110504Y880428D01*
X110462Y880845D01*
X110546Y881387D01*
X110671Y881678D01*
X110879Y881970D01*
X111171Y882178D01*
X111462Y882220D01*
X111754Y882137D01*
X111962Y881928D01*
G01X113437Y880220D02*
X113687Y879928D01*
X114021Y879762D01*
X114396Y879720D01*
X114729Y879762D01*
X115062Y879970D01*
X115271Y880220D01*
X115312Y880470D01*
X115229Y880762D01*
X114937Y880970D01*
X114646Y881053D01*
X114271D01*
G01X114646D02*
X114896Y881178D01*
X115104Y881387D01*
X115187Y881637D01*
X115104Y881887D01*
X114896Y882095D01*
X114521Y882220D01*
X114146Y882178D01*
X113771Y882012D01*
G01X117371Y879720D02*
X117454Y880262D01*
X117579Y880720D01*
X117746Y881137D01*
X117954Y881595D01*
X118287Y882220D01*
X116621D01*
G01X115279Y931053D02*
X115612Y930845D01*
X115987Y930720D01*
X116321D01*
X116654Y930845D01*
X116904Y931053D01*
X117029Y931345D01*
X116946Y931637D01*
X116737Y931887D01*
X116362Y932053D01*
X115862Y932137D01*
X115571Y932303D01*
X115446Y932595D01*
X115529Y932887D01*
X115737Y933095D01*
X116029Y933220D01*
X116321D01*
X116612Y933137D01*
X116862Y932928D01*
G01X118337Y933220D02*
Y931428D01*
X118504Y931053D01*
X118837Y930803D01*
X119254Y930720D01*
X119671Y930803D01*
X120004Y931053D01*
X120171Y931428D01*
Y933220D01*
G01X122354Y930720D02*
Y933220D01*
X121854Y932720D01*
G01Y930720D02*
X122854D01*
G01X124537Y931220D02*
X124787Y930928D01*
X125121Y930762D01*
X125496Y930720D01*
X125829Y930762D01*
X126162Y930970D01*
X126371Y931220D01*
X126412Y931470D01*
X126329Y931762D01*
X126037Y931970D01*
X125746Y932053D01*
X125371D01*
G01X125746D02*
X125996Y932178D01*
X126204Y932387D01*
X126287Y932637D01*
X126204Y932887D01*
X125996Y933095D01*
X125621Y933220D01*
X125246Y933178D01*
X124871Y933012D01*
G01X102971Y939645D02*
X103179Y939978D01*
X103304Y940353D01*
Y940687D01*
X103179Y941020D01*
X102971Y941270D01*
X102679Y941395D01*
X102387Y941312D01*
X102137Y941103D01*
X101971Y940728D01*
X101887Y940228D01*
X101721Y939937D01*
X101429Y939812D01*
X101137Y939895D01*
X100929Y940103D01*
X100804Y940395D01*
Y940687D01*
X100887Y940978D01*
X101096Y941228D01*
G01X101012Y944537D02*
X100887Y944287D01*
X100804Y943995D01*
Y943662D01*
X100929Y943287D01*
X101137Y942995D01*
X101387Y942787D01*
X101804Y942620D01*
X102179Y942578D01*
X102554Y942662D01*
X102804Y942787D01*
X103054Y943037D01*
X103221Y943328D01*
X103304Y943620D01*
Y943912D01*
X103221Y944203D01*
X103096Y944453D01*
X102929Y944662D01*
G01X103304Y947220D02*
X100804D01*
X102596Y945678D01*
Y947762D01*
G01X101221Y949028D02*
X100971Y949278D01*
X100846Y949570D01*
X100804Y949903D01*
X100887Y950320D01*
X101096Y950612D01*
X101346Y950695D01*
X101596Y950653D01*
X101804Y950487D01*
X102221Y949653D01*
X102512Y949278D01*
X102929Y949028D01*
X103304Y948945D01*
Y950695D01*
G01Y952837D02*
X102762Y952920D01*
X102304Y953045D01*
X101887Y953212D01*
X101429Y953420D01*
X100804Y953753D01*
Y952087D01*
G01X135888Y-22373D02*
X136355Y-21973D01*
X136621Y-21439D01*
X136688Y-20839D01*
X136621Y-20306D01*
X136288Y-19773D01*
X135888Y-19439D01*
X135488Y-19373D01*
X135021Y-19506D01*
X134688Y-19973D01*
X134555Y-20439D01*
Y-21039D01*
G01Y-20439D02*
X134355Y-20039D01*
X134021Y-19706D01*
X133621Y-19573D01*
X133221Y-19706D01*
X132888Y-20039D01*
X132688Y-20639D01*
X132755Y-21239D01*
X133021Y-21839D01*
G01X124990Y228528D02*
Y243328D01*
X117690D01*
Y273028D01*
X146090D01*
Y243328D01*
X138790D01*
Y228528D01*
X124990D01*
G01X121671Y282453D02*
Y284953D01*
X122712D01*
X123046Y284828D01*
X123254Y284661D01*
X123337Y284328D01*
X123254Y283995D01*
X123004Y283786D01*
X122712Y283661D01*
X121671D01*
G01X122712D02*
X123337Y282453D01*
G01X124812Y283495D02*
X125104Y283786D01*
X125354Y283953D01*
X125687Y284036D01*
X125979Y283953D01*
X126187Y283786D01*
X126354Y283536D01*
X126396Y283245D01*
X126354Y282995D01*
X126187Y282745D01*
X125937Y282536D01*
X125646Y282453D01*
X125312Y282536D01*
X125021Y282786D01*
X124854Y283161D01*
X124812Y283578D01*
X124896Y284120D01*
X125021Y284411D01*
X125229Y284703D01*
X125521Y284911D01*
X125812Y284953D01*
X126104Y284870D01*
X126312Y284661D01*
G01X127787Y282828D02*
X128037Y282620D01*
X128329Y282495D01*
X128704Y282453D01*
X129079Y282536D01*
X129371Y282703D01*
X129579Y282995D01*
X129621Y283328D01*
X129537Y283661D01*
X129329Y283870D01*
X129037Y284036D01*
X128746Y284078D01*
X128454Y284036D01*
X128079Y283870D01*
X128204Y284953D01*
X129329D01*
G01X131096Y282745D02*
X131387Y282536D01*
X131721Y282453D01*
X132054Y282536D01*
X132346Y282786D01*
X132554Y283161D01*
X132637Y283536D01*
Y283995D01*
X132554Y284370D01*
X132346Y284703D01*
X132096Y284870D01*
X131804Y284953D01*
X131471Y284870D01*
X131221Y284703D01*
X131054Y284453D01*
X130971Y284120D01*
X131054Y283828D01*
X131262Y283536D01*
X131512Y283370D01*
X131804Y283328D01*
X132137Y283411D01*
X132387Y283620D01*
X132637Y283995D01*
G01X149664Y294190D02*
Y286190D01*
X132064D01*
Y294190D01*
X149664D01*
G01X121707Y277663D02*
Y280163D01*
X122748D01*
X123082Y280038D01*
X123290Y279871D01*
X123373Y279538D01*
X123290Y279205D01*
X123040Y278996D01*
X122748Y278871D01*
X121707D01*
G01X122748D02*
X123373Y277663D01*
G01X124848Y279746D02*
X125098Y279996D01*
X125390Y280121D01*
X125723Y280163D01*
X126140Y280080D01*
X126432Y279871D01*
X126515Y279621D01*
X126473Y279371D01*
X126307Y279163D01*
X125473Y278746D01*
X125098Y278455D01*
X124848Y278038D01*
X124765Y277663D01*
X126515D01*
G01X128032Y277955D02*
X128323Y277746D01*
X128657Y277663D01*
X128990Y277746D01*
X129282Y277996D01*
X129490Y278371D01*
X129573Y278746D01*
Y279205D01*
X129490Y279580D01*
X129282Y279913D01*
X129032Y280080D01*
X128740Y280163D01*
X128407Y280080D01*
X128157Y279913D01*
X127990Y279663D01*
X127907Y279330D01*
X127990Y279038D01*
X128198Y278746D01*
X128448Y278580D01*
X128740Y278538D01*
X129073Y278621D01*
X129323Y278830D01*
X129573Y279205D01*
G01X131840Y280163D02*
X131507Y280080D01*
X131257Y279871D01*
X131090Y279621D01*
X130965Y279288D01*
X130923Y278913D01*
X130965Y278538D01*
X131090Y278205D01*
X131257Y277955D01*
X131507Y277746D01*
X131840Y277663D01*
X132173Y277746D01*
X132423Y277955D01*
X132590Y278205D01*
X132715Y278538D01*
X132757Y278913D01*
X132715Y279288D01*
X132590Y279621D01*
X132423Y279871D01*
X132173Y280080D01*
X131840Y280163D01*
G01X132691Y295343D02*
X145691D01*
G01X132691Y309343D02*
Y295343D01*
G01X124154Y298453D02*
Y312453D01*
G01X145691Y309343D02*
X132691D01*
G01X129154Y317470D02*
X126654D01*
Y318511D01*
X126779Y318845D01*
X126946Y319053D01*
X127279Y319136D01*
X127612Y319053D01*
X127821Y318803D01*
X127946Y318511D01*
Y317470D01*
G01Y318511D02*
X129154Y319136D01*
G01X128112Y320611D02*
X127821Y320903D01*
X127654Y321153D01*
X127571Y321486D01*
X127654Y321778D01*
X127821Y321986D01*
X128071Y322153D01*
X128362Y322195D01*
X128612Y322153D01*
X128862Y321986D01*
X129071Y321736D01*
X129154Y321445D01*
X129071Y321111D01*
X128821Y320820D01*
X128446Y320653D01*
X128029Y320611D01*
X127487Y320695D01*
X127196Y320820D01*
X126904Y321028D01*
X126696Y321320D01*
X126654Y321611D01*
X126737Y321903D01*
X126946Y322111D01*
G01X129154Y324420D02*
X128612Y324503D01*
X128154Y324628D01*
X127737Y324795D01*
X127279Y325003D01*
X126654Y325336D01*
Y323670D01*
G01X128654Y326686D02*
X128946Y326936D01*
X129112Y327270D01*
X129154Y327645D01*
X129112Y327978D01*
X128904Y328311D01*
X128654Y328520D01*
X128404Y328561D01*
X128112Y328478D01*
X127904Y328186D01*
X127821Y327895D01*
Y327520D01*
G01Y327895D02*
X127696Y328145D01*
X127487Y328353D01*
X127237Y328436D01*
X126987Y328353D01*
X126779Y328145D01*
X126654Y327770D01*
X126696Y327395D01*
X126862Y327020D01*
G01X129654Y314153D02*
X125654D01*
Y306753D01*
G01X132654Y330470D02*
X130154D01*
Y331511D01*
X130279Y331845D01*
X130446Y332053D01*
X130779Y332136D01*
X131112Y332053D01*
X131321Y331803D01*
X131446Y331511D01*
Y330470D01*
G01Y331511D02*
X132654Y332136D01*
G01X131612Y333611D02*
X131321Y333903D01*
X131154Y334153D01*
X131071Y334486D01*
X131154Y334778D01*
X131321Y334986D01*
X131571Y335153D01*
X131862Y335195D01*
X132112Y335153D01*
X132362Y334986D01*
X132571Y334736D01*
X132654Y334445D01*
X132571Y334111D01*
X132321Y333820D01*
X131946Y333653D01*
X131529Y333611D01*
X130987Y333695D01*
X130696Y333820D01*
X130404Y334028D01*
X130196Y334320D01*
X130154Y334611D01*
X130237Y334903D01*
X130446Y335111D01*
G01X132654Y337420D02*
X132112Y337503D01*
X131654Y337628D01*
X131237Y337795D01*
X130779Y338003D01*
X130154Y338336D01*
Y336670D01*
G01X132654Y341103D02*
X130154D01*
X131946Y339561D01*
Y341645D01*
G01X130967Y449725D02*
X131175Y450058D01*
X131300Y450433D01*
Y450767D01*
X131175Y451100D01*
X130967Y451350D01*
X130675Y451475D01*
X130383Y451392D01*
X130133Y451183D01*
X129967Y450808D01*
X129883Y450308D01*
X129717Y450017D01*
X129425Y449892D01*
X129133Y449975D01*
X128925Y450183D01*
X128800Y450475D01*
Y450767D01*
X128883Y451058D01*
X129092Y451308D01*
G01X131300Y452867D02*
X128800D01*
Y453908D01*
X128925Y454242D01*
X129092Y454450D01*
X129425Y454533D01*
X129758Y454450D01*
X129967Y454200D01*
X130092Y453908D01*
Y452867D01*
G01Y453908D02*
X131300Y454533D01*
G01Y456800D02*
X131258Y457092D01*
X131133Y457425D01*
X130925Y457633D01*
X130633Y457717D01*
X130342Y457633D01*
X130092Y457383D01*
X129967Y457008D01*
Y456592D01*
X129883Y456342D01*
X129675Y456133D01*
X129383Y456050D01*
X129092Y456175D01*
X128883Y456467D01*
X128800Y456800D01*
X128883Y457133D01*
X129092Y457425D01*
X129383Y457550D01*
X129675Y457467D01*
X129883Y457258D01*
X129967Y457008D01*
Y456592D01*
X130092Y456217D01*
X130342Y455967D01*
X130633Y455883D01*
X130925Y455967D01*
X131133Y456175D01*
X131258Y456508D01*
X131300Y456800D01*
G01Y460400D02*
X128800D01*
X130592Y458858D01*
Y460942D01*
G01X131300Y463000D02*
X131258Y463292D01*
X131133Y463625D01*
X130925Y463833D01*
X130633Y463917D01*
X130342Y463833D01*
X130092Y463583D01*
X129967Y463208D01*
Y462792D01*
X129883Y462542D01*
X129675Y462333D01*
X129383Y462250D01*
X129092Y462375D01*
X128883Y462667D01*
X128800Y463000D01*
X128883Y463333D01*
X129092Y463625D01*
X129383Y463750D01*
X129675Y463667D01*
X129883Y463458D01*
X129967Y463208D01*
Y462792D01*
X130092Y462417D01*
X130342Y462167D01*
X130633Y462083D01*
X130925Y462167D01*
X131133Y462375D01*
X131258Y462708D01*
X131300Y463000D01*
G01X133225Y466133D02*
X133558Y465925D01*
X133933Y465800D01*
X134267D01*
X134600Y465925D01*
X134850Y466133D01*
X134975Y466425D01*
X134892Y466717D01*
X134683Y466967D01*
X134308Y467133D01*
X133808Y467217D01*
X133517Y467383D01*
X133392Y467675D01*
X133475Y467967D01*
X133683Y468175D01*
X133975Y468300D01*
X134267D01*
X134558Y468217D01*
X134808Y468008D01*
G01X136367Y465800D02*
Y468300D01*
X137408D01*
X137742Y468175D01*
X137950Y468008D01*
X138033Y467675D01*
X137950Y467342D01*
X137700Y467133D01*
X137408Y467008D01*
X136367D01*
G01X137408D02*
X138033Y465800D01*
G01X139592Y466092D02*
X139883Y465883D01*
X140217Y465800D01*
X140550Y465883D01*
X140842Y466133D01*
X141050Y466508D01*
X141133Y466883D01*
Y467342D01*
X141050Y467717D01*
X140842Y468050D01*
X140592Y468217D01*
X140300Y468300D01*
X139967Y468217D01*
X139717Y468050D01*
X139550Y467800D01*
X139467Y467467D01*
X139550Y467175D01*
X139758Y466883D01*
X140008Y466717D01*
X140300Y466675D01*
X140633Y466758D01*
X140883Y466967D01*
X141133Y467342D01*
G01X142483Y466300D02*
X142733Y466008D01*
X143067Y465842D01*
X143442Y465800D01*
X143775Y465842D01*
X144108Y466050D01*
X144317Y466300D01*
X144358Y466550D01*
X144275Y466842D01*
X143983Y467050D01*
X143692Y467133D01*
X143317D01*
G01X143692D02*
X143942Y467258D01*
X144150Y467467D01*
X144233Y467717D01*
X144150Y467967D01*
X143942Y468175D01*
X143567Y468300D01*
X143192Y468258D01*
X142817Y468092D01*
G01X146417Y465800D02*
X146500Y466342D01*
X146625Y466800D01*
X146792Y467217D01*
X147000Y467675D01*
X147333Y468300D01*
X145667D01*
G01X126167Y661875D02*
X126375Y662208D01*
X126500Y662583D01*
Y662917D01*
X126375Y663250D01*
X126167Y663500D01*
X125875Y663625D01*
X125583Y663542D01*
X125333Y663333D01*
X125167Y662958D01*
X125083Y662458D01*
X124917Y662167D01*
X124625Y662042D01*
X124333Y662125D01*
X124125Y662333D01*
X124000Y662625D01*
Y662917D01*
X124083Y663208D01*
X124292Y663458D01*
G01X126500Y665017D02*
X124000D01*
Y666058D01*
X124125Y666392D01*
X124292Y666600D01*
X124625Y666683D01*
X124958Y666600D01*
X125167Y666350D01*
X125292Y666058D01*
Y665017D01*
G01Y666058D02*
X126500Y666683D01*
G01Y668950D02*
X124000D01*
X124500Y668450D01*
G01X126500D02*
Y669450D01*
G01X124417Y671258D02*
X124167Y671508D01*
X124042Y671800D01*
X124000Y672133D01*
X124083Y672550D01*
X124292Y672842D01*
X124542Y672925D01*
X124792Y672883D01*
X125000Y672717D01*
X125417Y671883D01*
X125708Y671508D01*
X126125Y671258D01*
X126500Y671175D01*
Y672925D01*
G01Y675067D02*
X125958Y675150D01*
X125500Y675275D01*
X125083Y675442D01*
X124625Y675650D01*
X124000Y675983D01*
Y674317D01*
G01X126500Y678250D02*
X126458Y678542D01*
X126333Y678875D01*
X126125Y679083D01*
X125833Y679167D01*
X125542Y679083D01*
X125292Y678833D01*
X125167Y678458D01*
Y678042D01*
X125083Y677792D01*
X124875Y677583D01*
X124583Y677500D01*
X124292Y677625D01*
X124083Y677917D01*
X124000Y678250D01*
X124083Y678583D01*
X124292Y678875D01*
X124583Y679000D01*
X124875Y678917D01*
X125083Y678708D01*
X125167Y678458D01*
Y678042D01*
X125292Y677667D01*
X125542Y677417D01*
X125833Y677333D01*
X126125Y677417D01*
X126333Y677625D01*
X126458Y677958D01*
X126500Y678250D01*
G01X121167Y671375D02*
X121375Y671708D01*
X121500Y672083D01*
Y672417D01*
X121375Y672750D01*
X121167Y673000D01*
X120875Y673125D01*
X120583Y673042D01*
X120333Y672833D01*
X120167Y672458D01*
X120083Y671958D01*
X119917Y671667D01*
X119625Y671542D01*
X119333Y671625D01*
X119125Y671833D01*
X119000Y672125D01*
Y672417D01*
X119083Y672708D01*
X119292Y672958D01*
G01X121500Y674517D02*
X119000D01*
Y675558D01*
X119125Y675892D01*
X119292Y676100D01*
X119625Y676183D01*
X119958Y676100D01*
X120167Y675850D01*
X120292Y675558D01*
Y674517D01*
G01Y675558D02*
X121500Y676183D01*
G01Y678450D02*
X119000D01*
X119500Y677950D01*
G01X121500D02*
Y678950D01*
G01X119417Y680758D02*
X119167Y681008D01*
X119042Y681300D01*
X119000Y681633D01*
X119083Y682050D01*
X119292Y682342D01*
X119542Y682425D01*
X119792Y682383D01*
X120000Y682217D01*
X120417Y681383D01*
X120708Y681008D01*
X121125Y680758D01*
X121500Y680675D01*
Y682425D01*
G01Y684650D02*
X121458Y684942D01*
X121333Y685275D01*
X121125Y685483D01*
X120833Y685567D01*
X120542Y685483D01*
X120292Y685233D01*
X120167Y684858D01*
Y684442D01*
X120083Y684192D01*
X119875Y683983D01*
X119583Y683900D01*
X119292Y684025D01*
X119083Y684317D01*
X119000Y684650D01*
X119083Y684983D01*
X119292Y685275D01*
X119583Y685400D01*
X119875Y685317D01*
X120083Y685108D01*
X120167Y684858D01*
Y684442D01*
X120292Y684067D01*
X120542Y683817D01*
X120833Y683733D01*
X121125Y683817D01*
X121333Y684025D01*
X121458Y684358D01*
X121500Y684650D01*
G01X119000Y687750D02*
X119083Y687417D01*
X119292Y687167D01*
X119542Y687000D01*
X119875Y686875D01*
X120250Y686833D01*
X120625Y686875D01*
X120958Y687000D01*
X121208Y687167D01*
X121417Y687417D01*
X121500Y687750D01*
X121417Y688083D01*
X121208Y688333D01*
X120958Y688500D01*
X120625Y688625D01*
X120250Y688667D01*
X119875Y688625D01*
X119542Y688500D01*
X119292Y688333D01*
X119083Y688083D01*
X119000Y687750D01*
G01X132000Y676800D02*
X136000D01*
Y684200D01*
G01X132000Y669300D02*
X136000D01*
Y676700D01*
G01X122975Y703333D02*
X123308Y703125D01*
X123683Y703000D01*
X124017D01*
X124350Y703125D01*
X124600Y703333D01*
X124725Y703625D01*
X124642Y703917D01*
X124433Y704167D01*
X124058Y704333D01*
X123558Y704417D01*
X123267Y704583D01*
X123142Y704875D01*
X123225Y705167D01*
X123433Y705375D01*
X123725Y705500D01*
X124017D01*
X124308Y705417D01*
X124558Y705208D01*
G01X126950Y703000D02*
X126617Y703042D01*
X126325Y703208D01*
X126075Y703458D01*
X125908Y703750D01*
X125825Y704083D01*
Y704417D01*
X125908Y704750D01*
X126075Y705042D01*
X126325Y705292D01*
X126617Y705458D01*
X126950Y705500D01*
X127283Y705458D01*
X127575Y705292D01*
X127825Y705042D01*
X127992Y704750D01*
X128075Y704417D01*
Y704083D01*
X127992Y703750D01*
X127825Y703458D01*
X127575Y703208D01*
X127283Y703042D01*
X126950Y703000D01*
G01X127283Y703667D02*
X127783Y703000D01*
G01X130050D02*
Y705500D01*
X129550Y705000D01*
G01Y703000D02*
X130550D01*
G01X132358Y704042D02*
X132650Y704333D01*
X132900Y704500D01*
X133233Y704583D01*
X133525Y704500D01*
X133733Y704333D01*
X133900Y704083D01*
X133942Y703792D01*
X133900Y703542D01*
X133733Y703292D01*
X133483Y703083D01*
X133192Y703000D01*
X132858Y703083D01*
X132567Y703333D01*
X132400Y703708D01*
X132358Y704125D01*
X132442Y704667D01*
X132567Y704958D01*
X132775Y705250D01*
X133067Y705458D01*
X133358Y705500D01*
X133650Y705417D01*
X133858Y705208D01*
G01X122975Y698833D02*
X123308Y698625D01*
X123683Y698500D01*
X124017D01*
X124350Y698625D01*
X124600Y698833D01*
X124725Y699125D01*
X124642Y699417D01*
X124433Y699667D01*
X124058Y699833D01*
X123558Y699917D01*
X123267Y700083D01*
X123142Y700375D01*
X123225Y700667D01*
X123433Y700875D01*
X123725Y701000D01*
X124017D01*
X124308Y700917D01*
X124558Y700708D01*
G01X126950Y698500D02*
X126617Y698542D01*
X126325Y698708D01*
X126075Y698958D01*
X125908Y699250D01*
X125825Y699583D01*
Y699917D01*
X125908Y700250D01*
X126075Y700542D01*
X126325Y700792D01*
X126617Y700958D01*
X126950Y701000D01*
X127283Y700958D01*
X127575Y700792D01*
X127825Y700542D01*
X127992Y700250D01*
X128075Y699917D01*
Y699583D01*
X127992Y699250D01*
X127825Y698958D01*
X127575Y698708D01*
X127283Y698542D01*
X126950Y698500D01*
G01X127283Y699167D02*
X127783Y698500D01*
G01X130050D02*
Y701000D01*
X129550Y700500D01*
G01Y698500D02*
X130550D01*
G01X133067D02*
X133150Y699042D01*
X133275Y699500D01*
X133442Y699917D01*
X133650Y700375D01*
X133983Y701000D01*
X132317D01*
G01X130475Y853333D02*
X130808Y853125D01*
X131183Y853000D01*
X131517D01*
X131850Y853125D01*
X132100Y853333D01*
X132225Y853625D01*
X132142Y853917D01*
X131933Y854167D01*
X131558Y854333D01*
X131058Y854417D01*
X130767Y854583D01*
X130642Y854875D01*
X130725Y855167D01*
X130933Y855375D01*
X131225Y855500D01*
X131517D01*
X131808Y855417D01*
X132058Y855208D01*
G01X133533Y855500D02*
Y853708D01*
X133700Y853333D01*
X134033Y853083D01*
X134450Y853000D01*
X134867Y853083D01*
X135200Y853333D01*
X135367Y853708D01*
Y855500D01*
G01X137467Y853000D02*
X137550Y853542D01*
X137675Y854000D01*
X137842Y854417D01*
X138050Y854875D01*
X138383Y855500D01*
X136717D01*
G01X141150Y853000D02*
Y855500D01*
X139608Y853708D01*
X141692D01*
G01X138300Y849700D02*
X127000D01*
G01X125667Y856975D02*
X125875Y857308D01*
X126000Y857683D01*
Y858017D01*
X125875Y858350D01*
X125667Y858600D01*
X125375Y858725D01*
X125083Y858642D01*
X124833Y858433D01*
X124667Y858058D01*
X124583Y857558D01*
X124417Y857267D01*
X124125Y857142D01*
X123833Y857225D01*
X123625Y857433D01*
X123500Y857725D01*
Y858017D01*
X123583Y858308D01*
X123792Y858558D01*
G01X123500Y860033D02*
X125292D01*
X125667Y860200D01*
X125917Y860533D01*
X126000Y860950D01*
X125917Y861367D01*
X125667Y861700D01*
X125292Y861867D01*
X123500D01*
G01X126000Y864050D02*
X123500D01*
X124000Y863550D01*
G01X126000D02*
Y864550D01*
G01Y867650D02*
X123500D01*
X125292Y866108D01*
Y868192D01*
G01X131904Y905520D02*
Y917920D01*
G01D02*
Y905520D01*
G01X143700Y281500D02*
Y285500D01*
X136300D01*
G01X145691Y295343D02*
Y309343D01*
G01X149154Y313853D02*
X149112Y313520D01*
X148946Y313228D01*
X148696Y312978D01*
X148404Y312811D01*
X148071Y312728D01*
X147737D01*
X147404Y312811D01*
X147112Y312978D01*
X146862Y313228D01*
X146696Y313520D01*
X146654Y313853D01*
X146696Y314186D01*
X146862Y314478D01*
X147112Y314728D01*
X147404Y314895D01*
X147737Y314978D01*
X148071D01*
X148404Y314895D01*
X148696Y314728D01*
X148946Y314478D01*
X149112Y314186D01*
X149154Y313853D01*
G01X148487Y314186D02*
X149154Y314686D01*
G01X147071Y316161D02*
X146821Y316411D01*
X146696Y316703D01*
X146654Y317036D01*
X146737Y317453D01*
X146946Y317745D01*
X147196Y317828D01*
X147446Y317786D01*
X147654Y317620D01*
X148071Y316786D01*
X148362Y316411D01*
X148779Y316161D01*
X149154Y316078D01*
Y317828D01*
G01X147071Y319261D02*
X146821Y319511D01*
X146696Y319803D01*
X146654Y320136D01*
X146737Y320553D01*
X146946Y320845D01*
X147196Y320928D01*
X147446Y320886D01*
X147654Y320720D01*
X148071Y319886D01*
X148362Y319511D01*
X148779Y319261D01*
X149154Y319178D01*
Y320928D01*
G01X141700Y310000D02*
Y314000D01*
X134300D01*
G01X136000Y314300D02*
X140000D01*
Y321700D01*
G01X134707Y324163D02*
Y326663D01*
X135748D01*
X136082Y326538D01*
X136290Y326371D01*
X136373Y326038D01*
X136290Y325705D01*
X136040Y325496D01*
X135748Y325371D01*
X134707D01*
G01X135748D02*
X136373Y324163D01*
G01X137848Y325205D02*
X138140Y325496D01*
X138390Y325663D01*
X138723Y325746D01*
X139015Y325663D01*
X139223Y325496D01*
X139390Y325246D01*
X139432Y324955D01*
X139390Y324705D01*
X139223Y324455D01*
X138973Y324246D01*
X138682Y324163D01*
X138348Y324246D01*
X138057Y324496D01*
X137890Y324871D01*
X137848Y325288D01*
X137932Y325830D01*
X138057Y326121D01*
X138265Y326413D01*
X138557Y326621D01*
X138848Y326663D01*
X139140Y326580D01*
X139348Y326371D01*
G01X141657Y324163D02*
X141740Y324705D01*
X141865Y325163D01*
X142032Y325580D01*
X142240Y326038D01*
X142573Y326663D01*
X140907D01*
G01X144757Y324163D02*
X144840Y324705D01*
X144965Y325163D01*
X145132Y325580D01*
X145340Y326038D01*
X145673Y326663D01*
X144007D01*
G01X139663Y328327D02*
X137163D01*
Y329368D01*
X137288Y329702D01*
X137455Y329910D01*
X137788Y329993D01*
X138121Y329910D01*
X138330Y329660D01*
X138455Y329368D01*
Y328327D01*
G01Y329368D02*
X139663Y329993D01*
G01X138621Y331468D02*
X138330Y331760D01*
X138163Y332010D01*
X138080Y332343D01*
X138163Y332635D01*
X138330Y332843D01*
X138580Y333010D01*
X138871Y333052D01*
X139121Y333010D01*
X139371Y332843D01*
X139580Y332593D01*
X139663Y332302D01*
X139580Y331968D01*
X139330Y331677D01*
X138955Y331510D01*
X138538Y331468D01*
X137996Y331552D01*
X137705Y331677D01*
X137413Y331885D01*
X137205Y332177D01*
X137163Y332468D01*
X137246Y332760D01*
X137455Y332968D01*
G01X139663Y335277D02*
X139121Y335360D01*
X138663Y335485D01*
X138246Y335652D01*
X137788Y335860D01*
X137163Y336193D01*
Y334527D01*
G01X138621Y337668D02*
X138330Y337960D01*
X138163Y338210D01*
X138080Y338543D01*
X138163Y338835D01*
X138330Y339043D01*
X138580Y339210D01*
X138871Y339252D01*
X139121Y339210D01*
X139371Y339043D01*
X139580Y338793D01*
X139663Y338502D01*
X139580Y338168D01*
X139330Y337877D01*
X138955Y337710D01*
X138538Y337668D01*
X137996Y337752D01*
X137705Y337877D01*
X137413Y338085D01*
X137205Y338377D01*
X137163Y338668D01*
X137246Y338960D01*
X137455Y339168D01*
G01X135467Y449725D02*
X135675Y450058D01*
X135800Y450433D01*
Y450767D01*
X135675Y451100D01*
X135467Y451350D01*
X135175Y451475D01*
X134883Y451392D01*
X134633Y451183D01*
X134467Y450808D01*
X134383Y450308D01*
X134217Y450017D01*
X133925Y449892D01*
X133633Y449975D01*
X133425Y450183D01*
X133300Y450475D01*
Y450767D01*
X133383Y451058D01*
X133592Y451308D01*
G01X135800Y452867D02*
X133300D01*
Y453908D01*
X133425Y454242D01*
X133592Y454450D01*
X133925Y454533D01*
X134258Y454450D01*
X134467Y454200D01*
X134592Y453908D01*
Y452867D01*
G01Y453908D02*
X135800Y454533D01*
G01Y456800D02*
X135758Y457092D01*
X135633Y457425D01*
X135425Y457633D01*
X135133Y457717D01*
X134842Y457633D01*
X134592Y457383D01*
X134467Y457008D01*
Y456592D01*
X134383Y456342D01*
X134175Y456133D01*
X133883Y456050D01*
X133592Y456175D01*
X133383Y456467D01*
X133300Y456800D01*
X133383Y457133D01*
X133592Y457425D01*
X133883Y457550D01*
X134175Y457467D01*
X134383Y457258D01*
X134467Y457008D01*
Y456592D01*
X134592Y456217D01*
X134842Y455967D01*
X135133Y455883D01*
X135425Y455967D01*
X135633Y456175D01*
X135758Y456508D01*
X135800Y456800D01*
G01X135425Y458983D02*
X135633Y459233D01*
X135758Y459525D01*
X135800Y459900D01*
X135717Y460275D01*
X135550Y460567D01*
X135258Y460775D01*
X134925Y460817D01*
X134592Y460733D01*
X134383Y460525D01*
X134217Y460233D01*
X134175Y459942D01*
X134217Y459650D01*
X134383Y459275D01*
X133300Y459400D01*
Y460525D01*
G01Y463000D02*
X133383Y462667D01*
X133592Y462417D01*
X133842Y462250D01*
X134175Y462125D01*
X134550Y462083D01*
X134925Y462125D01*
X135258Y462250D01*
X135508Y462417D01*
X135717Y462667D01*
X135800Y463000D01*
X135717Y463333D01*
X135508Y463583D01*
X135258Y463750D01*
X134925Y463875D01*
X134550Y463917D01*
X134175Y463875D01*
X133842Y463750D01*
X133592Y463583D01*
X133383Y463333D01*
X133300Y463000D01*
G01X146225Y483633D02*
X146558Y483425D01*
X146933Y483300D01*
X147267D01*
X147600Y483425D01*
X147850Y483633D01*
X147975Y483925D01*
X147892Y484217D01*
X147683Y484467D01*
X147308Y484633D01*
X146808Y484717D01*
X146517Y484883D01*
X146392Y485175D01*
X146475Y485467D01*
X146683Y485675D01*
X146975Y485800D01*
X147267D01*
X147558Y485717D01*
X147808Y485508D01*
G01X149367Y483300D02*
Y485800D01*
X150408D01*
X150742Y485675D01*
X150950Y485508D01*
X151033Y485175D01*
X150950Y484842D01*
X150700Y484633D01*
X150408Y484508D01*
X149367D01*
G01X150408D02*
X151033Y483300D01*
G01X153300D02*
X153592Y483342D01*
X153925Y483467D01*
X154133Y483675D01*
X154217Y483967D01*
X154133Y484258D01*
X153883Y484508D01*
X153508Y484633D01*
X153092D01*
X152842Y484717D01*
X152633Y484925D01*
X152550Y485217D01*
X152675Y485508D01*
X152967Y485717D01*
X153300Y485800D01*
X153633Y485717D01*
X153925Y485508D01*
X154050Y485217D01*
X153967Y484925D01*
X153758Y484717D01*
X153508Y484633D01*
X153092D01*
X152717Y484508D01*
X152467Y484258D01*
X152383Y483967D01*
X152467Y483675D01*
X152675Y483467D01*
X153008Y483342D01*
X153300Y483300D01*
G01X156900D02*
Y485800D01*
X155358Y484008D01*
X157442D01*
G01X159500Y483300D02*
Y485800D01*
X159000Y485300D01*
G01Y483300D02*
X160000D01*
G01X143175Y479633D02*
X143508Y479425D01*
X143883Y479300D01*
X144217D01*
X144550Y479425D01*
X144800Y479633D01*
X144925Y479925D01*
X144842Y480217D01*
X144633Y480467D01*
X144258Y480633D01*
X143758Y480717D01*
X143467Y480883D01*
X143342Y481175D01*
X143425Y481467D01*
X143633Y481675D01*
X143925Y481800D01*
X144217D01*
X144508Y481717D01*
X144758Y481508D01*
G01X148067Y481592D02*
X147817Y481717D01*
X147525Y481800D01*
X147192D01*
X146817Y481675D01*
X146525Y481467D01*
X146317Y481217D01*
X146150Y480800D01*
X146108Y480425D01*
X146192Y480050D01*
X146317Y479800D01*
X146567Y479550D01*
X146858Y479383D01*
X147150Y479300D01*
X147442D01*
X147733Y479383D01*
X147983Y479508D01*
X148192Y479675D01*
G01X150250Y479300D02*
Y481800D01*
X149750Y481300D01*
G01Y479300D02*
X150750D01*
G01X152433Y479800D02*
X152683Y479508D01*
X153017Y479342D01*
X153392Y479300D01*
X153725Y479342D01*
X154058Y479550D01*
X154267Y479800D01*
X154308Y480050D01*
X154225Y480342D01*
X153933Y480550D01*
X153642Y480633D01*
X153267D01*
G01X153642D02*
X153892Y480758D01*
X154100Y480967D01*
X154183Y481217D01*
X154100Y481467D01*
X153892Y481675D01*
X153517Y481800D01*
X153142Y481758D01*
X152767Y481592D01*
G01X156450Y481800D02*
X156117Y481717D01*
X155867Y481508D01*
X155700Y481258D01*
X155575Y480925D01*
X155533Y480550D01*
X155575Y480175D01*
X155700Y479842D01*
X155867Y479592D01*
X156117Y479383D01*
X156450Y479300D01*
X156783Y479383D01*
X157033Y479592D01*
X157200Y479842D01*
X157325Y480175D01*
X157367Y480550D01*
X157325Y480925D01*
X157200Y481258D01*
X157033Y481508D01*
X156783Y481717D01*
X156450Y481800D01*
G01X159550Y479300D02*
Y481800D01*
X159050Y481300D01*
G01Y479300D02*
X160050D01*
G01X146225Y488133D02*
X146558Y487925D01*
X146933Y487800D01*
X147267D01*
X147600Y487925D01*
X147850Y488133D01*
X147975Y488425D01*
X147892Y488717D01*
X147683Y488967D01*
X147308Y489133D01*
X146808Y489217D01*
X146517Y489383D01*
X146392Y489675D01*
X146475Y489967D01*
X146683Y490175D01*
X146975Y490300D01*
X147267D01*
X147558Y490217D01*
X147808Y490008D01*
G01X149367Y487800D02*
Y490300D01*
X150408D01*
X150742Y490175D01*
X150950Y490008D01*
X151033Y489675D01*
X150950Y489342D01*
X150700Y489133D01*
X150408Y489008D01*
X149367D01*
G01X150408D02*
X151033Y487800D01*
G01X152592Y488092D02*
X152883Y487883D01*
X153217Y487800D01*
X153550Y487883D01*
X153842Y488133D01*
X154050Y488508D01*
X154133Y488883D01*
Y489342D01*
X154050Y489717D01*
X153842Y490050D01*
X153592Y490217D01*
X153300Y490300D01*
X152967Y490217D01*
X152717Y490050D01*
X152550Y489800D01*
X152467Y489467D01*
X152550Y489175D01*
X152758Y488883D01*
X153008Y488717D01*
X153300Y488675D01*
X153633Y488758D01*
X153883Y488967D01*
X154133Y489342D01*
G01X155483Y488300D02*
X155733Y488008D01*
X156067Y487842D01*
X156442Y487800D01*
X156775Y487842D01*
X157108Y488050D01*
X157317Y488300D01*
X157358Y488550D01*
X157275Y488842D01*
X156983Y489050D01*
X156692Y489133D01*
X156317D01*
G01X156692D02*
X156942Y489258D01*
X157150Y489467D01*
X157233Y489717D01*
X157150Y489967D01*
X156942Y490175D01*
X156567Y490300D01*
X156192Y490258D01*
X155817Y490092D01*
G01X158792Y488092D02*
X159083Y487883D01*
X159417Y487800D01*
X159750Y487883D01*
X160042Y488133D01*
X160250Y488508D01*
X160333Y488883D01*
Y489342D01*
X160250Y489717D01*
X160042Y490050D01*
X159792Y490217D01*
X159500Y490300D01*
X159167Y490217D01*
X158917Y490050D01*
X158750Y489800D01*
X158667Y489467D01*
X158750Y489175D01*
X158958Y488883D01*
X159208Y488717D01*
X159500Y488675D01*
X159833Y488758D01*
X160083Y488967D01*
X160333Y489342D01*
G01X151055Y537900D02*
X151013Y537567D01*
X150847Y537275D01*
X150597Y537025D01*
X150305Y536858D01*
X149972Y536775D01*
X149638D01*
X149305Y536858D01*
X149013Y537025D01*
X148763Y537275D01*
X148597Y537567D01*
X148555Y537900D01*
X148597Y538233D01*
X148763Y538525D01*
X149013Y538775D01*
X149305Y538942D01*
X149638Y539025D01*
X149972D01*
X150305Y538942D01*
X150597Y538775D01*
X150847Y538525D01*
X151013Y538233D01*
X151055Y537900D01*
G01X150388Y538233D02*
X151055Y538733D01*
G01Y541000D02*
X148555D01*
X149055Y540500D01*
G01X151055D02*
Y541500D01*
G01X150680Y543183D02*
X150888Y543433D01*
X151013Y543725D01*
X151055Y544100D01*
X150972Y544475D01*
X150805Y544767D01*
X150513Y544975D01*
X150180Y545017D01*
X149847Y544933D01*
X149638Y544725D01*
X149472Y544433D01*
X149430Y544142D01*
X149472Y543850D01*
X149638Y543475D01*
X148555Y543600D01*
Y544725D01*
G01X146500Y645517D02*
X144000D01*
Y646558D01*
X144125Y646892D01*
X144292Y647100D01*
X144625Y647183D01*
X144958Y647100D01*
X145167Y646850D01*
X145292Y646558D01*
Y645517D01*
G01Y646558D02*
X146500Y647183D01*
G01Y649450D02*
X146458Y649742D01*
X146333Y650075D01*
X146125Y650283D01*
X145833Y650367D01*
X145542Y650283D01*
X145292Y650033D01*
X145167Y649658D01*
Y649242D01*
X145083Y648992D01*
X144875Y648783D01*
X144583Y648700D01*
X144292Y648825D01*
X144083Y649117D01*
X144000Y649450D01*
X144083Y649783D01*
X144292Y650075D01*
X144583Y650200D01*
X144875Y650117D01*
X145083Y649908D01*
X145167Y649658D01*
Y649242D01*
X145292Y648867D01*
X145542Y648617D01*
X145833Y648533D01*
X146125Y648617D01*
X146333Y648825D01*
X146458Y649158D01*
X146500Y649450D01*
G01X144000Y652550D02*
X144083Y652217D01*
X144292Y651967D01*
X144542Y651800D01*
X144875Y651675D01*
X145250Y651633D01*
X145625Y651675D01*
X145958Y651800D01*
X146208Y651967D01*
X146417Y652217D01*
X146500Y652550D01*
X146417Y652883D01*
X146208Y653133D01*
X145958Y653300D01*
X145625Y653425D01*
X145250Y653467D01*
X144875Y653425D01*
X144542Y653300D01*
X144292Y653133D01*
X144083Y652883D01*
X144000Y652550D01*
G01X146125Y654733D02*
X146333Y654983D01*
X146458Y655275D01*
X146500Y655650D01*
X146417Y656025D01*
X146250Y656317D01*
X145958Y656525D01*
X145625Y656567D01*
X145292Y656483D01*
X145083Y656275D01*
X144917Y655983D01*
X144875Y655692D01*
X144917Y655400D01*
X145083Y655025D01*
X144000Y655150D01*
Y656275D01*
G01X139667Y644875D02*
X139875Y645208D01*
X140000Y645583D01*
Y645917D01*
X139875Y646250D01*
X139667Y646500D01*
X139375Y646625D01*
X139083Y646542D01*
X138833Y646333D01*
X138667Y645958D01*
X138583Y645458D01*
X138417Y645167D01*
X138125Y645042D01*
X137833Y645125D01*
X137625Y645333D01*
X137500Y645625D01*
Y645917D01*
X137583Y646208D01*
X137792Y646458D01*
G01X140000Y648017D02*
X137500D01*
Y649058D01*
X137625Y649392D01*
X137792Y649600D01*
X138125Y649683D01*
X138458Y649600D01*
X138667Y649350D01*
X138792Y649058D01*
Y648017D01*
G01Y649058D02*
X140000Y649683D01*
G01Y651950D02*
X137500D01*
X138000Y651450D01*
G01X140000D02*
Y652450D01*
G01X137917Y654258D02*
X137667Y654508D01*
X137542Y654800D01*
X137500Y655133D01*
X137583Y655550D01*
X137792Y655842D01*
X138042Y655925D01*
X138292Y655883D01*
X138500Y655717D01*
X138917Y654883D01*
X139208Y654508D01*
X139625Y654258D01*
X140000Y654175D01*
Y655925D01*
G01Y658067D02*
X139458Y658150D01*
X139000Y658275D01*
X138583Y658442D01*
X138125Y658650D01*
X137500Y658983D01*
Y657317D01*
G01X139708Y660542D02*
X139917Y660833D01*
X140000Y661167D01*
X139917Y661500D01*
X139667Y661792D01*
X139292Y662000D01*
X138917Y662083D01*
X138458D01*
X138083Y662000D01*
X137750Y661792D01*
X137583Y661542D01*
X137500Y661250D01*
X137583Y660917D01*
X137750Y660667D01*
X138000Y660500D01*
X138333Y660417D01*
X138625Y660500D01*
X138917Y660708D01*
X139083Y660958D01*
X139125Y661250D01*
X139042Y661583D01*
X138833Y661833D01*
X138458Y662083D01*
G01X137000Y684000D02*
Y670000D01*
G01D02*
X150000D01*
G01X148700Y664500D02*
Y668500D01*
X141300D01*
G01X133300D02*
Y664500D01*
X140700D01*
G01X137000Y699210D02*
Y685210D01*
G01D02*
X150000D01*
G01Y684000D02*
X137000D01*
G01X150000Y699210D02*
X137000D01*
G01X149667Y701875D02*
X149875Y702208D01*
X150000Y702583D01*
Y702917D01*
X149875Y703250D01*
X149667Y703500D01*
X149375Y703625D01*
X149083Y703542D01*
X148833Y703333D01*
X148667Y702958D01*
X148583Y702458D01*
X148417Y702167D01*
X148125Y702042D01*
X147833Y702125D01*
X147625Y702333D01*
X147500Y702625D01*
Y702917D01*
X147583Y703208D01*
X147792Y703458D01*
G01X150000Y705017D02*
X147500D01*
Y706058D01*
X147625Y706392D01*
X147792Y706600D01*
X148125Y706683D01*
X148458Y706600D01*
X148667Y706350D01*
X148792Y706058D01*
Y705017D01*
G01Y706058D02*
X150000Y706683D01*
G01Y708950D02*
X147500D01*
X148000Y708450D01*
G01X150000D02*
Y709450D01*
G01X147917Y711258D02*
X147667Y711508D01*
X147542Y711800D01*
X147500Y712133D01*
X147583Y712550D01*
X147792Y712842D01*
X148042Y712925D01*
X148292Y712883D01*
X148500Y712717D01*
X148917Y711883D01*
X149208Y711508D01*
X149625Y711258D01*
X150000Y711175D01*
Y712925D01*
G01Y715067D02*
X149458Y715150D01*
X149000Y715275D01*
X148583Y715442D01*
X148125Y715650D01*
X147500Y715983D01*
Y714317D01*
G01X148958Y717458D02*
X148667Y717750D01*
X148500Y718000D01*
X148417Y718333D01*
X148500Y718625D01*
X148667Y718833D01*
X148917Y719000D01*
X149208Y719042D01*
X149458Y719000D01*
X149708Y718833D01*
X149917Y718583D01*
X150000Y718292D01*
X149917Y717958D01*
X149667Y717667D01*
X149292Y717500D01*
X148875Y717458D01*
X148333Y717542D01*
X148042Y717667D01*
X147750Y717875D01*
X147542Y718167D01*
X147500Y718458D01*
X147583Y718750D01*
X147792Y718958D01*
G01X141500Y700800D02*
X145500D01*
Y708200D01*
G01X148821Y790720D02*
Y793220D01*
X149862D01*
X150196Y793095D01*
X150404Y792928D01*
X150487Y792595D01*
X150404Y792262D01*
X150154Y792053D01*
X149862Y791928D01*
X148821D01*
G01X149862D02*
X150487Y790720D01*
G01X151837Y791095D02*
X152087Y790887D01*
X152379Y790762D01*
X152754Y790720D01*
X153129Y790803D01*
X153421Y790970D01*
X153629Y791262D01*
X153671Y791595D01*
X153587Y791928D01*
X153379Y792137D01*
X153087Y792303D01*
X152796Y792345D01*
X152504Y792303D01*
X152129Y792137D01*
X152254Y793220D01*
X153379D01*
G01X155062Y791762D02*
X155354Y792053D01*
X155604Y792220D01*
X155937Y792303D01*
X156229Y792220D01*
X156437Y792053D01*
X156604Y791803D01*
X156646Y791512D01*
X156604Y791262D01*
X156437Y791012D01*
X156187Y790803D01*
X155896Y790720D01*
X155562Y790803D01*
X155271Y791053D01*
X155104Y791428D01*
X155062Y791845D01*
X155146Y792387D01*
X155271Y792678D01*
X155479Y792970D01*
X155771Y793178D01*
X156062Y793220D01*
X156354Y793137D01*
X156562Y792928D01*
G01X158037Y791095D02*
X158287Y790887D01*
X158579Y790762D01*
X158954Y790720D01*
X159329Y790803D01*
X159621Y790970D01*
X159829Y791262D01*
X159871Y791595D01*
X159787Y791928D01*
X159579Y792137D01*
X159287Y792303D01*
X158996Y792345D01*
X158704Y792303D01*
X158329Y792137D01*
X158454Y793220D01*
X159579D01*
G01X143004Y789720D02*
Y793720D01*
X135604D01*
G01X148821Y781720D02*
Y784220D01*
X149862D01*
X150196Y784095D01*
X150404Y783928D01*
X150487Y783595D01*
X150404Y783262D01*
X150154Y783053D01*
X149862Y782928D01*
X148821D01*
G01X149862D02*
X150487Y781720D01*
G01X151837Y782095D02*
X152087Y781887D01*
X152379Y781762D01*
X152754Y781720D01*
X153129Y781803D01*
X153421Y781970D01*
X153629Y782262D01*
X153671Y782595D01*
X153587Y782928D01*
X153379Y783137D01*
X153087Y783303D01*
X152796Y783345D01*
X152504Y783303D01*
X152129Y783137D01*
X152254Y784220D01*
X153379D01*
G01X155062Y782762D02*
X155354Y783053D01*
X155604Y783220D01*
X155937Y783303D01*
X156229Y783220D01*
X156437Y783053D01*
X156604Y782803D01*
X156646Y782512D01*
X156604Y782262D01*
X156437Y782012D01*
X156187Y781803D01*
X155896Y781720D01*
X155562Y781803D01*
X155271Y782053D01*
X155104Y782428D01*
X155062Y782845D01*
X155146Y783387D01*
X155271Y783678D01*
X155479Y783970D01*
X155771Y784178D01*
X156062Y784220D01*
X156354Y784137D01*
X156562Y783928D01*
G01X158954Y781720D02*
X159246Y781762D01*
X159579Y781887D01*
X159787Y782095D01*
X159871Y782387D01*
X159787Y782678D01*
X159537Y782928D01*
X159162Y783053D01*
X158746D01*
X158496Y783137D01*
X158287Y783345D01*
X158204Y783637D01*
X158329Y783928D01*
X158621Y784137D01*
X158954Y784220D01*
X159287Y784137D01*
X159579Y783928D01*
X159704Y783637D01*
X159621Y783345D01*
X159412Y783137D01*
X159162Y783053D01*
X158746D01*
X158371Y782928D01*
X158121Y782678D01*
X158037Y782387D01*
X158121Y782095D01*
X158329Y781887D01*
X158662Y781762D01*
X158954Y781720D01*
G01X143004D02*
Y785720D01*
X135604D01*
G01X148771Y807220D02*
Y809720D01*
X149812D01*
X150146Y809595D01*
X150354Y809428D01*
X150437Y809095D01*
X150354Y808762D01*
X150104Y808553D01*
X149812Y808428D01*
X148771D01*
G01X149812D02*
X150437Y807220D01*
G01X151787Y807595D02*
X152037Y807387D01*
X152329Y807262D01*
X152704Y807220D01*
X153079Y807303D01*
X153371Y807470D01*
X153579Y807762D01*
X153621Y808095D01*
X153537Y808428D01*
X153329Y808637D01*
X153037Y808803D01*
X152746Y808845D01*
X152454Y808803D01*
X152079Y808637D01*
X152204Y809720D01*
X153329D01*
G01X154887Y807720D02*
X155137Y807428D01*
X155471Y807262D01*
X155846Y807220D01*
X156179Y807262D01*
X156512Y807470D01*
X156721Y807720D01*
X156762Y807970D01*
X156679Y808262D01*
X156387Y808470D01*
X156096Y808553D01*
X155721D01*
G01X156096D02*
X156346Y808678D01*
X156554Y808887D01*
X156637Y809137D01*
X156554Y809387D01*
X156346Y809595D01*
X155971Y809720D01*
X155596Y809678D01*
X155221Y809512D01*
G01X158904Y807220D02*
Y809720D01*
X158404Y809220D01*
G01Y807220D02*
X159404D01*
G01X162004Y809720D02*
X161671Y809637D01*
X161421Y809428D01*
X161254Y809178D01*
X161129Y808845D01*
X161087Y808470D01*
X161129Y808095D01*
X161254Y807762D01*
X161421Y807512D01*
X161671Y807303D01*
X162004Y807220D01*
X162337Y807303D01*
X162587Y807512D01*
X162754Y807762D01*
X162879Y808095D01*
X162921Y808470D01*
X162879Y808845D01*
X162754Y809178D01*
X162587Y809428D01*
X162337Y809637D01*
X162004Y809720D01*
G01X135604Y810220D02*
Y806220D01*
X143004D01*
G01X148771Y802220D02*
Y804720D01*
X149812D01*
X150146Y804595D01*
X150354Y804428D01*
X150437Y804095D01*
X150354Y803762D01*
X150104Y803553D01*
X149812Y803428D01*
X148771D01*
G01X149812D02*
X150437Y802220D01*
G01X151787Y802595D02*
X152037Y802387D01*
X152329Y802262D01*
X152704Y802220D01*
X153079Y802303D01*
X153371Y802470D01*
X153579Y802762D01*
X153621Y803095D01*
X153537Y803428D01*
X153329Y803637D01*
X153037Y803803D01*
X152746Y803845D01*
X152454Y803803D01*
X152079Y803637D01*
X152204Y804720D01*
X153329D01*
G01X154887Y802720D02*
X155137Y802428D01*
X155471Y802262D01*
X155846Y802220D01*
X156179Y802262D01*
X156512Y802470D01*
X156721Y802720D01*
X156762Y802970D01*
X156679Y803262D01*
X156387Y803470D01*
X156096Y803553D01*
X155721D01*
G01X156096D02*
X156346Y803678D01*
X156554Y803887D01*
X156637Y804137D01*
X156554Y804387D01*
X156346Y804595D01*
X155971Y804720D01*
X155596Y804678D01*
X155221Y804512D01*
G01X158904Y802220D02*
Y804720D01*
X158404Y804220D01*
G01Y802220D02*
X159404D01*
G01X162004D02*
Y804720D01*
X161504Y804220D01*
G01Y802220D02*
X162504D01*
G01X135604Y805720D02*
Y801720D01*
X143004D01*
G01X148821Y797720D02*
Y800220D01*
X149862D01*
X150196Y800095D01*
X150404Y799928D01*
X150487Y799595D01*
X150404Y799262D01*
X150154Y799053D01*
X149862Y798928D01*
X148821D01*
G01X149862D02*
X150487Y797720D01*
G01X151837Y798095D02*
X152087Y797887D01*
X152379Y797762D01*
X152754Y797720D01*
X153129Y797803D01*
X153421Y797970D01*
X153629Y798262D01*
X153671Y798595D01*
X153587Y798928D01*
X153379Y799137D01*
X153087Y799303D01*
X152796Y799345D01*
X152504Y799303D01*
X152129Y799137D01*
X152254Y800220D01*
X153379D01*
G01X155062Y798762D02*
X155354Y799053D01*
X155604Y799220D01*
X155937Y799303D01*
X156229Y799220D01*
X156437Y799053D01*
X156604Y798803D01*
X156646Y798512D01*
X156604Y798262D01*
X156437Y798012D01*
X156187Y797803D01*
X155896Y797720D01*
X155562Y797803D01*
X155271Y798053D01*
X155104Y798428D01*
X155062Y798845D01*
X155146Y799387D01*
X155271Y799678D01*
X155479Y799970D01*
X155771Y800178D01*
X156062Y800220D01*
X156354Y800137D01*
X156562Y799928D01*
G01X158162Y798762D02*
X158454Y799053D01*
X158704Y799220D01*
X159037Y799303D01*
X159329Y799220D01*
X159537Y799053D01*
X159704Y798803D01*
X159746Y798512D01*
X159704Y798262D01*
X159537Y798012D01*
X159287Y797803D01*
X158996Y797720D01*
X158662Y797803D01*
X158371Y798053D01*
X158204Y798428D01*
X158162Y798845D01*
X158246Y799387D01*
X158371Y799678D01*
X158579Y799970D01*
X158871Y800178D01*
X159162Y800220D01*
X159454Y800137D01*
X159662Y799928D01*
G01X135604Y801720D02*
Y797720D01*
X143004D01*
G01X148821Y812220D02*
Y814720D01*
X149862D01*
X150196Y814595D01*
X150404Y814428D01*
X150487Y814095D01*
X150404Y813762D01*
X150154Y813553D01*
X149862Y813428D01*
X148821D01*
G01X149862D02*
X150487Y812220D01*
G01X151837Y812595D02*
X152087Y812387D01*
X152379Y812262D01*
X152754Y812220D01*
X153129Y812303D01*
X153421Y812470D01*
X153629Y812762D01*
X153671Y813095D01*
X153587Y813428D01*
X153379Y813637D01*
X153087Y813803D01*
X152796Y813845D01*
X152504Y813803D01*
X152129Y813637D01*
X152254Y814720D01*
X153379D01*
G01X155771Y812220D02*
X155854Y812762D01*
X155979Y813220D01*
X156146Y813637D01*
X156354Y814095D01*
X156687Y814720D01*
X155021D01*
G01X158162Y814303D02*
X158412Y814553D01*
X158704Y814678D01*
X159037Y814720D01*
X159454Y814637D01*
X159746Y814428D01*
X159829Y814178D01*
X159787Y813928D01*
X159621Y813720D01*
X158787Y813303D01*
X158412Y813012D01*
X158162Y812595D01*
X158079Y812220D01*
X159829D01*
G01X135604Y814720D02*
Y810720D01*
X143004D01*
G01X133700Y838800D02*
Y849000D01*
G01X138300Y838800D02*
X133700D01*
G01X138300Y849700D02*
Y838800D01*
G01X146925Y832333D02*
X147258Y832125D01*
X147633Y832000D01*
X147967D01*
X148300Y832125D01*
X148550Y832333D01*
X148675Y832625D01*
X148592Y832917D01*
X148383Y833167D01*
X148008Y833333D01*
X147508Y833417D01*
X147217Y833583D01*
X147092Y833875D01*
X147175Y834167D01*
X147383Y834375D01*
X147675Y834500D01*
X147967D01*
X148258Y834417D01*
X148508Y834208D01*
G01X150067Y832000D02*
Y834500D01*
X151108D01*
X151442Y834375D01*
X151650Y834208D01*
X151733Y833875D01*
X151650Y833542D01*
X151400Y833333D01*
X151108Y833208D01*
X150067D01*
G01X151108D02*
X151733Y832000D01*
G01X154000D02*
X154292Y832042D01*
X154625Y832167D01*
X154833Y832375D01*
X154917Y832667D01*
X154833Y832958D01*
X154583Y833208D01*
X154208Y833333D01*
X153792D01*
X153542Y833417D01*
X153333Y833625D01*
X153250Y833917D01*
X153375Y834208D01*
X153667Y834417D01*
X154000Y834500D01*
X154333Y834417D01*
X154625Y834208D01*
X154750Y833917D01*
X154667Y833625D01*
X154458Y833417D01*
X154208Y833333D01*
X153792D01*
X153417Y833208D01*
X153167Y832958D01*
X153083Y832667D01*
X153167Y832375D01*
X153375Y832167D01*
X153708Y832042D01*
X154000Y832000D01*
G01X157600D02*
Y834500D01*
X156058Y832708D01*
X158142D01*
G01X159408Y834083D02*
X159658Y834333D01*
X159950Y834458D01*
X160283Y834500D01*
X160700Y834417D01*
X160992Y834208D01*
X161075Y833958D01*
X161033Y833708D01*
X160867Y833500D01*
X160033Y833083D01*
X159658Y832792D01*
X159408Y832375D01*
X159325Y832000D01*
X161075D01*
G01X147300Y846000D02*
Y842000D01*
X154700D01*
G01X146875Y837333D02*
X147208Y837125D01*
X147583Y837000D01*
X147917D01*
X148250Y837125D01*
X148500Y837333D01*
X148625Y837625D01*
X148542Y837917D01*
X148333Y838167D01*
X147958Y838333D01*
X147458Y838417D01*
X147167Y838583D01*
X147042Y838875D01*
X147125Y839167D01*
X147333Y839375D01*
X147625Y839500D01*
X147917D01*
X148208Y839417D01*
X148458Y839208D01*
G01X151767Y839292D02*
X151517Y839417D01*
X151225Y839500D01*
X150892D01*
X150517Y839375D01*
X150225Y839167D01*
X150017Y838917D01*
X149850Y838500D01*
X149808Y838125D01*
X149892Y837750D01*
X150017Y837500D01*
X150267Y837250D01*
X150558Y837083D01*
X150850Y837000D01*
X151142D01*
X151433Y837083D01*
X151683Y837208D01*
X151892Y837375D01*
G01X153950Y837000D02*
Y839500D01*
X153450Y839000D01*
G01Y837000D02*
X154450D01*
G01X156258Y839083D02*
X156508Y839333D01*
X156800Y839458D01*
X157133Y839500D01*
X157550Y839417D01*
X157842Y839208D01*
X157925Y838958D01*
X157883Y838708D01*
X157717Y838500D01*
X156883Y838083D01*
X156508Y837792D01*
X156258Y837375D01*
X156175Y837000D01*
X157925D01*
G01X160150D02*
X160442Y837042D01*
X160775Y837167D01*
X160983Y837375D01*
X161067Y837667D01*
X160983Y837958D01*
X160733Y838208D01*
X160358Y838333D01*
X159942D01*
X159692Y838417D01*
X159483Y838625D01*
X159400Y838917D01*
X159525Y839208D01*
X159817Y839417D01*
X160150Y839500D01*
X160483Y839417D01*
X160775Y839208D01*
X160900Y838917D01*
X160817Y838625D01*
X160608Y838417D01*
X160358Y838333D01*
X159942D01*
X159567Y838208D01*
X159317Y837958D01*
X159233Y837667D01*
X159317Y837375D01*
X159525Y837167D01*
X159858Y837042D01*
X160150Y837000D01*
G01X162458Y838042D02*
X162750Y838333D01*
X163000Y838500D01*
X163333Y838583D01*
X163625Y838500D01*
X163833Y838333D01*
X164000Y838083D01*
X164042Y837792D01*
X164000Y837542D01*
X163833Y837292D01*
X163583Y837083D01*
X163292Y837000D01*
X162958Y837083D01*
X162667Y837333D01*
X162500Y837708D01*
X162458Y838125D01*
X162542Y838667D01*
X162667Y838958D01*
X162875Y839250D01*
X163167Y839458D01*
X163458Y839500D01*
X163750Y839417D01*
X163958Y839208D01*
G01X188000Y855000D02*
X184500D01*
Y848500D01*
X173500D01*
Y853500D01*
X151500D01*
Y858000D01*
X134000D01*
Y872500D01*
X184000D01*
Y869500D01*
X187000D01*
G01X136000Y848500D02*
X137200Y849700D01*
G01X136000Y848500D02*
X134800Y849700D01*
G01X138217Y863292D02*
X137967Y863417D01*
X137675Y863500D01*
X137342D01*
X136967Y863375D01*
X136675Y863167D01*
X136467Y862917D01*
X136300Y862500D01*
X136258Y862125D01*
X136342Y861750D01*
X136467Y861500D01*
X136717Y861250D01*
X137008Y861083D01*
X137300Y861000D01*
X137592D01*
X137883Y861083D01*
X138133Y861208D01*
X138342Y861375D01*
G01X140317Y861000D02*
X140400Y861542D01*
X140525Y862000D01*
X140692Y862417D01*
X140900Y862875D01*
X141233Y863500D01*
X139567D01*
G01X142708Y863083D02*
X142958Y863333D01*
X143250Y863458D01*
X143583Y863500D01*
X144000Y863417D01*
X144292Y863208D01*
X144375Y862958D01*
X144333Y862708D01*
X144167Y862500D01*
X143333Y862083D01*
X142958Y861792D01*
X142708Y861375D01*
X142625Y861000D01*
X144375D01*
G01X146517D02*
X146600Y861542D01*
X146725Y862000D01*
X146892Y862417D01*
X147100Y862875D01*
X147433Y863500D01*
X145767D01*
G01X149700Y861000D02*
X149992Y861042D01*
X150325Y861167D01*
X150533Y861375D01*
X150617Y861667D01*
X150533Y861958D01*
X150283Y862208D01*
X149908Y862333D01*
X149492D01*
X149242Y862417D01*
X149033Y862625D01*
X148950Y862917D01*
X149075Y863208D01*
X149367Y863417D01*
X149700Y863500D01*
X150033Y863417D01*
X150325Y863208D01*
X150450Y862917D01*
X150367Y862625D01*
X150158Y862417D01*
X149908Y862333D01*
X149492D01*
X149117Y862208D01*
X148867Y861958D01*
X148783Y861667D01*
X148867Y861375D01*
X149075Y861167D01*
X149408Y861042D01*
X149700Y861000D01*
G01X137467Y865500D02*
Y868000D01*
X138508D01*
X138842Y867875D01*
X139050Y867708D01*
X139133Y867375D01*
X139050Y867042D01*
X138800Y866833D01*
X138508Y866708D01*
X137467D01*
G01X138508D02*
X139133Y865500D01*
G01X140692Y865792D02*
X140983Y865583D01*
X141317Y865500D01*
X141650Y865583D01*
X141942Y865833D01*
X142150Y866208D01*
X142233Y866583D01*
Y867042D01*
X142150Y867417D01*
X141942Y867750D01*
X141692Y867917D01*
X141400Y868000D01*
X141067Y867917D01*
X140817Y867750D01*
X140650Y867500D01*
X140567Y867167D01*
X140650Y866875D01*
X140858Y866583D01*
X141108Y866417D01*
X141400Y866375D01*
X141733Y866458D01*
X141983Y866667D01*
X142233Y867042D01*
G01X144500Y868000D02*
X144167Y867917D01*
X143917Y867708D01*
X143750Y867458D01*
X143625Y867125D01*
X143583Y866750D01*
X143625Y866375D01*
X143750Y866042D01*
X143917Y865792D01*
X144167Y865583D01*
X144500Y865500D01*
X144833Y865583D01*
X145083Y865792D01*
X145250Y866042D01*
X145375Y866375D01*
X145417Y866750D01*
X145375Y867125D01*
X145250Y867458D01*
X145083Y867708D01*
X144833Y867917D01*
X144500Y868000D01*
G01X146808Y867583D02*
X147058Y867833D01*
X147350Y867958D01*
X147683Y868000D01*
X148100Y867917D01*
X148392Y867708D01*
X148475Y867458D01*
X148433Y867208D01*
X148267Y867000D01*
X147433Y866583D01*
X147058Y866292D01*
X146808Y865875D01*
X146725Y865500D01*
X148475D01*
G01X150700D02*
Y868000D01*
X150200Y867500D01*
G01Y865500D02*
X151200D01*
G01X150800Y887367D02*
X148300D01*
Y888408D01*
X148425Y888742D01*
X148592Y888950D01*
X148925Y889033D01*
X149258Y888950D01*
X149467Y888700D01*
X149592Y888408D01*
Y887367D01*
G01Y888408D02*
X150800Y889033D01*
G01X148717Y890508D02*
X148467Y890758D01*
X148342Y891050D01*
X148300Y891383D01*
X148383Y891800D01*
X148592Y892092D01*
X148842Y892175D01*
X149092Y892133D01*
X149300Y891967D01*
X149717Y891133D01*
X150008Y890758D01*
X150425Y890508D01*
X150800Y890425D01*
Y892175D01*
G01Y894400D02*
X148300D01*
X148800Y893900D01*
G01X150800D02*
Y894900D01*
G01X148300Y897500D02*
X148383Y897167D01*
X148592Y896917D01*
X148842Y896750D01*
X149175Y896625D01*
X149550Y896583D01*
X149925Y896625D01*
X150258Y896750D01*
X150508Y896917D01*
X150717Y897167D01*
X150800Y897500D01*
X150717Y897833D01*
X150508Y898083D01*
X150258Y898250D01*
X149925Y898375D01*
X149550Y898417D01*
X149175Y898375D01*
X148842Y898250D01*
X148592Y898083D01*
X148383Y897833D01*
X148300Y897500D01*
G01X149758Y899808D02*
X149467Y900100D01*
X149300Y900350D01*
X149217Y900683D01*
X149300Y900975D01*
X149467Y901183D01*
X149717Y901350D01*
X150008Y901392D01*
X150258Y901350D01*
X150508Y901183D01*
X150717Y900933D01*
X150800Y900642D01*
X150717Y900308D01*
X150467Y900017D01*
X150092Y899850D01*
X149675Y899808D01*
X149133Y899892D01*
X148842Y900017D01*
X148550Y900225D01*
X148342Y900517D01*
X148300Y900808D01*
X148383Y901100D01*
X148592Y901308D01*
G01X146800Y887367D02*
X144300D01*
Y888408D01*
X144425Y888742D01*
X144592Y888950D01*
X144925Y889033D01*
X145258Y888950D01*
X145467Y888700D01*
X145592Y888408D01*
Y887367D01*
G01Y888408D02*
X146800Y889033D01*
G01X144717Y890508D02*
X144467Y890758D01*
X144342Y891050D01*
X144300Y891383D01*
X144383Y891800D01*
X144592Y892092D01*
X144842Y892175D01*
X145092Y892133D01*
X145300Y891967D01*
X145717Y891133D01*
X146008Y890758D01*
X146425Y890508D01*
X146800Y890425D01*
Y892175D01*
G01Y894400D02*
X144300D01*
X144800Y893900D01*
G01X146800D02*
Y894900D01*
G01X144300Y897500D02*
X144383Y897167D01*
X144592Y896917D01*
X144842Y896750D01*
X145175Y896625D01*
X145550Y896583D01*
X145925Y896625D01*
X146258Y896750D01*
X146508Y896917D01*
X146717Y897167D01*
X146800Y897500D01*
X146717Y897833D01*
X146508Y898083D01*
X146258Y898250D01*
X145925Y898375D01*
X145550Y898417D01*
X145175Y898375D01*
X144842Y898250D01*
X144592Y898083D01*
X144383Y897833D01*
X144300Y897500D01*
G01X146800Y900600D02*
X146758Y900892D01*
X146633Y901225D01*
X146425Y901433D01*
X146133Y901517D01*
X145842Y901433D01*
X145592Y901183D01*
X145467Y900808D01*
Y900392D01*
X145383Y900142D01*
X145175Y899933D01*
X144883Y899850D01*
X144592Y899975D01*
X144383Y900267D01*
X144300Y900600D01*
X144383Y900933D01*
X144592Y901225D01*
X144883Y901350D01*
X145175Y901267D01*
X145383Y901058D01*
X145467Y900808D01*
Y900392D01*
X145592Y900017D01*
X145842Y899767D01*
X146133Y899683D01*
X146425Y899767D01*
X146633Y899975D01*
X146758Y900308D01*
X146800Y900600D01*
G01X140008Y890617D02*
X139883Y890367D01*
X139800Y890075D01*
Y889742D01*
X139925Y889367D01*
X140133Y889075D01*
X140383Y888867D01*
X140800Y888700D01*
X141175Y888658D01*
X141550Y888742D01*
X141800Y888867D01*
X142050Y889117D01*
X142217Y889408D01*
X142300Y889700D01*
Y889992D01*
X142217Y890283D01*
X142092Y890533D01*
X141925Y890742D01*
G01X142300Y892717D02*
X141758Y892800D01*
X141300Y892925D01*
X140883Y893092D01*
X140425Y893300D01*
X139800Y893633D01*
Y891967D01*
G01X140217Y895108D02*
X139967Y895358D01*
X139842Y895650D01*
X139800Y895983D01*
X139883Y896400D01*
X140092Y896692D01*
X140342Y896775D01*
X140592Y896733D01*
X140800Y896567D01*
X141217Y895733D01*
X141508Y895358D01*
X141925Y895108D01*
X142300Y895025D01*
Y896775D01*
G01Y898917D02*
X141758Y899000D01*
X141300Y899125D01*
X140883Y899292D01*
X140425Y899500D01*
X139800Y899833D01*
Y898167D01*
G01X141925Y901183D02*
X142133Y901433D01*
X142258Y901725D01*
X142300Y902100D01*
X142217Y902475D01*
X142050Y902767D01*
X141758Y902975D01*
X141425Y903017D01*
X141092Y902933D01*
X140883Y902725D01*
X140717Y902433D01*
X140675Y902142D01*
X140717Y901850D01*
X140883Y901475D01*
X139800Y901600D01*
Y902725D01*
G01X169188Y-19106D02*
X165188D01*
X168055Y-21573D01*
Y-18239D01*
G01X150626Y227071D02*
Y272671D01*
X153376D01*
Y317971D01*
X224576D01*
Y272671D01*
X227326D01*
Y227071D01*
X150626D01*
G01X158793Y327863D02*
X158543Y327988D01*
X158251Y328071D01*
X157918D01*
X157543Y327946D01*
X157251Y327738D01*
X157043Y327488D01*
X156876Y327071D01*
X156834Y326696D01*
X156918Y326321D01*
X157043Y326071D01*
X157293Y325821D01*
X157584Y325654D01*
X157876Y325571D01*
X158168D01*
X158459Y325654D01*
X158709Y325779D01*
X158918Y325946D01*
G01X160018Y325571D02*
Y328071D01*
X161934Y325571D01*
Y328071D01*
G01X163284Y327654D02*
X163534Y327904D01*
X163826Y328029D01*
X164159Y328071D01*
X164576Y327988D01*
X164868Y327779D01*
X164951Y327529D01*
X164909Y327279D01*
X164743Y327071D01*
X163909Y326654D01*
X163534Y326363D01*
X163284Y325946D01*
X163201Y325571D01*
X164951D01*
G01X179900Y465350D02*
X162700D01*
Y475250D01*
X179900D01*
Y465350D01*
G01X163100Y459800D02*
Y455800D01*
X170500D01*
G01X157500Y472300D02*
Y476300D01*
X150100D01*
G01Y471800D02*
Y467800D01*
X157500D01*
G01X165245Y514250D02*
X179245D01*
G01X165245Y527250D02*
Y514250D01*
G01X158222Y511425D02*
X158430Y511758D01*
X158555Y512133D01*
Y512467D01*
X158430Y512800D01*
X158222Y513050D01*
X157930Y513175D01*
X157638Y513092D01*
X157388Y512883D01*
X157222Y512508D01*
X157138Y512008D01*
X156972Y511717D01*
X156680Y511592D01*
X156388Y511675D01*
X156180Y511883D01*
X156055Y512175D01*
Y512467D01*
X156138Y512758D01*
X156347Y513008D01*
G01X158555Y514567D02*
X156055D01*
Y515608D01*
X156180Y515942D01*
X156347Y516150D01*
X156680Y516233D01*
X157013Y516150D01*
X157222Y515900D01*
X157347Y515608D01*
Y514567D01*
G01Y515608D02*
X158555Y516233D01*
G01X158263Y517792D02*
X158472Y518083D01*
X158555Y518417D01*
X158472Y518750D01*
X158222Y519042D01*
X157847Y519250D01*
X157472Y519333D01*
X157013D01*
X156638Y519250D01*
X156305Y519042D01*
X156138Y518792D01*
X156055Y518500D01*
X156138Y518167D01*
X156305Y517917D01*
X156555Y517750D01*
X156888Y517667D01*
X157180Y517750D01*
X157472Y517958D01*
X157638Y518208D01*
X157680Y518500D01*
X157597Y518833D01*
X157388Y519083D01*
X157013Y519333D01*
G01X158555Y521600D02*
X156055D01*
X156555Y521100D01*
G01X158555D02*
Y522100D01*
G01X158180Y523783D02*
X158388Y524033D01*
X158513Y524325D01*
X158555Y524700D01*
X158472Y525075D01*
X158305Y525367D01*
X158013Y525575D01*
X157680Y525617D01*
X157347Y525533D01*
X157138Y525325D01*
X156972Y525033D01*
X156930Y524742D01*
X156972Y524450D01*
X157138Y524075D01*
X156055Y524200D01*
Y525325D01*
G01X153222Y511425D02*
X153430Y511758D01*
X153555Y512133D01*
Y512467D01*
X153430Y512800D01*
X153222Y513050D01*
X152930Y513175D01*
X152638Y513092D01*
X152388Y512883D01*
X152222Y512508D01*
X152138Y512008D01*
X151972Y511717D01*
X151680Y511592D01*
X151388Y511675D01*
X151180Y511883D01*
X151055Y512175D01*
Y512467D01*
X151138Y512758D01*
X151347Y513008D01*
G01X153555Y514567D02*
X151055D01*
Y515608D01*
X151180Y515942D01*
X151347Y516150D01*
X151680Y516233D01*
X152013Y516150D01*
X152222Y515900D01*
X152347Y515608D01*
Y514567D01*
G01Y515608D02*
X153555Y516233D01*
G01Y518500D02*
X153513Y518792D01*
X153388Y519125D01*
X153180Y519333D01*
X152888Y519417D01*
X152597Y519333D01*
X152347Y519083D01*
X152222Y518708D01*
Y518292D01*
X152138Y518042D01*
X151930Y517833D01*
X151638Y517750D01*
X151347Y517875D01*
X151138Y518167D01*
X151055Y518500D01*
X151138Y518833D01*
X151347Y519125D01*
X151638Y519250D01*
X151930Y519167D01*
X152138Y518958D01*
X152222Y518708D01*
Y518292D01*
X152347Y517917D01*
X152597Y517667D01*
X152888Y517583D01*
X153180Y517667D01*
X153388Y517875D01*
X153513Y518208D01*
X153555Y518500D01*
G01X153180Y520683D02*
X153388Y520933D01*
X153513Y521225D01*
X153555Y521600D01*
X153472Y521975D01*
X153305Y522267D01*
X153013Y522475D01*
X152680Y522517D01*
X152347Y522433D01*
X152138Y522225D01*
X151972Y521933D01*
X151930Y521642D01*
X151972Y521350D01*
X152138Y520975D01*
X151055Y521100D01*
Y522225D01*
G01X153555Y524617D02*
X153013Y524700D01*
X152555Y524825D01*
X152138Y524992D01*
X151680Y525200D01*
X151055Y525533D01*
Y523867D01*
G01X179245Y527250D02*
X165245D01*
G01X159855Y532000D02*
Y528000D01*
X167255D01*
G01X151855Y532000D02*
Y528000D01*
X159255D01*
G01X153055Y533000D02*
X166055D01*
G01X153055Y547000D02*
Y533000D01*
G01X166055Y547000D02*
X153055D01*
G01X157855Y552500D02*
Y548500D01*
X165255D01*
G01X153980Y554333D02*
X154313Y554125D01*
X154688Y554000D01*
X155022D01*
X155355Y554125D01*
X155605Y554333D01*
X155730Y554625D01*
X155647Y554917D01*
X155438Y555167D01*
X155063Y555333D01*
X154563Y555417D01*
X154272Y555583D01*
X154147Y555875D01*
X154230Y556167D01*
X154438Y556375D01*
X154730Y556500D01*
X155022D01*
X155313Y556417D01*
X155563Y556208D01*
G01X157122Y554000D02*
Y556500D01*
X158163D01*
X158497Y556375D01*
X158705Y556208D01*
X158788Y555875D01*
X158705Y555542D01*
X158455Y555333D01*
X158163Y555208D01*
X157122D01*
G01X158163D02*
X158788Y554000D01*
G01X160347Y554292D02*
X160638Y554083D01*
X160972Y554000D01*
X161305Y554083D01*
X161597Y554333D01*
X161805Y554708D01*
X161888Y555083D01*
Y555542D01*
X161805Y555917D01*
X161597Y556250D01*
X161347Y556417D01*
X161055Y556500D01*
X160722Y556417D01*
X160472Y556250D01*
X160305Y556000D01*
X160222Y555667D01*
X160305Y555375D01*
X160513Y555083D01*
X160763Y554917D01*
X161055Y554875D01*
X161388Y554958D01*
X161638Y555167D01*
X161888Y555542D01*
G01X164155Y554000D02*
Y556500D01*
X163655Y556000D01*
G01Y554000D02*
X164655D01*
G01X166463Y555042D02*
X166755Y555333D01*
X167005Y555500D01*
X167338Y555583D01*
X167630Y555500D01*
X167838Y555333D01*
X168005Y555083D01*
X168047Y554792D01*
X168005Y554542D01*
X167838Y554292D01*
X167588Y554083D01*
X167297Y554000D01*
X166963Y554083D01*
X166672Y554333D01*
X166505Y554708D01*
X166463Y555125D01*
X166547Y555667D01*
X166672Y555958D01*
X166880Y556250D01*
X167172Y556458D01*
X167463Y556500D01*
X167755Y556417D01*
X167963Y556208D01*
G01X163430Y581333D02*
X163763Y581125D01*
X164138Y581000D01*
X164472D01*
X164805Y581125D01*
X165055Y581333D01*
X165180Y581625D01*
X165097Y581917D01*
X164888Y582167D01*
X164513Y582333D01*
X164013Y582417D01*
X163722Y582583D01*
X163597Y582875D01*
X163680Y583167D01*
X163888Y583375D01*
X164180Y583500D01*
X164472D01*
X164763Y583417D01*
X165013Y583208D01*
G01X168322Y583292D02*
X168072Y583417D01*
X167780Y583500D01*
X167447D01*
X167072Y583375D01*
X166780Y583167D01*
X166572Y582917D01*
X166405Y582500D01*
X166363Y582125D01*
X166447Y581750D01*
X166572Y581500D01*
X166822Y581250D01*
X167113Y581083D01*
X167405Y581000D01*
X167697D01*
X167988Y581083D01*
X168238Y581208D01*
X168447Y581375D01*
G01X170505Y581000D02*
Y583500D01*
X170005Y583000D01*
G01Y581000D02*
X171005D01*
G01X173605D02*
Y583500D01*
X173105Y583000D01*
G01Y581000D02*
X174105D01*
G01X175913Y583083D02*
X176163Y583333D01*
X176455Y583458D01*
X176788Y583500D01*
X177205Y583417D01*
X177497Y583208D01*
X177580Y582958D01*
X177538Y582708D01*
X177372Y582500D01*
X176538Y582083D01*
X176163Y581792D01*
X175913Y581375D01*
X175830Y581000D01*
X177580D01*
G01X179013Y583083D02*
X179263Y583333D01*
X179555Y583458D01*
X179888Y583500D01*
X180305Y583417D01*
X180597Y583208D01*
X180680Y582958D01*
X180638Y582708D01*
X180472Y582500D01*
X179638Y582083D01*
X179263Y581792D01*
X179013Y581375D01*
X178930Y581000D01*
X180680D01*
G01X154208Y647767D02*
X154083Y647517D01*
X154000Y647225D01*
Y646892D01*
X154125Y646517D01*
X154333Y646225D01*
X154583Y646017D01*
X155000Y645850D01*
X155375Y645808D01*
X155750Y645892D01*
X156000Y646017D01*
X156250Y646267D01*
X156417Y646558D01*
X156500Y646850D01*
Y647142D01*
X156417Y647433D01*
X156292Y647683D01*
X156125Y647892D01*
G01X156000Y649033D02*
X156292Y649283D01*
X156458Y649617D01*
X156500Y649992D01*
X156458Y650325D01*
X156250Y650658D01*
X156000Y650867D01*
X155750Y650908D01*
X155458Y650825D01*
X155250Y650533D01*
X155167Y650242D01*
Y649867D01*
G01Y650242D02*
X155042Y650492D01*
X154833Y650700D01*
X154583Y650783D01*
X154333Y650700D01*
X154125Y650492D01*
X154000Y650117D01*
X154042Y649742D01*
X154208Y649367D01*
G01X156500Y652967D02*
X155958Y653050D01*
X155500Y653175D01*
X155083Y653342D01*
X154625Y653550D01*
X154000Y653883D01*
Y652217D01*
G01X156500Y656150D02*
X154000D01*
X154500Y655650D01*
G01X156500D02*
Y656650D01*
G01X161500Y651017D02*
X159000D01*
Y652058D01*
X159125Y652392D01*
X159292Y652600D01*
X159625Y652683D01*
X159958Y652600D01*
X160167Y652350D01*
X160292Y652058D01*
Y651017D01*
G01Y652058D02*
X161500Y652683D01*
G01Y655450D02*
X159000D01*
X160792Y653908D01*
Y655992D01*
G01X161500Y657967D02*
X160958Y658050D01*
X160500Y658175D01*
X160083Y658342D01*
X159625Y658550D01*
X159000Y658883D01*
Y657217D01*
G01X161000Y660233D02*
X161292Y660483D01*
X161458Y660817D01*
X161500Y661192D01*
X161458Y661525D01*
X161250Y661858D01*
X161000Y662067D01*
X160750Y662108D01*
X160458Y662025D01*
X160250Y661733D01*
X160167Y661442D01*
Y661067D01*
G01Y661442D02*
X160042Y661692D01*
X159833Y661900D01*
X159583Y661983D01*
X159333Y661900D01*
X159125Y661692D01*
X159000Y661317D01*
X159042Y660942D01*
X159208Y660567D01*
G01X166767Y661792D02*
X166517Y661917D01*
X166225Y662000D01*
X165892D01*
X165517Y661875D01*
X165225Y661667D01*
X165017Y661417D01*
X164850Y661000D01*
X164808Y660625D01*
X164892Y660250D01*
X165017Y660000D01*
X165267Y659750D01*
X165558Y659583D01*
X165850Y659500D01*
X166142D01*
X166433Y659583D01*
X166683Y659708D01*
X166892Y659875D01*
G01X168033Y660000D02*
X168283Y659708D01*
X168617Y659542D01*
X168992Y659500D01*
X169325Y659542D01*
X169658Y659750D01*
X169867Y660000D01*
X169908Y660250D01*
X169825Y660542D01*
X169533Y660750D01*
X169242Y660833D01*
X168867D01*
G01X169242D02*
X169492Y660958D01*
X169700Y661167D01*
X169783Y661417D01*
X169700Y661667D01*
X169492Y661875D01*
X169117Y662000D01*
X168742Y661958D01*
X168367Y661792D01*
G01X172050Y659500D02*
Y662000D01*
X171550Y661500D01*
G01Y659500D02*
X172550D01*
G01X174358Y660542D02*
X174650Y660833D01*
X174900Y661000D01*
X175233Y661083D01*
X175525Y661000D01*
X175733Y660833D01*
X175900Y660583D01*
X175942Y660292D01*
X175900Y660042D01*
X175733Y659792D01*
X175483Y659583D01*
X175192Y659500D01*
X174858Y659583D01*
X174567Y659833D01*
X174400Y660208D01*
X174358Y660625D01*
X174442Y661167D01*
X174567Y661458D01*
X174775Y661750D01*
X175067Y661958D01*
X175358Y662000D01*
X175650Y661917D01*
X175858Y661708D01*
G01X150000Y670000D02*
Y684000D01*
G01X156500D02*
Y670000D01*
G01D02*
X169500D01*
G01X151500Y676800D02*
X155500D01*
Y684200D01*
G01X151500Y668800D02*
X155500D01*
Y676200D01*
G01X155800Y668500D02*
Y664500D01*
X163200D01*
G01X156500Y699710D02*
Y685710D01*
G01D02*
X169500D01*
G01X150000Y685210D02*
Y699210D01*
G01X169500Y684000D02*
X156500D01*
G01X169500Y699710D02*
X156500D01*
G01X155167Y701875D02*
X155375Y702208D01*
X155500Y702583D01*
Y702917D01*
X155375Y703250D01*
X155167Y703500D01*
X154875Y703625D01*
X154583Y703542D01*
X154333Y703333D01*
X154167Y702958D01*
X154083Y702458D01*
X153917Y702167D01*
X153625Y702042D01*
X153333Y702125D01*
X153125Y702333D01*
X153000Y702625D01*
Y702917D01*
X153083Y703208D01*
X153292Y703458D01*
G01X155500Y705017D02*
X153000D01*
Y706058D01*
X153125Y706392D01*
X153292Y706600D01*
X153625Y706683D01*
X153958Y706600D01*
X154167Y706350D01*
X154292Y706058D01*
Y705017D01*
G01Y706058D02*
X155500Y706683D01*
G01Y708950D02*
X153000D01*
X153500Y708450D01*
G01X155500D02*
Y709450D01*
G01X153417Y711258D02*
X153167Y711508D01*
X153042Y711800D01*
X153000Y712133D01*
X153083Y712550D01*
X153292Y712842D01*
X153542Y712925D01*
X153792Y712883D01*
X154000Y712717D01*
X154417Y711883D01*
X154708Y711508D01*
X155125Y711258D01*
X155500Y711175D01*
Y712925D01*
G01Y715067D02*
X154958Y715150D01*
X154500Y715275D01*
X154083Y715442D01*
X153625Y715650D01*
X153000Y715983D01*
Y714317D01*
G01X153417Y717458D02*
X153167Y717708D01*
X153042Y718000D01*
X153000Y718333D01*
X153083Y718750D01*
X153292Y719042D01*
X153542Y719125D01*
X153792Y719083D01*
X154000Y718917D01*
X154417Y718083D01*
X154708Y717708D01*
X155125Y717458D01*
X155500Y717375D01*
Y719125D01*
G01X161000Y700800D02*
X165000D01*
Y708200D01*
G01X159118Y715909D02*
Y752909D01*
X291118D01*
Y715909D01*
X159118D01*
G01X152967Y855500D02*
Y858000D01*
X154008D01*
X154342Y857875D01*
X154550Y857708D01*
X154633Y857375D01*
X154550Y857042D01*
X154300Y856833D01*
X154008Y856708D01*
X152967D01*
G01X154008D02*
X154633Y855500D01*
G01X156192Y855792D02*
X156483Y855583D01*
X156817Y855500D01*
X157150Y855583D01*
X157442Y855833D01*
X157650Y856208D01*
X157733Y856583D01*
Y857042D01*
X157650Y857417D01*
X157442Y857750D01*
X157192Y857917D01*
X156900Y858000D01*
X156567Y857917D01*
X156317Y857750D01*
X156150Y857500D01*
X156067Y857167D01*
X156150Y856875D01*
X156358Y856583D01*
X156608Y856417D01*
X156900Y856375D01*
X157233Y856458D01*
X157483Y856667D01*
X157733Y857042D01*
G01X160000Y858000D02*
X159667Y857917D01*
X159417Y857708D01*
X159250Y857458D01*
X159125Y857125D01*
X159083Y856750D01*
X159125Y856375D01*
X159250Y856042D01*
X159417Y855792D01*
X159667Y855583D01*
X160000Y855500D01*
X160333Y855583D01*
X160583Y855792D01*
X160750Y856042D01*
X160875Y856375D01*
X160917Y856750D01*
X160875Y857125D01*
X160750Y857458D01*
X160583Y857708D01*
X160333Y857917D01*
X160000Y858000D01*
G01X162308Y857583D02*
X162558Y857833D01*
X162850Y857958D01*
X163183Y858000D01*
X163600Y857917D01*
X163892Y857708D01*
X163975Y857458D01*
X163933Y857208D01*
X163767Y857000D01*
X162933Y856583D01*
X162558Y856292D01*
X162308Y855875D01*
X162225Y855500D01*
X163975D01*
G01X165283Y856000D02*
X165533Y855708D01*
X165867Y855542D01*
X166242Y855500D01*
X166575Y855542D01*
X166908Y855750D01*
X167117Y856000D01*
X167158Y856250D01*
X167075Y856542D01*
X166783Y856750D01*
X166492Y856833D01*
X166117D01*
G01X166492D02*
X166742Y856958D01*
X166950Y857167D01*
X167033Y857417D01*
X166950Y857667D01*
X166742Y857875D01*
X166367Y858000D01*
X165992Y857958D01*
X165617Y857792D01*
G01X154717Y861792D02*
X154467Y861917D01*
X154175Y862000D01*
X153842D01*
X153467Y861875D01*
X153175Y861667D01*
X152967Y861417D01*
X152800Y861000D01*
X152758Y860625D01*
X152842Y860250D01*
X152967Y860000D01*
X153217Y859750D01*
X153508Y859583D01*
X153800Y859500D01*
X154092D01*
X154383Y859583D01*
X154633Y859708D01*
X154842Y859875D01*
G01X156817Y859500D02*
X156900Y860042D01*
X157025Y860500D01*
X157192Y860917D01*
X157400Y861375D01*
X157733Y862000D01*
X156067D01*
G01X159208Y861583D02*
X159458Y861833D01*
X159750Y861958D01*
X160083Y862000D01*
X160500Y861917D01*
X160792Y861708D01*
X160875Y861458D01*
X160833Y861208D01*
X160667Y861000D01*
X159833Y860583D01*
X159458Y860292D01*
X159208Y859875D01*
X159125Y859500D01*
X160875D01*
G01X163017D02*
X163100Y860042D01*
X163225Y860500D01*
X163392Y860917D01*
X163600Y861375D01*
X163933Y862000D01*
X162267D01*
G01X166117Y859500D02*
X166200Y860042D01*
X166325Y860500D01*
X166492Y860917D01*
X166700Y861375D01*
X167033Y862000D01*
X165367D01*
G01X152967Y864000D02*
Y866500D01*
X154008D01*
X154342Y866375D01*
X154550Y866208D01*
X154633Y865875D01*
X154550Y865542D01*
X154300Y865333D01*
X154008Y865208D01*
X152967D01*
G01X154008D02*
X154633Y864000D01*
G01X156108Y866083D02*
X156358Y866333D01*
X156650Y866458D01*
X156983Y866500D01*
X157400Y866417D01*
X157692Y866208D01*
X157775Y865958D01*
X157733Y865708D01*
X157567Y865500D01*
X156733Y865083D01*
X156358Y864792D01*
X156108Y864375D01*
X156025Y864000D01*
X157775D01*
G01X160000D02*
Y866500D01*
X159500Y866000D01*
G01Y864000D02*
X160500D01*
G01X163100D02*
Y866500D01*
X162600Y866000D01*
G01Y864000D02*
X163600D01*
G01X166117D02*
X166200Y864542D01*
X166325Y865000D01*
X166492Y865417D01*
X166700Y865875D01*
X167033Y866500D01*
X165367D01*
G01X152967Y868500D02*
Y871000D01*
X154008D01*
X154342Y870875D01*
X154550Y870708D01*
X154633Y870375D01*
X154550Y870042D01*
X154300Y869833D01*
X154008Y869708D01*
X152967D01*
G01X154008D02*
X154633Y868500D01*
G01X156108Y870583D02*
X156358Y870833D01*
X156650Y870958D01*
X156983Y871000D01*
X157400Y870917D01*
X157692Y870708D01*
X157775Y870458D01*
X157733Y870208D01*
X157567Y870000D01*
X156733Y869583D01*
X156358Y869292D01*
X156108Y868875D01*
X156025Y868500D01*
X157775D01*
G01X160000D02*
Y871000D01*
X159500Y870500D01*
G01Y868500D02*
X160500D01*
G01X163017D02*
X163100Y869042D01*
X163225Y869500D01*
X163392Y869917D01*
X163600Y870375D01*
X163933Y871000D01*
X162267D01*
G01X166200Y868500D02*
Y871000D01*
X165700Y870500D01*
G01Y868500D02*
X166700D01*
G01X167800Y884867D02*
X165300D01*
Y885908D01*
X165425Y886242D01*
X165592Y886450D01*
X165925Y886533D01*
X166258Y886450D01*
X166467Y886200D01*
X166592Y885908D01*
Y884867D01*
G01Y885908D02*
X167800Y886533D01*
G01X165717Y888008D02*
X165467Y888258D01*
X165342Y888550D01*
X165300Y888883D01*
X165383Y889300D01*
X165592Y889592D01*
X165842Y889675D01*
X166092Y889633D01*
X166300Y889467D01*
X166717Y888633D01*
X167008Y888258D01*
X167425Y888008D01*
X167800Y887925D01*
Y889675D01*
G01X165300Y891900D02*
X165383Y891567D01*
X165592Y891317D01*
X165842Y891150D01*
X166175Y891025D01*
X166550Y890983D01*
X166925Y891025D01*
X167258Y891150D01*
X167508Y891317D01*
X167717Y891567D01*
X167800Y891900D01*
X167717Y892233D01*
X167508Y892483D01*
X167258Y892650D01*
X166925Y892775D01*
X166550Y892817D01*
X166175Y892775D01*
X165842Y892650D01*
X165592Y892483D01*
X165383Y892233D01*
X165300Y891900D01*
G01X167508Y894292D02*
X167717Y894583D01*
X167800Y894917D01*
X167717Y895250D01*
X167467Y895542D01*
X167092Y895750D01*
X166717Y895833D01*
X166258D01*
X165883Y895750D01*
X165550Y895542D01*
X165383Y895292D01*
X165300Y895000D01*
X165383Y894667D01*
X165550Y894417D01*
X165800Y894250D01*
X166133Y894167D01*
X166425Y894250D01*
X166717Y894458D01*
X166883Y894708D01*
X166925Y895000D01*
X166842Y895333D01*
X166633Y895583D01*
X166258Y895833D01*
G01X167800Y898100D02*
X167758Y898392D01*
X167633Y898725D01*
X167425Y898933D01*
X167133Y899017D01*
X166842Y898933D01*
X166592Y898683D01*
X166467Y898308D01*
Y897892D01*
X166383Y897642D01*
X166175Y897433D01*
X165883Y897350D01*
X165592Y897475D01*
X165383Y897767D01*
X165300Y898100D01*
X165383Y898433D01*
X165592Y898725D01*
X165883Y898850D01*
X166175Y898767D01*
X166383Y898558D01*
X166467Y898308D01*
Y897892D01*
X166592Y897517D01*
X166842Y897267D01*
X167133Y897183D01*
X167425Y897267D01*
X167633Y897475D01*
X167758Y897808D01*
X167800Y898100D01*
G01X163800Y884867D02*
X161300D01*
Y885908D01*
X161425Y886242D01*
X161592Y886450D01*
X161925Y886533D01*
X162258Y886450D01*
X162467Y886200D01*
X162592Y885908D01*
Y884867D01*
G01Y885908D02*
X163800Y886533D01*
G01X161717Y888008D02*
X161467Y888258D01*
X161342Y888550D01*
X161300Y888883D01*
X161383Y889300D01*
X161592Y889592D01*
X161842Y889675D01*
X162092Y889633D01*
X162300Y889467D01*
X162717Y888633D01*
X163008Y888258D01*
X163425Y888008D01*
X163800Y887925D01*
Y889675D01*
G01Y891900D02*
X161300D01*
X161800Y891400D01*
G01X163800D02*
Y892400D01*
G01X161300Y895000D02*
X161383Y894667D01*
X161592Y894417D01*
X161842Y894250D01*
X162175Y894125D01*
X162550Y894083D01*
X162925Y894125D01*
X163258Y894250D01*
X163508Y894417D01*
X163717Y894667D01*
X163800Y895000D01*
X163717Y895333D01*
X163508Y895583D01*
X163258Y895750D01*
X162925Y895875D01*
X162550Y895917D01*
X162175Y895875D01*
X161842Y895750D01*
X161592Y895583D01*
X161383Y895333D01*
X161300Y895000D01*
G01X163800Y898017D02*
X163258Y898100D01*
X162800Y898225D01*
X162383Y898392D01*
X161925Y898600D01*
X161300Y898933D01*
Y897267D01*
G01X159800Y884867D02*
X157300D01*
Y885908D01*
X157425Y886242D01*
X157592Y886450D01*
X157925Y886533D01*
X158258Y886450D01*
X158467Y886200D01*
X158592Y885908D01*
Y884867D01*
G01Y885908D02*
X159800Y886533D01*
G01X157717Y888008D02*
X157467Y888258D01*
X157342Y888550D01*
X157300Y888883D01*
X157383Y889300D01*
X157592Y889592D01*
X157842Y889675D01*
X158092Y889633D01*
X158300Y889467D01*
X158717Y888633D01*
X159008Y888258D01*
X159425Y888008D01*
X159800Y887925D01*
Y889675D01*
G01Y891900D02*
X157300D01*
X157800Y891400D01*
G01X159800D02*
Y892400D01*
G01X157300Y895000D02*
X157383Y894667D01*
X157592Y894417D01*
X157842Y894250D01*
X158175Y894125D01*
X158550Y894083D01*
X158925Y894125D01*
X159258Y894250D01*
X159508Y894417D01*
X159717Y894667D01*
X159800Y895000D01*
X159717Y895333D01*
X159508Y895583D01*
X159258Y895750D01*
X158925Y895875D01*
X158550Y895917D01*
X158175Y895875D01*
X157842Y895750D01*
X157592Y895583D01*
X157383Y895333D01*
X157300Y895000D01*
G01X159508Y897392D02*
X159717Y897683D01*
X159800Y898017D01*
X159717Y898350D01*
X159467Y898642D01*
X159092Y898850D01*
X158717Y898933D01*
X158258D01*
X157883Y898850D01*
X157550Y898642D01*
X157383Y898392D01*
X157300Y898100D01*
X157383Y897767D01*
X157550Y897517D01*
X157800Y897350D01*
X158133Y897267D01*
X158425Y897350D01*
X158717Y897558D01*
X158883Y897808D01*
X158925Y898100D01*
X158842Y898433D01*
X158633Y898683D01*
X158258Y898933D01*
G01X153208Y889217D02*
X153083Y888967D01*
X153000Y888675D01*
Y888342D01*
X153125Y887967D01*
X153333Y887675D01*
X153583Y887467D01*
X154000Y887300D01*
X154375Y887258D01*
X154750Y887342D01*
X155000Y887467D01*
X155250Y887717D01*
X155417Y888008D01*
X155500Y888300D01*
Y888592D01*
X155417Y888883D01*
X155292Y889133D01*
X155125Y889342D01*
G01X155500Y891317D02*
X154958Y891400D01*
X154500Y891525D01*
X154083Y891692D01*
X153625Y891900D01*
X153000Y892233D01*
Y890567D01*
G01X153417Y893708D02*
X153167Y893958D01*
X153042Y894250D01*
X153000Y894583D01*
X153083Y895000D01*
X153292Y895292D01*
X153542Y895375D01*
X153792Y895333D01*
X154000Y895167D01*
X154417Y894333D01*
X154708Y893958D01*
X155125Y893708D01*
X155500Y893625D01*
Y895375D01*
G01Y897517D02*
X154958Y897600D01*
X154500Y897725D01*
X154083Y897892D01*
X153625Y898100D01*
X153000Y898433D01*
Y896767D01*
G01X154458Y899908D02*
X154167Y900200D01*
X154000Y900450D01*
X153917Y900783D01*
X154000Y901075D01*
X154167Y901283D01*
X154417Y901450D01*
X154708Y901492D01*
X154958Y901450D01*
X155208Y901283D01*
X155417Y901033D01*
X155500Y900742D01*
X155417Y900408D01*
X155167Y900117D01*
X154792Y899950D01*
X154375Y899908D01*
X153833Y899992D01*
X153542Y900117D01*
X153250Y900325D01*
X153042Y900617D01*
X153000Y900908D01*
X153083Y901200D01*
X153292Y901408D01*
G01X157650Y985750D02*
X158483D01*
Y985000D01*
X158233Y984750D01*
X157942Y984583D01*
X157525Y984500D01*
X157108Y984583D01*
X156817Y984750D01*
X156567Y985000D01*
X156400Y985292D01*
X156317Y985625D01*
Y985917D01*
X156400Y986167D01*
X156567Y986458D01*
X156817Y986708D01*
X157067Y986875D01*
X157400Y987000D01*
X157692D01*
X158025Y986917D01*
X158275Y986750D01*
G01X159708Y984500D02*
Y987000D01*
X161292D01*
G01X160708Y985792D02*
X159708D01*
G01X162808Y985542D02*
X163100Y985833D01*
X163350Y986000D01*
X163683Y986083D01*
X163975Y986000D01*
X164183Y985833D01*
X164350Y985583D01*
X164392Y985292D01*
X164350Y985042D01*
X164183Y984792D01*
X163933Y984583D01*
X163642Y984500D01*
X163308Y984583D01*
X163017Y984833D01*
X162850Y985208D01*
X162808Y985625D01*
X162892Y986167D01*
X163017Y986458D01*
X163225Y986750D01*
X163517Y986958D01*
X163808Y987000D01*
X164100Y986917D01*
X164308Y986708D01*
G01X166300Y448100D02*
X170300D01*
Y455500D01*
G01X170800Y448100D02*
X174800D01*
Y455500D01*
G01X169900Y465350D02*
Y465500D01*
X171150Y466750D01*
X172350Y465550D01*
Y465300D01*
G01X178000Y455800D02*
Y459800D01*
X170600D01*
G01X166233Y481300D02*
Y479508D01*
X166400Y479133D01*
X166733Y478883D01*
X167150Y478800D01*
X167567Y478883D01*
X167900Y479133D01*
X168067Y479508D01*
Y481300D01*
G01X170250Y478800D02*
Y481300D01*
X169750Y480800D01*
G01Y478800D02*
X170750D01*
G01X173350D02*
X173642Y478842D01*
X173975Y478967D01*
X174183Y479175D01*
X174267Y479467D01*
X174183Y479758D01*
X173933Y480008D01*
X173558Y480133D01*
X173142D01*
X172892Y480217D01*
X172683Y480425D01*
X172600Y480717D01*
X172725Y481008D01*
X173017Y481217D01*
X173350Y481300D01*
X173683Y481217D01*
X173975Y481008D01*
X174100Y480717D01*
X174017Y480425D01*
X173808Y480217D01*
X173558Y480133D01*
X173142D01*
X172767Y480008D01*
X172517Y479758D01*
X172433Y479467D01*
X172517Y479175D01*
X172725Y478967D01*
X173058Y478842D01*
X173350Y478800D01*
G01X175658Y479842D02*
X175950Y480133D01*
X176200Y480300D01*
X176533Y480383D01*
X176825Y480300D01*
X177033Y480133D01*
X177200Y479883D01*
X177242Y479592D01*
X177200Y479342D01*
X177033Y479092D01*
X176783Y478883D01*
X176492Y478800D01*
X176158Y478883D01*
X175867Y479133D01*
X175700Y479508D01*
X175658Y479925D01*
X175742Y480467D01*
X175867Y480758D01*
X176075Y481050D01*
X176367Y481258D01*
X176658Y481300D01*
X176950Y481217D01*
X177158Y481008D01*
G01X166530Y509833D02*
X166863Y509625D01*
X167238Y509500D01*
X167572D01*
X167905Y509625D01*
X168155Y509833D01*
X168280Y510125D01*
X168197Y510417D01*
X167988Y510667D01*
X167613Y510833D01*
X167113Y510917D01*
X166822Y511083D01*
X166697Y511375D01*
X166780Y511667D01*
X166988Y511875D01*
X167280Y512000D01*
X167572D01*
X167863Y511917D01*
X168113Y511708D01*
G01X170505Y509500D02*
X170172Y509542D01*
X169880Y509708D01*
X169630Y509958D01*
X169463Y510250D01*
X169380Y510583D01*
Y510917D01*
X169463Y511250D01*
X169630Y511542D01*
X169880Y511792D01*
X170172Y511958D01*
X170505Y512000D01*
X170838Y511958D01*
X171130Y511792D01*
X171380Y511542D01*
X171547Y511250D01*
X171630Y510917D01*
Y510583D01*
X171547Y510250D01*
X171380Y509958D01*
X171130Y509708D01*
X170838Y509542D01*
X170505Y509500D01*
G01X170838Y510167D02*
X171338Y509500D01*
G01X173605D02*
Y512000D01*
X173105Y511500D01*
G01Y509500D02*
X174105D01*
G01X175788Y510000D02*
X176038Y509708D01*
X176372Y509542D01*
X176747Y509500D01*
X177080Y509542D01*
X177413Y509750D01*
X177622Y510000D01*
X177663Y510250D01*
X177580Y510542D01*
X177288Y510750D01*
X176997Y510833D01*
X176622D01*
G01X176997D02*
X177247Y510958D01*
X177455Y511167D01*
X177538Y511417D01*
X177455Y511667D01*
X177247Y511875D01*
X176872Y512000D01*
X176497Y511958D01*
X176122Y511792D01*
G01X179245Y514250D02*
Y527250D01*
G01X181980Y513833D02*
X182313Y513625D01*
X182688Y513500D01*
X183022D01*
X183355Y513625D01*
X183605Y513833D01*
X183730Y514125D01*
X183647Y514417D01*
X183438Y514667D01*
X183063Y514833D01*
X182563Y514917D01*
X182272Y515083D01*
X182147Y515375D01*
X182230Y515667D01*
X182438Y515875D01*
X182730Y516000D01*
X183022D01*
X183313Y515917D01*
X183563Y515708D01*
G01X185122Y513500D02*
Y516000D01*
X186163D01*
X186497Y515875D01*
X186705Y515708D01*
X186788Y515375D01*
X186705Y515042D01*
X186455Y514833D01*
X186163Y514708D01*
X185122D01*
G01X186163D02*
X186788Y513500D01*
G01X189055D02*
X189347Y513542D01*
X189680Y513667D01*
X189888Y513875D01*
X189972Y514167D01*
X189888Y514458D01*
X189638Y514708D01*
X189263Y514833D01*
X188847D01*
X188597Y514917D01*
X188388Y515125D01*
X188305Y515417D01*
X188430Y515708D01*
X188722Y515917D01*
X189055Y516000D01*
X189388Y515917D01*
X189680Y515708D01*
X189805Y515417D01*
X189722Y515125D01*
X189513Y514917D01*
X189263Y514833D01*
X188847D01*
X188472Y514708D01*
X188222Y514458D01*
X188138Y514167D01*
X188222Y513875D01*
X188430Y513667D01*
X188763Y513542D01*
X189055Y513500D01*
G01X191363Y514542D02*
X191655Y514833D01*
X191905Y515000D01*
X192238Y515083D01*
X192530Y515000D01*
X192738Y514833D01*
X192905Y514583D01*
X192947Y514292D01*
X192905Y514042D01*
X192738Y513792D01*
X192488Y513583D01*
X192197Y513500D01*
X191863Y513583D01*
X191572Y513833D01*
X191405Y514208D01*
X191363Y514625D01*
X191447Y515167D01*
X191572Y515458D01*
X191780Y515750D01*
X192072Y515958D01*
X192363Y516000D01*
X192655Y515917D01*
X192863Y515708D01*
G01X195255Y516000D02*
X194922Y515917D01*
X194672Y515708D01*
X194505Y515458D01*
X194380Y515125D01*
X194338Y514750D01*
X194380Y514375D01*
X194505Y514042D01*
X194672Y513792D01*
X194922Y513583D01*
X195255Y513500D01*
X195588Y513583D01*
X195838Y513792D01*
X196005Y514042D01*
X196130Y514375D01*
X196172Y514750D01*
X196130Y515125D01*
X196005Y515458D01*
X195838Y515708D01*
X195588Y515917D01*
X195255Y516000D01*
G01X181980Y518333D02*
X182313Y518125D01*
X182688Y518000D01*
X183022D01*
X183355Y518125D01*
X183605Y518333D01*
X183730Y518625D01*
X183647Y518917D01*
X183438Y519167D01*
X183063Y519333D01*
X182563Y519417D01*
X182272Y519583D01*
X182147Y519875D01*
X182230Y520167D01*
X182438Y520375D01*
X182730Y520500D01*
X183022D01*
X183313Y520417D01*
X183563Y520208D01*
G01X185122Y518000D02*
Y520500D01*
X186163D01*
X186497Y520375D01*
X186705Y520208D01*
X186788Y519875D01*
X186705Y519542D01*
X186455Y519333D01*
X186163Y519208D01*
X185122D01*
G01X186163D02*
X186788Y518000D01*
G01X188347Y518292D02*
X188638Y518083D01*
X188972Y518000D01*
X189305Y518083D01*
X189597Y518333D01*
X189805Y518708D01*
X189888Y519083D01*
Y519542D01*
X189805Y519917D01*
X189597Y520250D01*
X189347Y520417D01*
X189055Y520500D01*
X188722Y520417D01*
X188472Y520250D01*
X188305Y520000D01*
X188222Y519667D01*
X188305Y519375D01*
X188513Y519083D01*
X188763Y518917D01*
X189055Y518875D01*
X189388Y518958D01*
X189638Y519167D01*
X189888Y519542D01*
G01X192155Y518000D02*
Y520500D01*
X191655Y520000D01*
G01Y518000D02*
X192655D01*
G01X195755D02*
Y520500D01*
X194213Y518708D01*
X196297D01*
G01X187255Y528000D02*
Y532000D01*
X179855D01*
G01Y527500D02*
Y523500D01*
X187255D01*
G01X172993Y547096D02*
X187493D01*
G01X172993Y551696D02*
Y547096D01*
G01X166055Y533000D02*
Y547000D01*
G01X180043Y539396D02*
Y535396D01*
X187443D01*
G01X187493Y551696D02*
X172993D01*
G01X175105Y565550D02*
Y562550D01*
X178105D01*
G01X181055Y563550D02*
Y561550D01*
G01X175105Y573450D02*
Y576450D01*
X178105D01*
G01X176530Y586833D02*
X176863Y586625D01*
X177238Y586500D01*
X177572D01*
X177905Y586625D01*
X178155Y586833D01*
X178280Y587125D01*
X178197Y587417D01*
X177988Y587667D01*
X177613Y587833D01*
X177113Y587917D01*
X176822Y588083D01*
X176697Y588375D01*
X176780Y588667D01*
X176988Y588875D01*
X177280Y589000D01*
X177572D01*
X177863Y588917D01*
X178113Y588708D01*
G01X179588Y589000D02*
Y587208D01*
X179755Y586833D01*
X180088Y586583D01*
X180505Y586500D01*
X180922Y586583D01*
X181255Y586833D01*
X181422Y587208D01*
Y589000D01*
G01X183522Y586500D02*
X183605Y587042D01*
X183730Y587500D01*
X183897Y587917D01*
X184105Y588375D01*
X184438Y589000D01*
X182772D01*
G01X185913Y587542D02*
X186205Y587833D01*
X186455Y588000D01*
X186788Y588083D01*
X187080Y588000D01*
X187288Y587833D01*
X187455Y587583D01*
X187497Y587292D01*
X187455Y587042D01*
X187288Y586792D01*
X187038Y586583D01*
X186747Y586500D01*
X186413Y586583D01*
X186122Y586833D01*
X185955Y587208D01*
X185913Y587625D01*
X185997Y588167D01*
X186122Y588458D01*
X186330Y588750D01*
X186622Y588958D01*
X186913Y589000D01*
X187205Y588917D01*
X187413Y588708D01*
G01X180167Y591475D02*
X180375Y591808D01*
X180500Y592183D01*
Y592517D01*
X180375Y592850D01*
X180167Y593100D01*
X179875Y593225D01*
X179583Y593142D01*
X179333Y592933D01*
X179167Y592558D01*
X179083Y592058D01*
X178917Y591767D01*
X178625Y591642D01*
X178333Y591725D01*
X178125Y591933D01*
X178000Y592225D01*
Y592517D01*
X178083Y592808D01*
X178292Y593058D01*
G01X178000Y594533D02*
X179792D01*
X180167Y594700D01*
X180417Y595033D01*
X180500Y595450D01*
X180417Y595867D01*
X180167Y596200D01*
X179792Y596367D01*
X178000D01*
G01X180500Y598467D02*
X179958Y598550D01*
X179500Y598675D01*
X179083Y598842D01*
X178625Y599050D01*
X178000Y599383D01*
Y597717D01*
G01X180125Y600733D02*
X180333Y600983D01*
X180458Y601275D01*
X180500Y601650D01*
X180417Y602025D01*
X180250Y602317D01*
X179958Y602525D01*
X179625Y602567D01*
X179292Y602483D01*
X179083Y602275D01*
X178917Y601983D01*
X178875Y601692D01*
X178917Y601400D01*
X179083Y601025D01*
X178000Y601150D01*
Y602275D01*
G01X169500Y670000D02*
Y684000D01*
G01X175375Y680833D02*
X175708Y680625D01*
X176083Y680500D01*
X176417D01*
X176750Y680625D01*
X177000Y680833D01*
X177125Y681125D01*
X177042Y681417D01*
X176833Y681667D01*
X176458Y681833D01*
X175958Y681917D01*
X175667Y682083D01*
X175542Y682375D01*
X175625Y682667D01*
X175833Y682875D01*
X176125Y683000D01*
X176417D01*
X176708Y682917D01*
X176958Y682708D01*
G01X178517Y680500D02*
Y683000D01*
X179558D01*
X179892Y682875D01*
X180100Y682708D01*
X180183Y682375D01*
X180100Y682042D01*
X179850Y681833D01*
X179558Y681708D01*
X178517D01*
G01X179558D02*
X180183Y680500D01*
G01X182450D02*
Y683000D01*
X181950Y682500D01*
G01Y680500D02*
X182950D01*
G01X184758Y682583D02*
X185008Y682833D01*
X185300Y682958D01*
X185633Y683000D01*
X186050Y682917D01*
X186342Y682708D01*
X186425Y682458D01*
X186383Y682208D01*
X186217Y682000D01*
X185383Y681583D01*
X185008Y681292D01*
X184758Y680875D01*
X184675Y680500D01*
X186425D01*
G01X188567D02*
X188650Y681042D01*
X188775Y681500D01*
X188942Y681917D01*
X189150Y682375D01*
X189483Y683000D01*
X187817D01*
G01X190833Y680875D02*
X191083Y680667D01*
X191375Y680542D01*
X191750Y680500D01*
X192125Y680583D01*
X192417Y680750D01*
X192625Y681042D01*
X192667Y681375D01*
X192583Y681708D01*
X192375Y681917D01*
X192083Y682083D01*
X191792Y682125D01*
X191500Y682083D01*
X191125Y681917D01*
X191250Y683000D01*
X192375D01*
G01X175375Y672833D02*
X175708Y672625D01*
X176083Y672500D01*
X176417D01*
X176750Y672625D01*
X177000Y672833D01*
X177125Y673125D01*
X177042Y673417D01*
X176833Y673667D01*
X176458Y673833D01*
X175958Y673917D01*
X175667Y674083D01*
X175542Y674375D01*
X175625Y674667D01*
X175833Y674875D01*
X176125Y675000D01*
X176417D01*
X176708Y674917D01*
X176958Y674708D01*
G01X178517Y672500D02*
Y675000D01*
X179558D01*
X179892Y674875D01*
X180100Y674708D01*
X180183Y674375D01*
X180100Y674042D01*
X179850Y673833D01*
X179558Y673708D01*
X178517D01*
G01X179558D02*
X180183Y672500D01*
G01X182450D02*
Y675000D01*
X181950Y674500D01*
G01Y672500D02*
X182950D01*
G01X184758Y674583D02*
X185008Y674833D01*
X185300Y674958D01*
X185633Y675000D01*
X186050Y674917D01*
X186342Y674708D01*
X186425Y674458D01*
X186383Y674208D01*
X186217Y674000D01*
X185383Y673583D01*
X185008Y673292D01*
X184758Y672875D01*
X184675Y672500D01*
X186425D01*
G01X188567D02*
X188650Y673042D01*
X188775Y673500D01*
X188942Y673917D01*
X189150Y674375D01*
X189483Y675000D01*
X187817D01*
G01X192250Y672500D02*
Y675000D01*
X190708Y673208D01*
X192792D01*
G01X174667Y689475D02*
X174875Y689808D01*
X175000Y690183D01*
Y690517D01*
X174875Y690850D01*
X174667Y691100D01*
X174375Y691225D01*
X174083Y691142D01*
X173833Y690933D01*
X173667Y690558D01*
X173583Y690058D01*
X173417Y689767D01*
X173125Y689642D01*
X172833Y689725D01*
X172625Y689933D01*
X172500Y690225D01*
Y690517D01*
X172583Y690808D01*
X172792Y691058D01*
G01X175000Y693450D02*
X174958Y693117D01*
X174792Y692825D01*
X174542Y692575D01*
X174250Y692408D01*
X173917Y692325D01*
X173583D01*
X173250Y692408D01*
X172958Y692575D01*
X172708Y692825D01*
X172542Y693117D01*
X172500Y693450D01*
X172542Y693783D01*
X172708Y694075D01*
X172958Y694325D01*
X173250Y694492D01*
X173583Y694575D01*
X173917D01*
X174250Y694492D01*
X174542Y694325D01*
X174792Y694075D01*
X174958Y693783D01*
X175000Y693450D01*
G01X174333Y693783D02*
X175000Y694283D01*
G01Y696550D02*
X172500D01*
X173000Y696050D01*
G01X175000D02*
Y697050D01*
G01Y700150D02*
X172500D01*
X174292Y698608D01*
Y700692D01*
G01X169500Y685710D02*
Y699710D01*
G01X170967Y826000D02*
Y828500D01*
X172008D01*
X172342Y828375D01*
X172550Y828208D01*
X172633Y827875D01*
X172550Y827542D01*
X172300Y827333D01*
X172008Y827208D01*
X170967D01*
G01X172008D02*
X172633Y826000D01*
G01X174108Y828083D02*
X174358Y828333D01*
X174650Y828458D01*
X174983Y828500D01*
X175400Y828417D01*
X175692Y828208D01*
X175775Y827958D01*
X175733Y827708D01*
X175567Y827500D01*
X174733Y827083D01*
X174358Y826792D01*
X174108Y826375D01*
X174025Y826000D01*
X175775D01*
G01X178000D02*
Y828500D01*
X177500Y828000D01*
G01Y826000D02*
X178500D01*
G01X181017D02*
X181100Y826542D01*
X181225Y827000D01*
X181392Y827417D01*
X181600Y827875D01*
X181933Y828500D01*
X180267D01*
G01X183408Y828083D02*
X183658Y828333D01*
X183950Y828458D01*
X184283Y828500D01*
X184700Y828417D01*
X184992Y828208D01*
X185075Y827958D01*
X185033Y827708D01*
X184867Y827500D01*
X184033Y827083D01*
X183658Y826792D01*
X183408Y826375D01*
X183325Y826000D01*
X185075D01*
G01X170967Y830000D02*
Y832500D01*
X172008D01*
X172342Y832375D01*
X172550Y832208D01*
X172633Y831875D01*
X172550Y831542D01*
X172300Y831333D01*
X172008Y831208D01*
X170967D01*
G01X172008D02*
X172633Y830000D01*
G01X174108Y832083D02*
X174358Y832333D01*
X174650Y832458D01*
X174983Y832500D01*
X175400Y832417D01*
X175692Y832208D01*
X175775Y831958D01*
X175733Y831708D01*
X175567Y831500D01*
X174733Y831083D01*
X174358Y830792D01*
X174108Y830375D01*
X174025Y830000D01*
X175775D01*
G01X178000D02*
Y832500D01*
X177500Y832000D01*
G01Y830000D02*
X178500D01*
G01X181100Y832500D02*
X180767Y832417D01*
X180517Y832208D01*
X180350Y831958D01*
X180225Y831625D01*
X180183Y831250D01*
X180225Y830875D01*
X180350Y830542D01*
X180517Y830292D01*
X180767Y830083D01*
X181100Y830000D01*
X181433Y830083D01*
X181683Y830292D01*
X181850Y830542D01*
X181975Y830875D01*
X182017Y831250D01*
X181975Y831625D01*
X181850Y831958D01*
X181683Y832208D01*
X181433Y832417D01*
X181100Y832500D01*
G01X183283Y830500D02*
X183533Y830208D01*
X183867Y830042D01*
X184242Y830000D01*
X184575Y830042D01*
X184908Y830250D01*
X185117Y830500D01*
X185158Y830750D01*
X185075Y831042D01*
X184783Y831250D01*
X184492Y831333D01*
X184117D01*
G01X184492D02*
X184742Y831458D01*
X184950Y831667D01*
X185033Y831917D01*
X184950Y832167D01*
X184742Y832375D01*
X184367Y832500D01*
X183992Y832458D01*
X183617Y832292D01*
G01X171217Y840292D02*
X170967Y840417D01*
X170675Y840500D01*
X170342D01*
X169967Y840375D01*
X169675Y840167D01*
X169467Y839917D01*
X169300Y839500D01*
X169258Y839125D01*
X169342Y838750D01*
X169467Y838500D01*
X169717Y838250D01*
X170008Y838083D01*
X170300Y838000D01*
X170592D01*
X170883Y838083D01*
X171133Y838208D01*
X171342Y838375D01*
G01X173317Y838000D02*
X173400Y838542D01*
X173525Y839000D01*
X173692Y839417D01*
X173900Y839875D01*
X174233Y840500D01*
X172567D01*
G01X175583Y838500D02*
X175833Y838208D01*
X176167Y838042D01*
X176542Y838000D01*
X176875Y838042D01*
X177208Y838250D01*
X177417Y838500D01*
X177458Y838750D01*
X177375Y839042D01*
X177083Y839250D01*
X176792Y839333D01*
X176417D01*
G01X176792D02*
X177042Y839458D01*
X177250Y839667D01*
X177333Y839917D01*
X177250Y840167D01*
X177042Y840375D01*
X176667Y840500D01*
X176292Y840458D01*
X175917Y840292D01*
G01X179600Y838000D02*
Y840500D01*
X179100Y840000D01*
G01Y838000D02*
X180100D01*
G01X182617D02*
X182700Y838542D01*
X182825Y839000D01*
X182992Y839417D01*
X183200Y839875D01*
X183533Y840500D01*
X181867D01*
G01X172717Y836292D02*
X172467Y836417D01*
X172175Y836500D01*
X171842D01*
X171467Y836375D01*
X171175Y836167D01*
X170967Y835917D01*
X170800Y835500D01*
X170758Y835125D01*
X170842Y834750D01*
X170967Y834500D01*
X171217Y834250D01*
X171508Y834083D01*
X171800Y834000D01*
X172092D01*
X172383Y834083D01*
X172633Y834208D01*
X172842Y834375D01*
G01X174817Y834000D02*
X174900Y834542D01*
X175025Y835000D01*
X175192Y835417D01*
X175400Y835875D01*
X175733Y836500D01*
X174067D01*
G01X177208Y836083D02*
X177458Y836333D01*
X177750Y836458D01*
X178083Y836500D01*
X178500Y836417D01*
X178792Y836208D01*
X178875Y835958D01*
X178833Y835708D01*
X178667Y835500D01*
X177833Y835083D01*
X177458Y834792D01*
X177208Y834375D01*
X177125Y834000D01*
X178875D01*
G01X181017D02*
X181100Y834542D01*
X181225Y835000D01*
X181392Y835417D01*
X181600Y835875D01*
X181933Y836500D01*
X180267D01*
G01X183283Y834500D02*
X183533Y834208D01*
X183867Y834042D01*
X184242Y834000D01*
X184575Y834042D01*
X184908Y834250D01*
X185117Y834500D01*
X185158Y834750D01*
X185075Y835042D01*
X184783Y835250D01*
X184492Y835333D01*
X184117D01*
G01X184492D02*
X184742Y835458D01*
X184950Y835667D01*
X185033Y835917D01*
X184950Y836167D01*
X184742Y836375D01*
X184367Y836500D01*
X183992Y836458D01*
X183617Y836292D01*
G01X171500Y856967D02*
X169000D01*
Y858008D01*
X169125Y858342D01*
X169292Y858550D01*
X169625Y858633D01*
X169958Y858550D01*
X170167Y858300D01*
X170292Y858008D01*
Y856967D01*
G01Y858008D02*
X171500Y858633D01*
G01X169417Y860108D02*
X169167Y860358D01*
X169042Y860650D01*
X169000Y860983D01*
X169083Y861400D01*
X169292Y861692D01*
X169542Y861775D01*
X169792Y861733D01*
X170000Y861567D01*
X170417Y860733D01*
X170708Y860358D01*
X171125Y860108D01*
X171500Y860025D01*
Y861775D01*
G01Y864000D02*
X169000D01*
X169500Y863500D01*
G01X171500D02*
Y864500D01*
G01Y867017D02*
X170958Y867100D01*
X170500Y867225D01*
X170083Y867392D01*
X169625Y867600D01*
X169000Y867933D01*
Y866267D01*
G01X171500Y870700D02*
X169000D01*
X170792Y869158D01*
Y871242D01*
G01X181500Y867700D02*
X177500D01*
Y860300D01*
G01X171217Y877792D02*
X170967Y877917D01*
X170675Y878000D01*
X170342D01*
X169967Y877875D01*
X169675Y877667D01*
X169467Y877417D01*
X169300Y877000D01*
X169258Y876625D01*
X169342Y876250D01*
X169467Y876000D01*
X169717Y875750D01*
X170008Y875583D01*
X170300Y875500D01*
X170592D01*
X170883Y875583D01*
X171133Y875708D01*
X171342Y875875D01*
G01X173317Y875500D02*
X173400Y876042D01*
X173525Y876500D01*
X173692Y876917D01*
X173900Y877375D01*
X174233Y878000D01*
X172567D01*
G01X175583Y876000D02*
X175833Y875708D01*
X176167Y875542D01*
X176542Y875500D01*
X176875Y875542D01*
X177208Y875750D01*
X177417Y876000D01*
X177458Y876250D01*
X177375Y876542D01*
X177083Y876750D01*
X176792Y876833D01*
X176417D01*
G01X176792D02*
X177042Y876958D01*
X177250Y877167D01*
X177333Y877417D01*
X177250Y877667D01*
X177042Y877875D01*
X176667Y878000D01*
X176292Y877958D01*
X175917Y877792D01*
G01X179600Y875500D02*
Y878000D01*
X179100Y877500D01*
G01Y875500D02*
X180100D01*
G01X181908Y876542D02*
X182200Y876833D01*
X182450Y877000D01*
X182783Y877083D01*
X183075Y877000D01*
X183283Y876833D01*
X183450Y876583D01*
X183492Y876292D01*
X183450Y876042D01*
X183283Y875792D01*
X183033Y875583D01*
X182742Y875500D01*
X182408Y875583D01*
X182117Y875833D01*
X181950Y876208D01*
X181908Y876625D01*
X181992Y877167D01*
X182117Y877458D01*
X182325Y877750D01*
X182617Y877958D01*
X182908Y878000D01*
X183200Y877917D01*
X183408Y877708D01*
G01X180800Y888767D02*
X178300D01*
Y889808D01*
X178425Y890142D01*
X178592Y890350D01*
X178925Y890433D01*
X179258Y890350D01*
X179467Y890100D01*
X179592Y889808D01*
Y888767D01*
G01Y889808D02*
X180800Y890433D01*
G01X178717Y891908D02*
X178467Y892158D01*
X178342Y892450D01*
X178300Y892783D01*
X178383Y893200D01*
X178592Y893492D01*
X178842Y893575D01*
X179092Y893533D01*
X179300Y893367D01*
X179717Y892533D01*
X180008Y892158D01*
X180425Y891908D01*
X180800Y891825D01*
Y893575D01*
G01Y895800D02*
X178300D01*
X178800Y895300D01*
G01X180800D02*
Y896300D01*
G01Y898900D02*
X178300D01*
X178800Y898400D01*
G01X180800D02*
Y899400D01*
G01X180508Y901292D02*
X180717Y901583D01*
X180800Y901917D01*
X180717Y902250D01*
X180467Y902542D01*
X180092Y902750D01*
X179717Y902833D01*
X179258D01*
X178883Y902750D01*
X178550Y902542D01*
X178383Y902292D01*
X178300Y902000D01*
X178383Y901667D01*
X178550Y901417D01*
X178800Y901250D01*
X179133Y901167D01*
X179425Y901250D01*
X179717Y901458D01*
X179883Y901708D01*
X179925Y902000D01*
X179842Y902333D01*
X179633Y902583D01*
X179258Y902833D01*
G01X169467Y880000D02*
Y882500D01*
X170508D01*
X170842Y882375D01*
X171050Y882208D01*
X171133Y881875D01*
X171050Y881542D01*
X170800Y881333D01*
X170508Y881208D01*
X169467D01*
G01X170508D02*
X171133Y880000D01*
G01X172692Y880292D02*
X172983Y880083D01*
X173317Y880000D01*
X173650Y880083D01*
X173942Y880333D01*
X174150Y880708D01*
X174233Y881083D01*
Y881542D01*
X174150Y881917D01*
X173942Y882250D01*
X173692Y882417D01*
X173400Y882500D01*
X173067Y882417D01*
X172817Y882250D01*
X172650Y882000D01*
X172567Y881667D01*
X172650Y881375D01*
X172858Y881083D01*
X173108Y880917D01*
X173400Y880875D01*
X173733Y880958D01*
X173983Y881167D01*
X174233Y881542D01*
G01X176500Y882500D02*
X176167Y882417D01*
X175917Y882208D01*
X175750Y881958D01*
X175625Y881625D01*
X175583Y881250D01*
X175625Y880875D01*
X175750Y880542D01*
X175917Y880292D01*
X176167Y880083D01*
X176500Y880000D01*
X176833Y880083D01*
X177083Y880292D01*
X177250Y880542D01*
X177375Y880875D01*
X177417Y881250D01*
X177375Y881625D01*
X177250Y881958D01*
X177083Y882208D01*
X176833Y882417D01*
X176500Y882500D01*
G01X178808Y882083D02*
X179058Y882333D01*
X179350Y882458D01*
X179683Y882500D01*
X180100Y882417D01*
X180392Y882208D01*
X180475Y881958D01*
X180433Y881708D01*
X180267Y881500D01*
X179433Y881083D01*
X179058Y880792D01*
X178808Y880375D01*
X178725Y880000D01*
X180475D01*
G01X181908Y882083D02*
X182158Y882333D01*
X182450Y882458D01*
X182783Y882500D01*
X183200Y882417D01*
X183492Y882208D01*
X183575Y881958D01*
X183533Y881708D01*
X183367Y881500D01*
X182533Y881083D01*
X182158Y880792D01*
X181908Y880375D01*
X181825Y880000D01*
X183575D01*
G01X172300Y884817D02*
X169800D01*
Y885817D01*
X169925Y886150D01*
X170217Y886400D01*
X170550Y886483D01*
X170883Y886400D01*
X171133Y886192D01*
X171258Y885817D01*
Y884817D01*
G01X170008Y889667D02*
X169883Y889417D01*
X169800Y889125D01*
Y888792D01*
X169925Y888417D01*
X170133Y888125D01*
X170383Y887917D01*
X170800Y887750D01*
X171175Y887708D01*
X171550Y887792D01*
X171800Y887917D01*
X172050Y888167D01*
X172217Y888458D01*
X172300Y888750D01*
Y889042D01*
X172217Y889333D01*
X172092Y889583D01*
X171925Y889792D01*
G01X172300Y891850D02*
X169800D01*
X170300Y891350D01*
G01X172300D02*
Y892350D01*
G01X169800Y894950D02*
X169883Y894617D01*
X170092Y894367D01*
X170342Y894200D01*
X170675Y894075D01*
X171050Y894033D01*
X171425Y894075D01*
X171758Y894200D01*
X172008Y894367D01*
X172217Y894617D01*
X172300Y894950D01*
X172217Y895283D01*
X172008Y895533D01*
X171758Y895700D01*
X171425Y895825D01*
X171050Y895867D01*
X170675Y895825D01*
X170342Y895700D01*
X170092Y895533D01*
X169883Y895283D01*
X169800Y894950D01*
G01X172300Y898050D02*
X172258Y898342D01*
X172133Y898675D01*
X171925Y898883D01*
X171633Y898967D01*
X171342Y898883D01*
X171092Y898633D01*
X170967Y898258D01*
Y897842D01*
X170883Y897592D01*
X170675Y897383D01*
X170383Y897300D01*
X170092Y897425D01*
X169883Y897717D01*
X169800Y898050D01*
X169883Y898383D01*
X170092Y898675D01*
X170383Y898800D01*
X170675Y898717D01*
X170883Y898508D01*
X170967Y898258D01*
Y897842D01*
X171092Y897467D01*
X171342Y897217D01*
X171633Y897133D01*
X171925Y897217D01*
X172133Y897425D01*
X172258Y897758D01*
X172300Y898050D01*
G01X171800Y900233D02*
X172092Y900483D01*
X172258Y900817D01*
X172300Y901192D01*
X172258Y901525D01*
X172050Y901858D01*
X171800Y902067D01*
X171550Y902108D01*
X171258Y902025D01*
X171050Y901733D01*
X170967Y901442D01*
Y901067D01*
G01Y901442D02*
X170842Y901692D01*
X170633Y901900D01*
X170383Y901983D01*
X170133Y901900D01*
X169925Y901692D01*
X169800Y901317D01*
X169842Y900942D01*
X170008Y900567D01*
G01X176567Y886892D02*
X176317Y887017D01*
X176025Y887100D01*
X175692D01*
X175317Y886975D01*
X175025Y886767D01*
X174817Y886517D01*
X174650Y886100D01*
X174608Y885725D01*
X174692Y885350D01*
X174817Y885100D01*
X175067Y884850D01*
X175358Y884683D01*
X175650Y884600D01*
X175942D01*
X176233Y884683D01*
X176483Y884808D01*
X176692Y884975D01*
G01X177833Y885100D02*
X178083Y884808D01*
X178417Y884642D01*
X178792Y884600D01*
X179125Y884642D01*
X179458Y884850D01*
X179667Y885100D01*
X179708Y885350D01*
X179625Y885642D01*
X179333Y885850D01*
X179042Y885933D01*
X178667D01*
G01X179042D02*
X179292Y886058D01*
X179500Y886267D01*
X179583Y886517D01*
X179500Y886767D01*
X179292Y886975D01*
X178917Y887100D01*
X178542Y887058D01*
X178167Y886892D01*
G01X181767Y884600D02*
X181850Y885142D01*
X181975Y885600D01*
X182142Y886017D01*
X182350Y886475D01*
X182683Y887100D01*
X181017D01*
G01X184158Y886683D02*
X184408Y886933D01*
X184700Y887058D01*
X185033Y887100D01*
X185450Y887017D01*
X185742Y886808D01*
X185825Y886558D01*
X185783Y886308D01*
X185617Y886100D01*
X184783Y885683D01*
X184408Y885392D01*
X184158Y884975D01*
X184075Y884600D01*
X185825D01*
G01X179208Y919767D02*
X179083Y919517D01*
X179000Y919225D01*
Y918892D01*
X179125Y918517D01*
X179333Y918225D01*
X179583Y918017D01*
X180000Y917850D01*
X180375Y917808D01*
X180750Y917892D01*
X181000Y918017D01*
X181250Y918267D01*
X181417Y918558D01*
X181500Y918850D01*
Y919142D01*
X181417Y919433D01*
X181292Y919683D01*
X181125Y919892D01*
G01X181000Y921033D02*
X181292Y921283D01*
X181458Y921617D01*
X181500Y921992D01*
X181458Y922325D01*
X181250Y922658D01*
X181000Y922867D01*
X180750Y922908D01*
X180458Y922825D01*
X180250Y922533D01*
X180167Y922242D01*
Y921867D01*
G01Y922242D02*
X180042Y922492D01*
X179833Y922700D01*
X179583Y922783D01*
X179333Y922700D01*
X179125Y922492D01*
X179000Y922117D01*
X179042Y921742D01*
X179208Y921367D01*
G01X179000Y925050D02*
X179083Y924717D01*
X179292Y924467D01*
X179542Y924300D01*
X179875Y924175D01*
X180250Y924133D01*
X180625Y924175D01*
X180958Y924300D01*
X181208Y924467D01*
X181417Y924717D01*
X181500Y925050D01*
X181417Y925383D01*
X181208Y925633D01*
X180958Y925800D01*
X180625Y925925D01*
X180250Y925967D01*
X179875Y925925D01*
X179542Y925800D01*
X179292Y925633D01*
X179083Y925383D01*
X179000Y925050D01*
G01X179417Y927358D02*
X179167Y927608D01*
X179042Y927900D01*
X179000Y928233D01*
X179083Y928650D01*
X179292Y928942D01*
X179542Y929025D01*
X179792Y928983D01*
X180000Y928817D01*
X180417Y927983D01*
X180708Y927608D01*
X181125Y927358D01*
X181500Y927275D01*
Y929025D01*
G01X174708Y919267D02*
X174583Y919017D01*
X174500Y918725D01*
Y918392D01*
X174625Y918017D01*
X174833Y917725D01*
X175083Y917517D01*
X175500Y917350D01*
X175875Y917308D01*
X176250Y917392D01*
X176500Y917517D01*
X176750Y917767D01*
X176917Y918058D01*
X177000Y918350D01*
Y918642D01*
X176917Y918933D01*
X176792Y919183D01*
X176625Y919392D01*
G01X176500Y920533D02*
X176792Y920783D01*
X176958Y921117D01*
X177000Y921492D01*
X176958Y921825D01*
X176750Y922158D01*
X176500Y922367D01*
X176250Y922408D01*
X175958Y922325D01*
X175750Y922033D01*
X175667Y921742D01*
Y921367D01*
G01Y921742D02*
X175542Y921992D01*
X175333Y922200D01*
X175083Y922283D01*
X174833Y922200D01*
X174625Y921992D01*
X174500Y921617D01*
X174542Y921242D01*
X174708Y920867D01*
G01X174500Y924550D02*
X174583Y924217D01*
X174792Y923967D01*
X175042Y923800D01*
X175375Y923675D01*
X175750Y923633D01*
X176125Y923675D01*
X176458Y923800D01*
X176708Y923967D01*
X176917Y924217D01*
X177000Y924550D01*
X176917Y924883D01*
X176708Y925133D01*
X176458Y925300D01*
X176125Y925425D01*
X175750Y925467D01*
X175375Y925425D01*
X175042Y925300D01*
X174792Y925133D01*
X174583Y924883D01*
X174500Y924550D01*
G01X177000Y927650D02*
X174500D01*
X175000Y927150D01*
G01X177000D02*
Y928150D01*
G01X170708Y919267D02*
X170583Y919017D01*
X170500Y918725D01*
Y918392D01*
X170625Y918017D01*
X170833Y917725D01*
X171083Y917517D01*
X171500Y917350D01*
X171875Y917308D01*
X172250Y917392D01*
X172500Y917517D01*
X172750Y917767D01*
X172917Y918058D01*
X173000Y918350D01*
Y918642D01*
X172917Y918933D01*
X172792Y919183D01*
X172625Y919392D01*
G01X172500Y920533D02*
X172792Y920783D01*
X172958Y921117D01*
X173000Y921492D01*
X172958Y921825D01*
X172750Y922158D01*
X172500Y922367D01*
X172250Y922408D01*
X171958Y922325D01*
X171750Y922033D01*
X171667Y921742D01*
Y921367D01*
G01Y921742D02*
X171542Y921992D01*
X171333Y922200D01*
X171083Y922283D01*
X170833Y922200D01*
X170625Y921992D01*
X170500Y921617D01*
X170542Y921242D01*
X170708Y920867D01*
G01X170500Y924550D02*
X170583Y924217D01*
X170792Y923967D01*
X171042Y923800D01*
X171375Y923675D01*
X171750Y923633D01*
X172125Y923675D01*
X172458Y923800D01*
X172708Y923967D01*
X172917Y924217D01*
X173000Y924550D01*
X172917Y924883D01*
X172708Y925133D01*
X172458Y925300D01*
X172125Y925425D01*
X171750Y925467D01*
X171375Y925425D01*
X171042Y925300D01*
X170792Y925133D01*
X170583Y924883D01*
X170500Y924550D01*
G01X172500Y926733D02*
X172792Y926983D01*
X172958Y927317D01*
X173000Y927692D01*
X172958Y928025D01*
X172750Y928358D01*
X172500Y928567D01*
X172250Y928608D01*
X171958Y928525D01*
X171750Y928233D01*
X171667Y927942D01*
Y927567D01*
G01Y927942D02*
X171542Y928192D01*
X171333Y928400D01*
X171083Y928483D01*
X170833Y928400D01*
X170625Y928192D01*
X170500Y927817D01*
X170542Y927442D01*
X170708Y927067D01*
G01X200133Y-23086D02*
X200466Y-22686D01*
X200666Y-22219D01*
X200733Y-21619D01*
X200600Y-21019D01*
X200333Y-20552D01*
X199866Y-20219D01*
X199333Y-20152D01*
X198800Y-20286D01*
X198466Y-20619D01*
X198200Y-21086D01*
X198133Y-21552D01*
X198200Y-22019D01*
X198466Y-22619D01*
X196733Y-22419D01*
Y-20619D01*
G01X190583Y378500D02*
X188917D01*
Y381000D01*
X190583D01*
G01X189917Y379792D02*
X188917D01*
G01X191975Y378500D02*
X193725Y381000D01*
G01X191975D02*
X193725Y378500D01*
G01X195117D02*
Y381000D01*
X196117D01*
X196450Y380875D01*
X196700Y380583D01*
X196783Y380250D01*
X196700Y379917D01*
X196492Y379667D01*
X196117Y379542D01*
X195117D01*
G01X197800Y377667D02*
X200300D01*
G01X201275Y378833D02*
X201608Y378625D01*
X201983Y378500D01*
X202317D01*
X202650Y378625D01*
X202900Y378833D01*
X203025Y379125D01*
X202942Y379417D01*
X202733Y379667D01*
X202358Y379833D01*
X201858Y379917D01*
X201567Y380083D01*
X201442Y380375D01*
X201525Y380667D01*
X201733Y380875D01*
X202025Y381000D01*
X202317D01*
X202608Y380917D01*
X202858Y380708D01*
G01X204333Y378500D02*
Y381000D01*
X205167D01*
X205500Y380875D01*
X205750Y380708D01*
X205958Y380458D01*
X206125Y380167D01*
X206167Y379750D01*
X206125Y379333D01*
X205958Y379042D01*
X205750Y378792D01*
X205500Y378625D01*
X205167Y378500D01*
X204333D01*
G01X208683Y379833D02*
X208850Y379958D01*
X208975Y380167D01*
X209058Y380458D01*
X208975Y380708D01*
X208808Y380875D01*
X208517Y381000D01*
X207392D01*
Y378500D01*
X208767D01*
X209058Y378667D01*
X209225Y378917D01*
X209308Y379208D01*
X209225Y379500D01*
X208975Y379750D01*
X208683Y379833D01*
X207392D01*
G01X193475Y371333D02*
X193808Y371125D01*
X194183Y371000D01*
X194517D01*
X194850Y371125D01*
X195100Y371333D01*
X195225Y371625D01*
X195142Y371917D01*
X194933Y372167D01*
X194558Y372333D01*
X194058Y372417D01*
X193767Y372583D01*
X193642Y372875D01*
X193725Y373167D01*
X193933Y373375D01*
X194225Y373500D01*
X194517D01*
X194808Y373417D01*
X195058Y373208D01*
G01X198367Y373292D02*
X198117Y373417D01*
X197825Y373500D01*
X197492D01*
X197117Y373375D01*
X196825Y373167D01*
X196617Y372917D01*
X196450Y372500D01*
X196408Y372125D01*
X196492Y371750D01*
X196617Y371500D01*
X196867Y371250D01*
X197158Y371083D01*
X197450Y371000D01*
X197742D01*
X198033Y371083D01*
X198283Y371208D01*
X198492Y371375D01*
G01X199592Y371000D02*
Y373500D01*
X201508Y371000D01*
Y373500D01*
G01X202733Y371375D02*
X202983Y371167D01*
X203275Y371042D01*
X203650Y371000D01*
X204025Y371083D01*
X204317Y371250D01*
X204525Y371542D01*
X204567Y371875D01*
X204483Y372208D01*
X204275Y372417D01*
X203983Y372583D01*
X203692Y372625D01*
X203400Y372583D01*
X203025Y372417D01*
X203150Y373500D01*
X204275D01*
G01X189250Y387500D02*
Y388333D01*
X190000D01*
X190250Y388083D01*
X190417Y387792D01*
X190500Y387375D01*
X190417Y386958D01*
X190250Y386667D01*
X190000Y386417D01*
X189708Y386250D01*
X189375Y386167D01*
X189083D01*
X188833Y386250D01*
X188542Y386417D01*
X188292Y386667D01*
X188125Y386917D01*
X188000Y387250D01*
Y387542D01*
X188083Y387875D01*
X188250Y388125D01*
G01X190500Y389642D02*
X188833D01*
G01X189250D02*
X189042Y389808D01*
X188875Y390058D01*
X188833Y390392D01*
X188875Y390683D01*
X189042Y390933D01*
X189333Y391058D01*
X190500D01*
G01X188000Y394200D02*
X190500D01*
G01X190125D02*
X190333Y394033D01*
X190458Y393783D01*
X190500Y393492D01*
X190417Y393158D01*
X190208Y392908D01*
X189958Y392742D01*
X189667Y392700D01*
X189375Y392742D01*
X189125Y392908D01*
X188917Y393158D01*
X188833Y393492D01*
X188875Y393783D01*
X188958Y393992D01*
X189125Y394200D01*
G01X190500Y398917D02*
X188000D01*
Y399958D01*
X188125Y400292D01*
X188292Y400500D01*
X188625Y400583D01*
X188958Y400500D01*
X189167Y400250D01*
X189292Y399958D01*
Y398917D01*
G01Y399958D02*
X190500Y400583D01*
G01X188833Y402225D02*
X190500Y403475D01*
G01X188833D02*
X190500Y402225D01*
G01X206000Y385500D02*
Y427500D01*
X194000D01*
Y385500D01*
X206000D01*
G01X188000Y409750D02*
X190500D01*
G01X188000Y408792D02*
Y410708D01*
G01X188833Y412225D02*
X190500Y413475D01*
G01X188833D02*
X190500Y412225D01*
G01X188000Y417708D02*
X190500Y418750D01*
X188000Y419792D01*
G01X189042Y422517D02*
X188875Y422225D01*
X188833Y421975D01*
X188917Y421642D01*
X189083Y421392D01*
X189375Y421225D01*
X189667Y421183D01*
X189958Y421225D01*
X190208Y421392D01*
X190417Y421642D01*
X190500Y421975D01*
X190417Y422267D01*
X190250Y422517D01*
G01X189042Y425617D02*
X188875Y425325D01*
X188833Y425075D01*
X188917Y424742D01*
X189083Y424492D01*
X189375Y424325D01*
X189667Y424283D01*
X189958Y424325D01*
X190208Y424492D01*
X190417Y424742D01*
X190500Y425075D01*
X190417Y425367D01*
X190250Y425617D01*
G01X185300Y448100D02*
X189300D01*
Y455500D01*
G01X189800Y448100D02*
X193800D01*
Y455500D01*
G01X187375Y437333D02*
X187708Y437125D01*
X188083Y437000D01*
X188417D01*
X188750Y437125D01*
X189000Y437333D01*
X189125Y437625D01*
X189042Y437917D01*
X188833Y438167D01*
X188458Y438333D01*
X187958Y438417D01*
X187667Y438583D01*
X187542Y438875D01*
X187625Y439167D01*
X187833Y439375D01*
X188125Y439500D01*
X188417D01*
X188708Y439417D01*
X188958Y439208D01*
G01X192267Y439292D02*
X192017Y439417D01*
X191725Y439500D01*
X191392D01*
X191017Y439375D01*
X190725Y439167D01*
X190517Y438917D01*
X190350Y438500D01*
X190308Y438125D01*
X190392Y437750D01*
X190517Y437500D01*
X190767Y437250D01*
X191058Y437083D01*
X191350Y437000D01*
X191642D01*
X191933Y437083D01*
X192183Y437208D01*
X192392Y437375D01*
G01X194450Y437000D02*
Y439500D01*
X193950Y439000D01*
G01Y437000D02*
X194950D01*
G01X196633Y437500D02*
X196883Y437208D01*
X197217Y437042D01*
X197592Y437000D01*
X197925Y437042D01*
X198258Y437250D01*
X198467Y437500D01*
X198508Y437750D01*
X198425Y438042D01*
X198133Y438250D01*
X197842Y438333D01*
X197467D01*
G01X197842D02*
X198092Y438458D01*
X198300Y438667D01*
X198383Y438917D01*
X198300Y439167D01*
X198092Y439375D01*
X197717Y439500D01*
X197342Y439458D01*
X196967Y439292D01*
G01X200650Y439500D02*
X200317Y439417D01*
X200067Y439208D01*
X199900Y438958D01*
X199775Y438625D01*
X199733Y438250D01*
X199775Y437875D01*
X199900Y437542D01*
X200067Y437292D01*
X200317Y437083D01*
X200650Y437000D01*
X200983Y437083D01*
X201233Y437292D01*
X201400Y437542D01*
X201525Y437875D01*
X201567Y438250D01*
X201525Y438625D01*
X201400Y438958D01*
X201233Y439208D01*
X200983Y439417D01*
X200650Y439500D01*
G01X203667Y437000D02*
X203750Y437542D01*
X203875Y438000D01*
X204042Y438417D01*
X204250Y438875D01*
X204583Y439500D01*
X202917D01*
G01X183225Y482633D02*
X183558Y482425D01*
X183933Y482300D01*
X184267D01*
X184600Y482425D01*
X184850Y482633D01*
X184975Y482925D01*
X184892Y483217D01*
X184683Y483467D01*
X184308Y483633D01*
X183808Y483717D01*
X183517Y483883D01*
X183392Y484175D01*
X183475Y484467D01*
X183683Y484675D01*
X183975Y484800D01*
X184267D01*
X184558Y484717D01*
X184808Y484508D01*
G01X186367Y482300D02*
Y484800D01*
X187408D01*
X187742Y484675D01*
X187950Y484508D01*
X188033Y484175D01*
X187950Y483842D01*
X187700Y483633D01*
X187408Y483508D01*
X186367D01*
G01X187408D02*
X188033Y482300D01*
G01X189592Y482592D02*
X189883Y482383D01*
X190217Y482300D01*
X190550Y482383D01*
X190842Y482633D01*
X191050Y483008D01*
X191133Y483383D01*
Y483842D01*
X191050Y484217D01*
X190842Y484550D01*
X190592Y484717D01*
X190300Y484800D01*
X189967Y484717D01*
X189717Y484550D01*
X189550Y484300D01*
X189467Y483967D01*
X189550Y483675D01*
X189758Y483383D01*
X190008Y483217D01*
X190300Y483175D01*
X190633Y483258D01*
X190883Y483467D01*
X191133Y483842D01*
G01X193900Y482300D02*
Y484800D01*
X192358Y483008D01*
X194442D01*
G01X196500Y484800D02*
X196167Y484717D01*
X195917Y484508D01*
X195750Y484258D01*
X195625Y483925D01*
X195583Y483550D01*
X195625Y483175D01*
X195750Y482842D01*
X195917Y482592D01*
X196167Y482383D01*
X196500Y482300D01*
X196833Y482383D01*
X197083Y482592D01*
X197250Y482842D01*
X197375Y483175D01*
X197417Y483550D01*
X197375Y483925D01*
X197250Y484258D01*
X197083Y484508D01*
X196833Y484717D01*
X196500Y484800D01*
G01X185100Y476800D02*
Y472800D01*
X192500D01*
G01X211755Y525000D02*
X198355D01*
G01D02*
Y535000D01*
G01X187493Y547796D02*
X185893Y549396D01*
G01X187493Y547096D02*
Y551696D01*
G01X211755Y537500D02*
X198355D01*
G01Y547500D02*
X211755D01*
G01X198355Y537500D02*
Y547500D01*
G01Y535000D02*
X211755D01*
G01X185893Y549396D02*
X187493Y550996D01*
G01X197530Y564333D02*
X197863Y564125D01*
X198238Y564000D01*
X198572D01*
X198905Y564125D01*
X199155Y564333D01*
X199280Y564625D01*
X199197Y564917D01*
X198988Y565167D01*
X198613Y565333D01*
X198113Y565417D01*
X197822Y565583D01*
X197697Y565875D01*
X197780Y566167D01*
X197988Y566375D01*
X198280Y566500D01*
X198572D01*
X198863Y566417D01*
X199113Y566208D01*
G01X200588Y566500D02*
Y564708D01*
X200755Y564333D01*
X201088Y564083D01*
X201505Y564000D01*
X201922Y564083D01*
X202255Y564333D01*
X202422Y564708D01*
Y566500D01*
G01X204522Y564000D02*
X204605Y564542D01*
X204730Y565000D01*
X204897Y565417D01*
X205105Y565875D01*
X205438Y566500D01*
X203772D01*
G01X206997Y564292D02*
X207288Y564083D01*
X207622Y564000D01*
X207955Y564083D01*
X208247Y564333D01*
X208455Y564708D01*
X208538Y565083D01*
Y565542D01*
X208455Y565917D01*
X208247Y566250D01*
X207997Y566417D01*
X207705Y566500D01*
X207372Y566417D01*
X207122Y566250D01*
X206955Y566000D01*
X206872Y565667D01*
X206955Y565375D01*
X207163Y565083D01*
X207413Y564917D01*
X207705Y564875D01*
X208038Y564958D01*
X208288Y565167D01*
X208538Y565542D01*
G01X198355Y560500D02*
X211755D01*
G01X198355Y550500D02*
Y560500D01*
G01X211755Y550500D02*
X198355D01*
G01X191555Y572200D02*
X187555D01*
Y564800D01*
G01X187005Y565550D02*
Y562550D01*
X184005D01*
G01X182980Y581333D02*
X183313Y581125D01*
X183688Y581000D01*
X184022D01*
X184355Y581125D01*
X184605Y581333D01*
X184730Y581625D01*
X184647Y581917D01*
X184438Y582167D01*
X184063Y582333D01*
X183563Y582417D01*
X183272Y582583D01*
X183147Y582875D01*
X183230Y583167D01*
X183438Y583375D01*
X183730Y583500D01*
X184022D01*
X184313Y583417D01*
X184563Y583208D01*
G01X186122Y581000D02*
Y583500D01*
X187163D01*
X187497Y583375D01*
X187705Y583208D01*
X187788Y582875D01*
X187705Y582542D01*
X187455Y582333D01*
X187163Y582208D01*
X186122D01*
G01X187163D02*
X187788Y581000D01*
G01X189972D02*
X190055Y581542D01*
X190180Y582000D01*
X190347Y582417D01*
X190555Y582875D01*
X190888Y583500D01*
X189222D01*
G01X192447Y581292D02*
X192738Y581083D01*
X193072Y581000D01*
X193405Y581083D01*
X193697Y581333D01*
X193905Y581708D01*
X193988Y582083D01*
Y582542D01*
X193905Y582917D01*
X193697Y583250D01*
X193447Y583417D01*
X193155Y583500D01*
X192822Y583417D01*
X192572Y583250D01*
X192405Y583000D01*
X192322Y582667D01*
X192405Y582375D01*
X192613Y582083D01*
X192863Y581917D01*
X193155Y581875D01*
X193488Y581958D01*
X193738Y582167D01*
X193988Y582542D01*
G01X195338Y581375D02*
X195588Y581167D01*
X195880Y581042D01*
X196255Y581000D01*
X196630Y581083D01*
X196922Y581250D01*
X197130Y581542D01*
X197172Y581875D01*
X197088Y582208D01*
X196880Y582417D01*
X196588Y582583D01*
X196297Y582625D01*
X196005Y582583D01*
X195630Y582417D01*
X195755Y583500D01*
X196880D01*
G01X185722Y591425D02*
X185930Y591758D01*
X186055Y592133D01*
Y592467D01*
X185930Y592800D01*
X185722Y593050D01*
X185430Y593175D01*
X185138Y593092D01*
X184888Y592883D01*
X184722Y592508D01*
X184638Y592008D01*
X184472Y591717D01*
X184180Y591592D01*
X183888Y591675D01*
X183680Y591883D01*
X183555Y592175D01*
Y592467D01*
X183638Y592758D01*
X183847Y593008D01*
G01X186055Y594567D02*
X183555D01*
Y595608D01*
X183680Y595942D01*
X183847Y596150D01*
X184180Y596233D01*
X184513Y596150D01*
X184722Y595900D01*
X184847Y595608D01*
Y594567D01*
G01Y595608D02*
X186055Y596233D01*
G01Y598417D02*
X185513Y598500D01*
X185055Y598625D01*
X184638Y598792D01*
X184180Y599000D01*
X183555Y599333D01*
Y597667D01*
G01X185763Y600892D02*
X185972Y601183D01*
X186055Y601517D01*
X185972Y601850D01*
X185722Y602142D01*
X185347Y602350D01*
X184972Y602433D01*
X184513D01*
X184138Y602350D01*
X183805Y602142D01*
X183638Y601892D01*
X183555Y601600D01*
X183638Y601267D01*
X183805Y601017D01*
X184055Y600850D01*
X184388Y600767D01*
X184680Y600850D01*
X184972Y601058D01*
X185138Y601308D01*
X185180Y601600D01*
X185097Y601933D01*
X184888Y602183D01*
X184513Y602433D01*
G01X186055Y604700D02*
X183555D01*
X184055Y604200D01*
G01X186055D02*
Y605200D01*
G01X197667Y671475D02*
X197875Y671808D01*
X198000Y672183D01*
Y672517D01*
X197875Y672850D01*
X197667Y673100D01*
X197375Y673225D01*
X197083Y673142D01*
X196833Y672933D01*
X196667Y672558D01*
X196583Y672058D01*
X196417Y671767D01*
X196125Y671642D01*
X195833Y671725D01*
X195625Y671933D01*
X195500Y672225D01*
Y672517D01*
X195583Y672808D01*
X195792Y673058D01*
G01X198000Y675450D02*
X197958Y675117D01*
X197792Y674825D01*
X197542Y674575D01*
X197250Y674408D01*
X196917Y674325D01*
X196583D01*
X196250Y674408D01*
X195958Y674575D01*
X195708Y674825D01*
X195542Y675117D01*
X195500Y675450D01*
X195542Y675783D01*
X195708Y676075D01*
X195958Y676325D01*
X196250Y676492D01*
X196583Y676575D01*
X196917D01*
X197250Y676492D01*
X197542Y676325D01*
X197792Y676075D01*
X197958Y675783D01*
X198000Y675450D01*
G01X197333Y675783D02*
X198000Y676283D01*
G01Y678550D02*
X195500D01*
X196000Y678050D01*
G01X198000D02*
Y679050D01*
G01X197625Y680733D02*
X197833Y680983D01*
X197958Y681275D01*
X198000Y681650D01*
X197917Y682025D01*
X197750Y682317D01*
X197458Y682525D01*
X197125Y682567D01*
X196792Y682483D01*
X196583Y682275D01*
X196417Y681983D01*
X196375Y681692D01*
X196417Y681400D01*
X196583Y681025D01*
X195500Y681150D01*
Y682275D01*
G01X192500Y791400D02*
X192458Y791067D01*
X192292Y790775D01*
X192042Y790525D01*
X191750Y790358D01*
X191417Y790275D01*
X191083D01*
X190750Y790358D01*
X190458Y790525D01*
X190208Y790775D01*
X190042Y791067D01*
X190000Y791400D01*
X190042Y791733D01*
X190208Y792025D01*
X190458Y792275D01*
X190750Y792442D01*
X191083Y792525D01*
X191417D01*
X191750Y792442D01*
X192042Y792275D01*
X192292Y792025D01*
X192458Y791733D01*
X192500Y791400D01*
G01X191833Y791733D02*
X192500Y792233D01*
G01X192208Y793792D02*
X192417Y794083D01*
X192500Y794417D01*
X192417Y794750D01*
X192167Y795042D01*
X191792Y795250D01*
X191417Y795333D01*
X190958D01*
X190583Y795250D01*
X190250Y795042D01*
X190083Y794792D01*
X190000Y794500D01*
X190083Y794167D01*
X190250Y793917D01*
X190500Y793750D01*
X190833Y793667D01*
X191125Y793750D01*
X191417Y793958D01*
X191583Y794208D01*
X191625Y794500D01*
X191542Y794833D01*
X191333Y795083D01*
X190958Y795333D01*
G01X192500Y798100D02*
X190000D01*
X191792Y796558D01*
Y798642D01*
G01X195000Y786500D02*
X209000D01*
G01X195000Y799500D02*
Y786500D01*
G01X209000Y799500D02*
X195000D01*
G01X192500Y802900D02*
X192458Y802567D01*
X192292Y802275D01*
X192042Y802025D01*
X191750Y801858D01*
X191417Y801775D01*
X191083D01*
X190750Y801858D01*
X190458Y802025D01*
X190208Y802275D01*
X190042Y802567D01*
X190000Y802900D01*
X190042Y803233D01*
X190208Y803525D01*
X190458Y803775D01*
X190750Y803942D01*
X191083Y804025D01*
X191417D01*
X191750Y803942D01*
X192042Y803775D01*
X192292Y803525D01*
X192458Y803233D01*
X192500Y802900D01*
G01X191833Y803233D02*
X192500Y803733D01*
G01X192208Y805292D02*
X192417Y805583D01*
X192500Y805917D01*
X192417Y806250D01*
X192167Y806542D01*
X191792Y806750D01*
X191417Y806833D01*
X190958D01*
X190583Y806750D01*
X190250Y806542D01*
X190083Y806292D01*
X190000Y806000D01*
X190083Y805667D01*
X190250Y805417D01*
X190500Y805250D01*
X190833Y805167D01*
X191125Y805250D01*
X191417Y805458D01*
X191583Y805708D01*
X191625Y806000D01*
X191542Y806333D01*
X191333Y806583D01*
X190958Y806833D01*
G01X192000Y808183D02*
X192292Y808433D01*
X192458Y808767D01*
X192500Y809142D01*
X192458Y809475D01*
X192250Y809808D01*
X192000Y810017D01*
X191750Y810058D01*
X191458Y809975D01*
X191250Y809683D01*
X191167Y809392D01*
Y809017D01*
G01Y809392D02*
X191042Y809642D01*
X190833Y809850D01*
X190583Y809933D01*
X190333Y809850D01*
X190125Y809642D01*
X190000Y809267D01*
X190042Y808892D01*
X190208Y808517D01*
G01X195000Y800500D02*
X209000D01*
G01X195000Y813500D02*
Y800500D01*
G01X191517Y820000D02*
Y822500D01*
X192558D01*
X192892Y822375D01*
X193100Y822208D01*
X193183Y821875D01*
X193100Y821542D01*
X192850Y821333D01*
X192558Y821208D01*
X191517D01*
G01X192558D02*
X193183Y820000D01*
G01X194658Y821042D02*
X194950Y821333D01*
X195200Y821500D01*
X195533Y821583D01*
X195825Y821500D01*
X196033Y821333D01*
X196200Y821083D01*
X196242Y820792D01*
X196200Y820542D01*
X196033Y820292D01*
X195783Y820083D01*
X195492Y820000D01*
X195158Y820083D01*
X194867Y820333D01*
X194700Y820708D01*
X194658Y821125D01*
X194742Y821667D01*
X194867Y821958D01*
X195075Y822250D01*
X195367Y822458D01*
X195658Y822500D01*
X195950Y822417D01*
X196158Y822208D01*
G01X197842Y820292D02*
X198133Y820083D01*
X198467Y820000D01*
X198800Y820083D01*
X199092Y820333D01*
X199300Y820708D01*
X199383Y821083D01*
Y821542D01*
X199300Y821917D01*
X199092Y822250D01*
X198842Y822417D01*
X198550Y822500D01*
X198217Y822417D01*
X197967Y822250D01*
X197800Y822000D01*
X197717Y821667D01*
X197800Y821375D01*
X198008Y821083D01*
X198258Y820917D01*
X198550Y820875D01*
X198883Y820958D01*
X199133Y821167D01*
X199383Y821542D01*
G01X200858Y822083D02*
X201108Y822333D01*
X201400Y822458D01*
X201733Y822500D01*
X202150Y822417D01*
X202442Y822208D01*
X202525Y821958D01*
X202483Y821708D01*
X202317Y821500D01*
X201483Y821083D01*
X201108Y820792D01*
X200858Y820375D01*
X200775Y820000D01*
X202525D01*
G01X209000Y813500D02*
X195000D01*
G01X193267Y826792D02*
X193017Y826917D01*
X192725Y827000D01*
X192392D01*
X192017Y826875D01*
X191725Y826667D01*
X191517Y826417D01*
X191350Y826000D01*
X191308Y825625D01*
X191392Y825250D01*
X191517Y825000D01*
X191767Y824750D01*
X192058Y824583D01*
X192350Y824500D01*
X192642D01*
X192933Y824583D01*
X193183Y824708D01*
X193392Y824875D01*
G01X194533Y825000D02*
X194783Y824708D01*
X195117Y824542D01*
X195492Y824500D01*
X195825Y824542D01*
X196158Y824750D01*
X196367Y825000D01*
X196408Y825250D01*
X196325Y825542D01*
X196033Y825750D01*
X195742Y825833D01*
X195367D01*
G01X195742D02*
X195992Y825958D01*
X196200Y826167D01*
X196283Y826417D01*
X196200Y826667D01*
X195992Y826875D01*
X195617Y827000D01*
X195242Y826958D01*
X194867Y826792D01*
G01X197633Y825000D02*
X197883Y824708D01*
X198217Y824542D01*
X198592Y824500D01*
X198925Y824542D01*
X199258Y824750D01*
X199467Y825000D01*
X199508Y825250D01*
X199425Y825542D01*
X199133Y825750D01*
X198842Y825833D01*
X198467D01*
G01X198842D02*
X199092Y825958D01*
X199300Y826167D01*
X199383Y826417D01*
X199300Y826667D01*
X199092Y826875D01*
X198717Y827000D01*
X198342Y826958D01*
X197967Y826792D01*
G01X200942Y824792D02*
X201233Y824583D01*
X201567Y824500D01*
X201900Y824583D01*
X202192Y824833D01*
X202400Y825208D01*
X202483Y825583D01*
Y826042D01*
X202400Y826417D01*
X202192Y826750D01*
X201942Y826917D01*
X201650Y827000D01*
X201317Y826917D01*
X201067Y826750D01*
X200900Y826500D01*
X200817Y826167D01*
X200900Y825875D01*
X201108Y825583D01*
X201358Y825417D01*
X201650Y825375D01*
X201983Y825458D01*
X202233Y825667D01*
X202483Y826042D01*
G01X191517Y816000D02*
Y818500D01*
X192558D01*
X192892Y818375D01*
X193100Y818208D01*
X193183Y817875D01*
X193100Y817542D01*
X192850Y817333D01*
X192558Y817208D01*
X191517D01*
G01X192558D02*
X193183Y816000D01*
G01X194658Y817042D02*
X194950Y817333D01*
X195200Y817500D01*
X195533Y817583D01*
X195825Y817500D01*
X196033Y817333D01*
X196200Y817083D01*
X196242Y816792D01*
X196200Y816542D01*
X196033Y816292D01*
X195783Y816083D01*
X195492Y816000D01*
X195158Y816083D01*
X194867Y816333D01*
X194700Y816708D01*
X194658Y817125D01*
X194742Y817667D01*
X194867Y817958D01*
X195075Y818250D01*
X195367Y818458D01*
X195658Y818500D01*
X195950Y818417D01*
X196158Y818208D01*
G01X197842Y816292D02*
X198133Y816083D01*
X198467Y816000D01*
X198800Y816083D01*
X199092Y816333D01*
X199300Y816708D01*
X199383Y817083D01*
Y817542D01*
X199300Y817917D01*
X199092Y818250D01*
X198842Y818417D01*
X198550Y818500D01*
X198217Y818417D01*
X197967Y818250D01*
X197800Y818000D01*
X197717Y817667D01*
X197800Y817375D01*
X198008Y817083D01*
X198258Y816917D01*
X198550Y816875D01*
X198883Y816958D01*
X199133Y817167D01*
X199383Y817542D01*
G01X201650Y816000D02*
Y818500D01*
X201150Y818000D01*
G01Y816000D02*
X202150D01*
G01X190467Y829500D02*
Y832000D01*
X191508D01*
X191842Y831875D01*
X192050Y831708D01*
X192133Y831375D01*
X192050Y831042D01*
X191800Y830833D01*
X191508Y830708D01*
X190467D01*
G01X191508D02*
X192133Y829500D01*
G01X193608Y831583D02*
X193858Y831833D01*
X194150Y831958D01*
X194483Y832000D01*
X194900Y831917D01*
X195192Y831708D01*
X195275Y831458D01*
X195233Y831208D01*
X195067Y831000D01*
X194233Y830583D01*
X193858Y830292D01*
X193608Y829875D01*
X193525Y829500D01*
X195275D01*
G01X197500D02*
Y832000D01*
X197000Y831500D01*
G01Y829500D02*
X198000D01*
G01X200600D02*
Y832000D01*
X200100Y831500D01*
G01Y829500D02*
X201100D01*
G01X202783Y830000D02*
X203033Y829708D01*
X203367Y829542D01*
X203742Y829500D01*
X204075Y829542D01*
X204408Y829750D01*
X204617Y830000D01*
X204658Y830250D01*
X204575Y830542D01*
X204283Y830750D01*
X203992Y830833D01*
X203617D01*
G01X203992D02*
X204242Y830958D01*
X204450Y831167D01*
X204533Y831417D01*
X204450Y831667D01*
X204242Y831875D01*
X203867Y832000D01*
X203492Y831958D01*
X203117Y831792D01*
G01X195700Y838000D02*
Y842000D01*
X188300D01*
G01X195700D02*
Y846000D01*
X188300D01*
G01X197000Y864500D02*
Y853500D01*
X196000D01*
G01X196500Y866700D02*
X192500D01*
Y859300D01*
G01X195700Y854500D02*
Y858500D01*
X188300D01*
G01X196000Y870000D02*
X198500D01*
Y867500D01*
G01X192200Y863500D02*
Y867500D01*
X184800D01*
G01X188800Y871500D02*
Y867500D01*
X196200D01*
G01Y876500D02*
Y880500D01*
X188800D01*
G01X185300Y888767D02*
X182800D01*
Y889808D01*
X182925Y890142D01*
X183092Y890350D01*
X183425Y890433D01*
X183758Y890350D01*
X183967Y890100D01*
X184092Y889808D01*
Y888767D01*
G01Y889808D02*
X185300Y890433D01*
G01X183217Y891908D02*
X182967Y892158D01*
X182842Y892450D01*
X182800Y892783D01*
X182883Y893200D01*
X183092Y893492D01*
X183342Y893575D01*
X183592Y893533D01*
X183800Y893367D01*
X184217Y892533D01*
X184508Y892158D01*
X184925Y891908D01*
X185300Y891825D01*
Y893575D01*
G01Y895800D02*
X182800D01*
X183300Y895300D01*
G01X185300D02*
Y896300D01*
G01X183217Y898108D02*
X182967Y898358D01*
X182842Y898650D01*
X182800Y898983D01*
X182883Y899400D01*
X183092Y899692D01*
X183342Y899775D01*
X183592Y899733D01*
X183800Y899567D01*
X184217Y898733D01*
X184508Y898358D01*
X184925Y898108D01*
X185300Y898025D01*
Y899775D01*
G01X183217Y901208D02*
X182967Y901458D01*
X182842Y901750D01*
X182800Y902083D01*
X182883Y902500D01*
X183092Y902792D01*
X183342Y902875D01*
X183592Y902833D01*
X183800Y902667D01*
X184217Y901833D01*
X184508Y901458D01*
X184925Y901208D01*
X185300Y901125D01*
Y902875D01*
G01X201000Y889200D02*
X197000D01*
Y881800D01*
G01X193000D02*
X197000D01*
Y889200D01*
G01X196008Y920277D02*
X195883Y920027D01*
X195800Y919735D01*
Y919402D01*
X195925Y919027D01*
X196133Y918735D01*
X196383Y918527D01*
X196800Y918360D01*
X197175Y918318D01*
X197550Y918402D01*
X197800Y918527D01*
X198050Y918777D01*
X198217Y919068D01*
X198300Y919360D01*
Y919652D01*
X198217Y919943D01*
X198092Y920193D01*
X197925Y920402D01*
G01X196217Y921668D02*
X195967Y921918D01*
X195842Y922210D01*
X195800Y922543D01*
X195883Y922960D01*
X196092Y923252D01*
X196342Y923335D01*
X196592Y923293D01*
X196800Y923127D01*
X197217Y922293D01*
X197508Y921918D01*
X197925Y921668D01*
X198300Y921585D01*
Y923335D01*
G01X198008Y924852D02*
X198217Y925143D01*
X198300Y925477D01*
X198217Y925810D01*
X197967Y926102D01*
X197592Y926310D01*
X197217Y926393D01*
X196758D01*
X196383Y926310D01*
X196050Y926102D01*
X195883Y925852D01*
X195800Y925560D01*
X195883Y925227D01*
X196050Y924977D01*
X196300Y924810D01*
X196633Y924727D01*
X196925Y924810D01*
X197217Y925018D01*
X197383Y925268D01*
X197425Y925560D01*
X197342Y925893D01*
X197133Y926143D01*
X196758Y926393D01*
G01X197258Y927868D02*
X196967Y928160D01*
X196800Y928410D01*
X196717Y928743D01*
X196800Y929035D01*
X196967Y929243D01*
X197217Y929410D01*
X197508Y929452D01*
X197758Y929410D01*
X198008Y929243D01*
X198217Y928993D01*
X198300Y928702D01*
X198217Y928368D01*
X197967Y928077D01*
X197592Y927910D01*
X197175Y927868D01*
X196633Y927952D01*
X196342Y928077D01*
X196050Y928285D01*
X195842Y928577D01*
X195800Y928868D01*
X195883Y929160D01*
X196092Y929368D01*
G01X189208Y919767D02*
X189083Y919517D01*
X189000Y919225D01*
Y918892D01*
X189125Y918517D01*
X189333Y918225D01*
X189583Y918017D01*
X190000Y917850D01*
X190375Y917808D01*
X190750Y917892D01*
X191000Y918017D01*
X191250Y918267D01*
X191417Y918558D01*
X191500Y918850D01*
Y919142D01*
X191417Y919433D01*
X191292Y919683D01*
X191125Y919892D01*
G01X189417Y921158D02*
X189167Y921408D01*
X189042Y921700D01*
X189000Y922033D01*
X189083Y922450D01*
X189292Y922742D01*
X189542Y922825D01*
X189792Y922783D01*
X190000Y922617D01*
X190417Y921783D01*
X190708Y921408D01*
X191125Y921158D01*
X191500Y921075D01*
Y922825D01*
G01Y924967D02*
X190958Y925050D01*
X190500Y925175D01*
X190083Y925342D01*
X189625Y925550D01*
X189000Y925883D01*
Y924217D01*
G01X191500Y928650D02*
X189000D01*
X190792Y927108D01*
Y929192D01*
G01X184208Y919767D02*
X184083Y919517D01*
X184000Y919225D01*
Y918892D01*
X184125Y918517D01*
X184333Y918225D01*
X184583Y918017D01*
X185000Y917850D01*
X185375Y917808D01*
X185750Y917892D01*
X186000Y918017D01*
X186250Y918267D01*
X186417Y918558D01*
X186500Y918850D01*
Y919142D01*
X186417Y919433D01*
X186292Y919683D01*
X186125Y919892D01*
G01X184417Y921158D02*
X184167Y921408D01*
X184042Y921700D01*
X184000Y922033D01*
X184083Y922450D01*
X184292Y922742D01*
X184542Y922825D01*
X184792Y922783D01*
X185000Y922617D01*
X185417Y921783D01*
X185708Y921408D01*
X186125Y921158D01*
X186500Y921075D01*
Y922825D01*
G01X186208Y924342D02*
X186417Y924633D01*
X186500Y924967D01*
X186417Y925300D01*
X186167Y925592D01*
X185792Y925800D01*
X185417Y925883D01*
X184958D01*
X184583Y925800D01*
X184250Y925592D01*
X184083Y925342D01*
X184000Y925050D01*
X184083Y924717D01*
X184250Y924467D01*
X184500Y924300D01*
X184833Y924217D01*
X185125Y924300D01*
X185417Y924508D01*
X185583Y924758D01*
X185625Y925050D01*
X185542Y925383D01*
X185333Y925633D01*
X184958Y925883D01*
G01X186208Y927442D02*
X186417Y927733D01*
X186500Y928067D01*
X186417Y928400D01*
X186167Y928692D01*
X185792Y928900D01*
X185417Y928983D01*
X184958D01*
X184583Y928900D01*
X184250Y928692D01*
X184083Y928442D01*
X184000Y928150D01*
X184083Y927817D01*
X184250Y927567D01*
X184500Y927400D01*
X184833Y927317D01*
X185125Y927400D01*
X185417Y927608D01*
X185583Y927858D01*
X185625Y928150D01*
X185542Y928483D01*
X185333Y928733D01*
X184958Y928983D01*
G01X215083Y379833D02*
X215250Y379958D01*
X215375Y380167D01*
X215458Y380458D01*
X215375Y380708D01*
X215208Y380875D01*
X214917Y381000D01*
X213792D01*
Y378500D01*
X215167D01*
X215458Y378667D01*
X215625Y378917D01*
X215708Y379208D01*
X215625Y379500D01*
X215375Y379750D01*
X215083Y379833D01*
X213792D01*
G01X216767Y378500D02*
Y381000D01*
X217850Y378917D01*
X218933Y381000D01*
Y378500D01*
G01X221867Y380792D02*
X221617Y380917D01*
X221325Y381000D01*
X220992D01*
X220617Y380875D01*
X220325Y380667D01*
X220117Y380417D01*
X219950Y380000D01*
X219908Y379625D01*
X219992Y379250D01*
X220117Y379000D01*
X220367Y378750D01*
X220658Y378583D01*
X220950Y378500D01*
X221242D01*
X221533Y378583D01*
X221783Y378708D01*
X221992Y378875D01*
G01X209975Y371333D02*
X210308Y371125D01*
X210683Y371000D01*
X211017D01*
X211350Y371125D01*
X211600Y371333D01*
X211725Y371625D01*
X211642Y371917D01*
X211433Y372167D01*
X211058Y372333D01*
X210558Y372417D01*
X210267Y372583D01*
X210142Y372875D01*
X210225Y373167D01*
X210433Y373375D01*
X210725Y373500D01*
X211017D01*
X211308Y373417D01*
X211558Y373208D01*
G01X214867Y373292D02*
X214617Y373417D01*
X214325Y373500D01*
X213992D01*
X213617Y373375D01*
X213325Y373167D01*
X213117Y372917D01*
X212950Y372500D01*
X212908Y372125D01*
X212992Y371750D01*
X213117Y371500D01*
X213367Y371250D01*
X213658Y371083D01*
X213950Y371000D01*
X214242D01*
X214533Y371083D01*
X214783Y371208D01*
X214992Y371375D01*
G01X216092Y371000D02*
Y373500D01*
X218008Y371000D01*
Y373500D01*
G01X220150Y371000D02*
X220442Y371042D01*
X220775Y371167D01*
X220983Y371375D01*
X221067Y371667D01*
X220983Y371958D01*
X220733Y372208D01*
X220358Y372333D01*
X219942D01*
X219692Y372417D01*
X219483Y372625D01*
X219400Y372917D01*
X219525Y373208D01*
X219817Y373417D01*
X220150Y373500D01*
X220483Y373417D01*
X220775Y373208D01*
X220900Y372917D01*
X220817Y372625D01*
X220608Y372417D01*
X220358Y372333D01*
X219942D01*
X219567Y372208D01*
X219317Y371958D01*
X219233Y371667D01*
X219317Y371375D01*
X219525Y371167D01*
X219858Y371042D01*
X220150Y371000D01*
G01X222500Y385500D02*
Y427500D01*
X210500D01*
Y385500D01*
X222500D01*
G01X203967Y446725D02*
X204175Y447058D01*
X204300Y447433D01*
Y447767D01*
X204175Y448100D01*
X203967Y448350D01*
X203675Y448475D01*
X203383Y448392D01*
X203133Y448183D01*
X202967Y447808D01*
X202883Y447308D01*
X202717Y447017D01*
X202425Y446892D01*
X202133Y446975D01*
X201925Y447183D01*
X201800Y447475D01*
Y447767D01*
X201883Y448058D01*
X202092Y448308D01*
G01X204300Y449867D02*
X201800D01*
Y450908D01*
X201925Y451242D01*
X202092Y451450D01*
X202425Y451533D01*
X202758Y451450D01*
X202967Y451200D01*
X203092Y450908D01*
Y449867D01*
G01Y450908D02*
X204300Y451533D01*
G01X204008Y453092D02*
X204217Y453383D01*
X204300Y453717D01*
X204217Y454050D01*
X203967Y454342D01*
X203592Y454550D01*
X203217Y454633D01*
X202758D01*
X202383Y454550D01*
X202050Y454342D01*
X201883Y454092D01*
X201800Y453800D01*
X201883Y453467D01*
X202050Y453217D01*
X202300Y453050D01*
X202633Y452967D01*
X202925Y453050D01*
X203217Y453258D01*
X203383Y453508D01*
X203425Y453800D01*
X203342Y454133D01*
X203133Y454383D01*
X202758Y454633D01*
G01X204300Y457400D02*
X201800D01*
X203592Y455858D01*
Y457942D01*
G01X202217Y459208D02*
X201967Y459458D01*
X201842Y459750D01*
X201800Y460083D01*
X201883Y460500D01*
X202092Y460792D01*
X202342Y460875D01*
X202592Y460833D01*
X202800Y460667D01*
X203217Y459833D01*
X203508Y459458D01*
X203925Y459208D01*
X204300Y459125D01*
Y460875D01*
G01X208467Y446725D02*
X208675Y447058D01*
X208800Y447433D01*
Y447767D01*
X208675Y448100D01*
X208467Y448350D01*
X208175Y448475D01*
X207883Y448392D01*
X207633Y448183D01*
X207467Y447808D01*
X207383Y447308D01*
X207217Y447017D01*
X206925Y446892D01*
X206633Y446975D01*
X206425Y447183D01*
X206300Y447475D01*
Y447767D01*
X206383Y448058D01*
X206592Y448308D01*
G01X208800Y449867D02*
X206300D01*
Y450908D01*
X206425Y451242D01*
X206592Y451450D01*
X206925Y451533D01*
X207258Y451450D01*
X207467Y451200D01*
X207592Y450908D01*
Y449867D01*
G01Y450908D02*
X208800Y451533D01*
G01X208508Y453092D02*
X208717Y453383D01*
X208800Y453717D01*
X208717Y454050D01*
X208467Y454342D01*
X208092Y454550D01*
X207717Y454633D01*
X207258D01*
X206883Y454550D01*
X206550Y454342D01*
X206383Y454092D01*
X206300Y453800D01*
X206383Y453467D01*
X206550Y453217D01*
X206800Y453050D01*
X207133Y452967D01*
X207425Y453050D01*
X207717Y453258D01*
X207883Y453508D01*
X207925Y453800D01*
X207842Y454133D01*
X207633Y454383D01*
X207258Y454633D01*
G01X208800Y457400D02*
X206300D01*
X208092Y455858D01*
Y457942D01*
G01X208800Y460000D02*
X206300D01*
X206800Y459500D01*
G01X208800D02*
Y460500D01*
G01X207375Y440833D02*
X207708Y440625D01*
X208083Y440500D01*
X208417D01*
X208750Y440625D01*
X209000Y440833D01*
X209125Y441125D01*
X209042Y441417D01*
X208833Y441667D01*
X208458Y441833D01*
X207958Y441917D01*
X207667Y442083D01*
X207542Y442375D01*
X207625Y442667D01*
X207833Y442875D01*
X208125Y443000D01*
X208417D01*
X208708Y442917D01*
X208958Y442708D01*
G01X212267Y442792D02*
X212017Y442917D01*
X211725Y443000D01*
X211392D01*
X211017Y442875D01*
X210725Y442667D01*
X210517Y442417D01*
X210350Y442000D01*
X210308Y441625D01*
X210392Y441250D01*
X210517Y441000D01*
X210767Y440750D01*
X211058Y440583D01*
X211350Y440500D01*
X211642D01*
X211933Y440583D01*
X212183Y440708D01*
X212392Y440875D01*
G01X214450Y440500D02*
Y443000D01*
X213950Y442500D01*
G01Y440500D02*
X214950D01*
G01X216633Y441000D02*
X216883Y440708D01*
X217217Y440542D01*
X217592Y440500D01*
X217925Y440542D01*
X218258Y440750D01*
X218467Y441000D01*
X218508Y441250D01*
X218425Y441542D01*
X218133Y441750D01*
X217842Y441833D01*
X217467D01*
G01X217842D02*
X218092Y441958D01*
X218300Y442167D01*
X218383Y442417D01*
X218300Y442667D01*
X218092Y442875D01*
X217717Y443000D01*
X217342Y442958D01*
X216967Y442792D01*
G01X220650Y443000D02*
X220317Y442917D01*
X220067Y442708D01*
X219900Y442458D01*
X219775Y442125D01*
X219733Y441750D01*
X219775Y441375D01*
X219900Y441042D01*
X220067Y440792D01*
X220317Y440583D01*
X220650Y440500D01*
X220983Y440583D01*
X221233Y440792D01*
X221400Y441042D01*
X221525Y441375D01*
X221567Y441750D01*
X221525Y442125D01*
X221400Y442458D01*
X221233Y442708D01*
X220983Y442917D01*
X220650Y443000D01*
G01X222958Y441542D02*
X223250Y441833D01*
X223500Y442000D01*
X223833Y442083D01*
X224125Y442000D01*
X224333Y441833D01*
X224500Y441583D01*
X224542Y441292D01*
X224500Y441042D01*
X224333Y440792D01*
X224083Y440583D01*
X223792Y440500D01*
X223458Y440583D01*
X223167Y440833D01*
X223000Y441208D01*
X222958Y441625D01*
X223042Y442167D01*
X223167Y442458D01*
X223375Y442750D01*
X223667Y442958D01*
X223958Y443000D01*
X224250Y442917D01*
X224458Y442708D01*
G01X206967Y465675D02*
X207175Y466008D01*
X207300Y466383D01*
Y466717D01*
X207175Y467050D01*
X206967Y467300D01*
X206675Y467425D01*
X206383Y467342D01*
X206133Y467133D01*
X205967Y466758D01*
X205883Y466258D01*
X205717Y465967D01*
X205425Y465842D01*
X205133Y465925D01*
X204925Y466133D01*
X204800Y466425D01*
Y466717D01*
X204883Y467008D01*
X205092Y467258D01*
G01X205008Y470567D02*
X204883Y470317D01*
X204800Y470025D01*
Y469692D01*
X204925Y469317D01*
X205133Y469025D01*
X205383Y468817D01*
X205800Y468650D01*
X206175Y468608D01*
X206550Y468692D01*
X206800Y468817D01*
X207050Y469067D01*
X207217Y469358D01*
X207300Y469650D01*
Y469942D01*
X207217Y470233D01*
X207092Y470483D01*
X206925Y470692D01*
G01X207300Y472750D02*
X204800D01*
X205300Y472250D01*
G01X207300D02*
Y473250D01*
G01X205217Y475058D02*
X204967Y475308D01*
X204842Y475600D01*
X204800Y475933D01*
X204883Y476350D01*
X205092Y476642D01*
X205342Y476725D01*
X205592Y476683D01*
X205800Y476517D01*
X206217Y475683D01*
X206508Y475308D01*
X206925Y475058D01*
X207300Y474975D01*
Y476725D01*
G01X207008Y478242D02*
X207217Y478533D01*
X207300Y478867D01*
X207217Y479200D01*
X206967Y479492D01*
X206592Y479700D01*
X206217Y479783D01*
X205758D01*
X205383Y479700D01*
X205050Y479492D01*
X204883Y479242D01*
X204800Y478950D01*
X204883Y478617D01*
X205050Y478367D01*
X205300Y478200D01*
X205633Y478117D01*
X205925Y478200D01*
X206217Y478408D01*
X206383Y478658D01*
X206425Y478950D01*
X206342Y479283D01*
X206133Y479533D01*
X205758Y479783D01*
G01X207300Y482050D02*
X207258Y482342D01*
X207133Y482675D01*
X206925Y482883D01*
X206633Y482967D01*
X206342Y482883D01*
X206092Y482633D01*
X205967Y482258D01*
Y481842D01*
X205883Y481592D01*
X205675Y481383D01*
X205383Y481300D01*
X205092Y481425D01*
X204883Y481717D01*
X204800Y482050D01*
X204883Y482383D01*
X205092Y482675D01*
X205383Y482800D01*
X205675Y482717D01*
X205883Y482508D01*
X205967Y482258D01*
Y481842D01*
X206092Y481467D01*
X206342Y481217D01*
X206633Y481133D01*
X206925Y481217D01*
X207133Y481425D01*
X207258Y481758D01*
X207300Y482050D01*
G01X202467Y465675D02*
X202675Y466008D01*
X202800Y466383D01*
Y466717D01*
X202675Y467050D01*
X202467Y467300D01*
X202175Y467425D01*
X201883Y467342D01*
X201633Y467133D01*
X201467Y466758D01*
X201383Y466258D01*
X201217Y465967D01*
X200925Y465842D01*
X200633Y465925D01*
X200425Y466133D01*
X200300Y466425D01*
Y466717D01*
X200383Y467008D01*
X200592Y467258D01*
G01X200508Y470567D02*
X200383Y470317D01*
X200300Y470025D01*
Y469692D01*
X200425Y469317D01*
X200633Y469025D01*
X200883Y468817D01*
X201300Y468650D01*
X201675Y468608D01*
X202050Y468692D01*
X202300Y468817D01*
X202550Y469067D01*
X202717Y469358D01*
X202800Y469650D01*
Y469942D01*
X202717Y470233D01*
X202592Y470483D01*
X202425Y470692D01*
G01X202800Y472750D02*
X200300D01*
X200800Y472250D01*
G01X202800D02*
Y473250D01*
G01X202300Y474933D02*
X202592Y475183D01*
X202758Y475517D01*
X202800Y475892D01*
X202758Y476225D01*
X202550Y476558D01*
X202300Y476767D01*
X202050Y476808D01*
X201758Y476725D01*
X201550Y476433D01*
X201467Y476142D01*
Y475767D01*
G01Y476142D02*
X201342Y476392D01*
X201133Y476600D01*
X200883Y476683D01*
X200633Y476600D01*
X200425Y476392D01*
X200300Y476017D01*
X200342Y475642D01*
X200508Y475267D01*
G01X200300Y478950D02*
X200383Y478617D01*
X200592Y478367D01*
X200842Y478200D01*
X201175Y478075D01*
X201550Y478033D01*
X201925Y478075D01*
X202258Y478200D01*
X202508Y478367D01*
X202717Y478617D01*
X202800Y478950D01*
X202717Y479283D01*
X202508Y479533D01*
X202258Y479700D01*
X201925Y479825D01*
X201550Y479867D01*
X201175Y479825D01*
X200842Y479700D01*
X200592Y479533D01*
X200383Y479283D01*
X200300Y478950D01*
G01Y482050D02*
X200383Y481717D01*
X200592Y481467D01*
X200842Y481300D01*
X201175Y481175D01*
X201550Y481133D01*
X201925Y481175D01*
X202258Y481300D01*
X202508Y481467D01*
X202717Y481717D01*
X202800Y482050D01*
X202717Y482383D01*
X202508Y482633D01*
X202258Y482800D01*
X201925Y482925D01*
X201550Y482967D01*
X201175Y482925D01*
X200842Y482800D01*
X200592Y482633D01*
X200383Y482383D01*
X200300Y482050D01*
G01X200480Y514333D02*
X200813Y514125D01*
X201188Y514000D01*
X201522D01*
X201855Y514125D01*
X202105Y514333D01*
X202230Y514625D01*
X202147Y514917D01*
X201938Y515167D01*
X201563Y515333D01*
X201063Y515417D01*
X200772Y515583D01*
X200647Y515875D01*
X200730Y516167D01*
X200938Y516375D01*
X201230Y516500D01*
X201522D01*
X201813Y516417D01*
X202063Y516208D01*
G01X203622Y514000D02*
Y516500D01*
X204663D01*
X204997Y516375D01*
X205205Y516208D01*
X205288Y515875D01*
X205205Y515542D01*
X204955Y515333D01*
X204663Y515208D01*
X203622D01*
G01X204663D02*
X205288Y514000D01*
G01X207472D02*
X207555Y514542D01*
X207680Y515000D01*
X207847Y515417D01*
X208055Y515875D01*
X208388Y516500D01*
X206722D01*
G01X210655Y514000D02*
X210947Y514042D01*
X211280Y514167D01*
X211488Y514375D01*
X211572Y514667D01*
X211488Y514958D01*
X211238Y515208D01*
X210863Y515333D01*
X210447D01*
X210197Y515417D01*
X209988Y515625D01*
X209905Y515917D01*
X210030Y516208D01*
X210322Y516417D01*
X210655Y516500D01*
X210988Y516417D01*
X211280Y516208D01*
X211405Y515917D01*
X211322Y515625D01*
X211113Y515417D01*
X210863Y515333D01*
X210447D01*
X210072Y515208D01*
X209822Y514958D01*
X209738Y514667D01*
X209822Y514375D01*
X210030Y514167D01*
X210363Y514042D01*
X210655Y514000D01*
G01X214255D02*
Y516500D01*
X212713Y514708D01*
X214797D01*
G01X214055Y526983D02*
X215847D01*
X216222Y527150D01*
X216472Y527483D01*
X216555Y527900D01*
X216472Y528317D01*
X216222Y528650D01*
X215847Y528817D01*
X214055D01*
G01X216055Y530083D02*
X216347Y530333D01*
X216513Y530667D01*
X216555Y531042D01*
X216513Y531375D01*
X216305Y531708D01*
X216055Y531917D01*
X215805Y531958D01*
X215513Y531875D01*
X215305Y531583D01*
X215222Y531292D01*
Y530917D01*
G01Y531292D02*
X215097Y531542D01*
X214888Y531750D01*
X214638Y531833D01*
X214388Y531750D01*
X214180Y531542D01*
X214055Y531167D01*
X214097Y530792D01*
X214263Y530417D01*
G01X216263Y533392D02*
X216472Y533683D01*
X216555Y534017D01*
X216472Y534350D01*
X216222Y534642D01*
X215847Y534850D01*
X215472Y534933D01*
X215013D01*
X214638Y534850D01*
X214305Y534642D01*
X214138Y534392D01*
X214055Y534100D01*
X214138Y533767D01*
X214305Y533517D01*
X214555Y533350D01*
X214888Y533267D01*
X215180Y533350D01*
X215472Y533558D01*
X215638Y533808D01*
X215680Y534100D01*
X215597Y534433D01*
X215388Y534683D01*
X215013Y534933D01*
G01X211755Y535000D02*
Y525000D01*
G01X205823Y523183D02*
Y519183D01*
X213223D01*
G01X216222Y537475D02*
X216430Y537808D01*
X216555Y538183D01*
Y538517D01*
X216430Y538850D01*
X216222Y539100D01*
X215930Y539225D01*
X215638Y539142D01*
X215388Y538933D01*
X215222Y538558D01*
X215138Y538058D01*
X214972Y537767D01*
X214680Y537642D01*
X214388Y537725D01*
X214180Y537933D01*
X214055Y538225D01*
Y538517D01*
X214138Y538808D01*
X214347Y539058D01*
G01X214055Y540533D02*
X215847D01*
X216222Y540700D01*
X216472Y541033D01*
X216555Y541450D01*
X216472Y541867D01*
X216222Y542200D01*
X215847Y542367D01*
X214055D01*
G01X216555Y544550D02*
X216513Y544842D01*
X216388Y545175D01*
X216180Y545383D01*
X215888Y545467D01*
X215597Y545383D01*
X215347Y545133D01*
X215222Y544758D01*
Y544342D01*
X215138Y544092D01*
X214930Y543883D01*
X214638Y543800D01*
X214347Y543925D01*
X214138Y544217D01*
X214055Y544550D01*
X214138Y544883D01*
X214347Y545175D01*
X214638Y545300D01*
X214930Y545217D01*
X215138Y545008D01*
X215222Y544758D01*
Y544342D01*
X215347Y543967D01*
X215597Y543717D01*
X215888Y543633D01*
X216180Y543717D01*
X216388Y543925D01*
X216513Y544258D01*
X216555Y544550D01*
G01X214055Y547650D02*
X214138Y547317D01*
X214347Y547067D01*
X214597Y546900D01*
X214930Y546775D01*
X215305Y546733D01*
X215680Y546775D01*
X216013Y546900D01*
X216263Y547067D01*
X216472Y547317D01*
X216555Y547650D01*
X216472Y547983D01*
X216263Y548233D01*
X216013Y548400D01*
X215680Y548525D01*
X215305Y548567D01*
X214930Y548525D01*
X214597Y548400D01*
X214347Y548233D01*
X214138Y547983D01*
X214055Y547650D01*
G01X211755Y547500D02*
Y537500D01*
G01Y560500D02*
Y550500D01*
G01X203430Y572833D02*
X203763Y572625D01*
X204138Y572500D01*
X204472D01*
X204805Y572625D01*
X205055Y572833D01*
X205180Y573125D01*
X205097Y573417D01*
X204888Y573667D01*
X204513Y573833D01*
X204013Y573917D01*
X203722Y574083D01*
X203597Y574375D01*
X203680Y574667D01*
X203888Y574875D01*
X204180Y575000D01*
X204472D01*
X204763Y574917D01*
X205013Y574708D01*
G01X206572Y572500D02*
Y575000D01*
X207613D01*
X207947Y574875D01*
X208155Y574708D01*
X208238Y574375D01*
X208155Y574042D01*
X207905Y573833D01*
X207613Y573708D01*
X206572D01*
G01X207613D02*
X208238Y572500D01*
G01X210505D02*
Y575000D01*
X210005Y574500D01*
G01Y572500D02*
X211005D01*
G01X212813Y574583D02*
X213063Y574833D01*
X213355Y574958D01*
X213688Y575000D01*
X214105Y574917D01*
X214397Y574708D01*
X214480Y574458D01*
X214438Y574208D01*
X214272Y574000D01*
X213438Y573583D01*
X213063Y573292D01*
X212813Y572875D01*
X212730Y572500D01*
X214480D01*
G01X216622D02*
X216705Y573042D01*
X216830Y573500D01*
X216997Y573917D01*
X217205Y574375D01*
X217538Y575000D01*
X215872D01*
G01X218888Y573000D02*
X219138Y572708D01*
X219472Y572542D01*
X219847Y572500D01*
X220180Y572542D01*
X220513Y572750D01*
X220722Y573000D01*
X220763Y573250D01*
X220680Y573542D01*
X220388Y573750D01*
X220097Y573833D01*
X219722D01*
G01X220097D02*
X220347Y573958D01*
X220555Y574167D01*
X220638Y574417D01*
X220555Y574667D01*
X220347Y574875D01*
X219972Y575000D01*
X219597Y574958D01*
X219222Y574792D01*
G01X203430Y577333D02*
X203763Y577125D01*
X204138Y577000D01*
X204472D01*
X204805Y577125D01*
X205055Y577333D01*
X205180Y577625D01*
X205097Y577917D01*
X204888Y578167D01*
X204513Y578333D01*
X204013Y578417D01*
X203722Y578583D01*
X203597Y578875D01*
X203680Y579167D01*
X203888Y579375D01*
X204180Y579500D01*
X204472D01*
X204763Y579417D01*
X205013Y579208D01*
G01X206572Y577000D02*
Y579500D01*
X207613D01*
X207947Y579375D01*
X208155Y579208D01*
X208238Y578875D01*
X208155Y578542D01*
X207905Y578333D01*
X207613Y578208D01*
X206572D01*
G01X207613D02*
X208238Y577000D01*
G01X210505D02*
Y579500D01*
X210005Y579000D01*
G01Y577000D02*
X211005D01*
G01X212813Y579083D02*
X213063Y579333D01*
X213355Y579458D01*
X213688Y579500D01*
X214105Y579417D01*
X214397Y579208D01*
X214480Y578958D01*
X214438Y578708D01*
X214272Y578500D01*
X213438Y578083D01*
X213063Y577792D01*
X212813Y577375D01*
X212730Y577000D01*
X214480D01*
G01X216622D02*
X216705Y577542D01*
X216830Y578000D01*
X216997Y578417D01*
X217205Y578875D01*
X217538Y579500D01*
X215872D01*
G01X219722Y577000D02*
X219805Y577542D01*
X219930Y578000D01*
X220097Y578417D01*
X220305Y578875D01*
X220638Y579500D01*
X218972D01*
G01X209167Y688425D02*
X209375Y688758D01*
X209500Y689133D01*
Y689467D01*
X209375Y689800D01*
X209167Y690050D01*
X208875Y690175D01*
X208583Y690092D01*
X208333Y689883D01*
X208167Y689508D01*
X208083Y689008D01*
X207917Y688717D01*
X207625Y688592D01*
X207333Y688675D01*
X207125Y688883D01*
X207000Y689175D01*
Y689467D01*
X207083Y689758D01*
X207292Y690008D01*
G01X209500Y691567D02*
X207000D01*
Y692608D01*
X207125Y692942D01*
X207292Y693150D01*
X207625Y693233D01*
X207958Y693150D01*
X208167Y692900D01*
X208292Y692608D01*
Y691567D01*
G01Y692608D02*
X209500Y693233D01*
G01Y695500D02*
X209458Y695792D01*
X209333Y696125D01*
X209125Y696333D01*
X208833Y696417D01*
X208542Y696333D01*
X208292Y696083D01*
X208167Y695708D01*
Y695292D01*
X208083Y695042D01*
X207875Y694833D01*
X207583Y694750D01*
X207292Y694875D01*
X207083Y695167D01*
X207000Y695500D01*
X207083Y695833D01*
X207292Y696125D01*
X207583Y696250D01*
X207875Y696167D01*
X208083Y695958D01*
X208167Y695708D01*
Y695292D01*
X208292Y694917D01*
X208542Y694667D01*
X208833Y694583D01*
X209125Y694667D01*
X209333Y694875D01*
X209458Y695208D01*
X209500Y695500D01*
G01X207000Y698600D02*
X207083Y698267D01*
X207292Y698017D01*
X207542Y697850D01*
X207875Y697725D01*
X208250Y697683D01*
X208625Y697725D01*
X208958Y697850D01*
X209208Y698017D01*
X209417Y698267D01*
X209500Y698600D01*
X209417Y698933D01*
X209208Y699183D01*
X208958Y699350D01*
X208625Y699475D01*
X208250Y699517D01*
X207875Y699475D01*
X207542Y699350D01*
X207292Y699183D01*
X207083Y698933D01*
X207000Y698600D01*
G01X209208Y700992D02*
X209417Y701283D01*
X209500Y701617D01*
X209417Y701950D01*
X209167Y702242D01*
X208792Y702450D01*
X208417Y702533D01*
X207958D01*
X207583Y702450D01*
X207250Y702242D01*
X207083Y701992D01*
X207000Y701700D01*
X207083Y701367D01*
X207250Y701117D01*
X207500Y700950D01*
X207833Y700867D01*
X208125Y700950D01*
X208417Y701158D01*
X208583Y701408D01*
X208625Y701700D01*
X208542Y702033D01*
X208333Y702283D01*
X207958Y702533D01*
G01X213667Y688425D02*
X213875Y688758D01*
X214000Y689133D01*
Y689467D01*
X213875Y689800D01*
X213667Y690050D01*
X213375Y690175D01*
X213083Y690092D01*
X212833Y689883D01*
X212667Y689508D01*
X212583Y689008D01*
X212417Y688717D01*
X212125Y688592D01*
X211833Y688675D01*
X211625Y688883D01*
X211500Y689175D01*
Y689467D01*
X211583Y689758D01*
X211792Y690008D01*
G01X214000Y691567D02*
X211500D01*
Y692608D01*
X211625Y692942D01*
X211792Y693150D01*
X212125Y693233D01*
X212458Y693150D01*
X212667Y692900D01*
X212792Y692608D01*
Y691567D01*
G01Y692608D02*
X214000Y693233D01*
G01Y695500D02*
X213958Y695792D01*
X213833Y696125D01*
X213625Y696333D01*
X213333Y696417D01*
X213042Y696333D01*
X212792Y696083D01*
X212667Y695708D01*
Y695292D01*
X212583Y695042D01*
X212375Y694833D01*
X212083Y694750D01*
X211792Y694875D01*
X211583Y695167D01*
X211500Y695500D01*
X211583Y695833D01*
X211792Y696125D01*
X212083Y696250D01*
X212375Y696167D01*
X212583Y695958D01*
X212667Y695708D01*
Y695292D01*
X212792Y694917D01*
X213042Y694667D01*
X213333Y694583D01*
X213625Y694667D01*
X213833Y694875D01*
X213958Y695208D01*
X214000Y695500D01*
G01Y698600D02*
X211500D01*
X212000Y698100D01*
G01X214000D02*
Y699100D01*
G01X211500Y701700D02*
X211583Y701367D01*
X211792Y701117D01*
X212042Y700950D01*
X212375Y700825D01*
X212750Y700783D01*
X213125Y700825D01*
X213458Y700950D01*
X213708Y701117D01*
X213917Y701367D01*
X214000Y701700D01*
X213917Y702033D01*
X213708Y702283D01*
X213458Y702450D01*
X213125Y702575D01*
X212750Y702617D01*
X212375Y702575D01*
X212042Y702450D01*
X211792Y702283D01*
X211583Y702033D01*
X211500Y701700D01*
G01X205500Y705300D02*
X209500D01*
Y712700D01*
G01X210000Y705300D02*
X214000D01*
Y712700D01*
G01X214500Y705300D02*
X218500D01*
Y712700D01*
G01X215093Y757742D02*
X215426Y757534D01*
X215801Y757409D01*
X216135D01*
X216468Y757534D01*
X216718Y757742D01*
X216843Y758034D01*
X216760Y758326D01*
X216551Y758576D01*
X216176Y758742D01*
X215676Y758826D01*
X215385Y758992D01*
X215260Y759284D01*
X215343Y759576D01*
X215551Y759784D01*
X215843Y759909D01*
X216135D01*
X216426Y759826D01*
X216676Y759617D01*
G01X219985Y759701D02*
X219735Y759826D01*
X219443Y759909D01*
X219110D01*
X218735Y759784D01*
X218443Y759576D01*
X218235Y759326D01*
X218068Y758909D01*
X218026Y758534D01*
X218110Y758159D01*
X218235Y757909D01*
X218485Y757659D01*
X218776Y757492D01*
X219068Y757409D01*
X219360D01*
X219651Y757492D01*
X219901Y757617D01*
X220110Y757784D01*
G01X221210Y757409D02*
Y759909D01*
X223126Y757409D01*
Y759909D01*
G01X224351Y757909D02*
X224601Y757617D01*
X224935Y757451D01*
X225310Y757409D01*
X225643Y757451D01*
X225976Y757659D01*
X226185Y757909D01*
X226226Y758159D01*
X226143Y758451D01*
X225851Y758659D01*
X225560Y758742D01*
X225185D01*
G01X225560D02*
X225810Y758867D01*
X226018Y759076D01*
X226101Y759326D01*
X226018Y759576D01*
X225810Y759784D01*
X225435Y759909D01*
X225060Y759867D01*
X224685Y759701D01*
G01X209000Y786500D02*
Y799500D01*
G01Y800500D02*
Y813500D01*
G01X210300Y814000D02*
Y810000D01*
X217700D01*
G01X212000Y834700D02*
X208000D01*
Y827300D01*
G01X213150Y844650D02*
X208150D01*
Y849650D01*
G01X207050Y857513D02*
X209050D01*
G01X206700Y874333D02*
X208492D01*
X208867Y874500D01*
X209117Y874833D01*
X209200Y875250D01*
X209117Y875667D01*
X208867Y876000D01*
X208492Y876167D01*
X206700D01*
G01X207117Y877558D02*
X206867Y877808D01*
X206742Y878100D01*
X206700Y878433D01*
X206783Y878850D01*
X206992Y879142D01*
X207242Y879225D01*
X207492Y879183D01*
X207700Y879017D01*
X208117Y878183D01*
X208408Y877808D01*
X208825Y877558D01*
X209200Y877475D01*
Y879225D01*
G01X218000Y889200D02*
X214000D01*
Y881800D01*
G01Y889200D02*
X210000D01*
Y881800D01*
G01X206000D02*
X210000D01*
Y889200D01*
G01X218950Y916800D02*
X209850D01*
Y895000D01*
X218950D01*
Y916800D01*
G01X201208Y920267D02*
X201083Y920017D01*
X201000Y919725D01*
Y919392D01*
X201125Y919017D01*
X201333Y918725D01*
X201583Y918517D01*
X202000Y918350D01*
X202375Y918308D01*
X202750Y918392D01*
X203000Y918517D01*
X203250Y918767D01*
X203417Y919058D01*
X203500Y919350D01*
Y919642D01*
X203417Y919933D01*
X203292Y920183D01*
X203125Y920392D01*
G01X203000Y921533D02*
X203292Y921783D01*
X203458Y922117D01*
X203500Y922492D01*
X203458Y922825D01*
X203250Y923158D01*
X203000Y923367D01*
X202750Y923408D01*
X202458Y923325D01*
X202250Y923033D01*
X202167Y922742D01*
Y922367D01*
G01Y922742D02*
X202042Y922992D01*
X201833Y923200D01*
X201583Y923283D01*
X201333Y923200D01*
X201125Y922992D01*
X201000Y922617D01*
X201042Y922242D01*
X201208Y921867D01*
G01X201000Y925550D02*
X201083Y925217D01*
X201292Y924967D01*
X201542Y924800D01*
X201875Y924675D01*
X202250Y924633D01*
X202625Y924675D01*
X202958Y924800D01*
X203208Y924967D01*
X203417Y925217D01*
X203500Y925550D01*
X203417Y925883D01*
X203208Y926133D01*
X202958Y926300D01*
X202625Y926425D01*
X202250Y926467D01*
X201875Y926425D01*
X201542Y926300D01*
X201292Y926133D01*
X201083Y925883D01*
X201000Y925550D01*
G01Y928650D02*
X201083Y928317D01*
X201292Y928067D01*
X201542Y927900D01*
X201875Y927775D01*
X202250Y927733D01*
X202625Y927775D01*
X202958Y927900D01*
X203208Y928067D01*
X203417Y928317D01*
X203500Y928650D01*
X203417Y928983D01*
X203208Y929233D01*
X202958Y929400D01*
X202625Y929525D01*
X202250Y929567D01*
X201875Y929525D01*
X201542Y929400D01*
X201292Y929233D01*
X201083Y928983D01*
X201000Y928650D01*
G01X215900Y920383D02*
X213400D01*
Y921217D01*
X213525Y921550D01*
X213692Y921800D01*
X213942Y922008D01*
X214233Y922175D01*
X214650Y922217D01*
X215067Y922175D01*
X215358Y922008D01*
X215608Y921800D01*
X215775Y921550D01*
X215900Y921217D01*
Y920383D01*
G01X215400Y923483D02*
X215692Y923733D01*
X215858Y924067D01*
X215900Y924442D01*
X215858Y924775D01*
X215650Y925108D01*
X215400Y925317D01*
X215150Y925358D01*
X214858Y925275D01*
X214650Y924983D01*
X214567Y924692D01*
Y924317D01*
G01Y924692D02*
X214442Y924942D01*
X214233Y925150D01*
X213983Y925233D01*
X213733Y925150D01*
X213525Y924942D01*
X213400Y924567D01*
X213442Y924192D01*
X213608Y923817D01*
G01X215900Y927417D02*
X215358Y927500D01*
X214900Y927625D01*
X214483Y927792D01*
X214025Y928000D01*
X213400Y928333D01*
Y926667D01*
G01X230698Y-22968D02*
X230232Y-22501D01*
X229965Y-22101D01*
X229832Y-21568D01*
X229965Y-21101D01*
X230232Y-20768D01*
X230632Y-20501D01*
X231098Y-20434D01*
X231498Y-20501D01*
X231898Y-20768D01*
X232232Y-21168D01*
X232365Y-21634D01*
X232232Y-22168D01*
X231832Y-22634D01*
X231232Y-22901D01*
X230565Y-22968D01*
X229698Y-22834D01*
X229232Y-22634D01*
X228765Y-22301D01*
X228432Y-21834D01*
X228365Y-21368D01*
X228498Y-20901D01*
X228832Y-20568D01*
G01X226750Y388500D02*
Y389333D01*
X227500D01*
X227750Y389083D01*
X227917Y388792D01*
X228000Y388375D01*
X227917Y387958D01*
X227750Y387667D01*
X227500Y387417D01*
X227208Y387250D01*
X226875Y387167D01*
X226583D01*
X226333Y387250D01*
X226042Y387417D01*
X225792Y387667D01*
X225625Y387917D01*
X225500Y388250D01*
Y388542D01*
X225583Y388875D01*
X225750Y389125D01*
G01X228000Y390642D02*
X226333D01*
G01X226750D02*
X226542Y390808D01*
X226375Y391058D01*
X226333Y391392D01*
X226375Y391683D01*
X226542Y391933D01*
X226833Y392058D01*
X228000D01*
G01X225500Y395200D02*
X228000D01*
G01X227625D02*
X227833Y395033D01*
X227958Y394783D01*
X228000Y394492D01*
X227917Y394158D01*
X227708Y393908D01*
X227458Y393742D01*
X227167Y393700D01*
X226875Y393742D01*
X226625Y393908D01*
X226417Y394158D01*
X226333Y394492D01*
X226375Y394783D01*
X226458Y394992D01*
X226625Y395200D01*
G01X228000Y399417D02*
X225500D01*
Y400458D01*
X225625Y400792D01*
X225792Y401000D01*
X226125Y401083D01*
X226458Y401000D01*
X226667Y400750D01*
X226792Y400458D01*
Y399417D01*
G01Y400458D02*
X228000Y401083D01*
G01X226333Y402725D02*
X228000Y403975D01*
G01X226333D02*
X228000Y402725D01*
G01X225000Y410250D02*
X227500D01*
G01X225000Y409292D02*
Y411208D01*
G01X225833Y412725D02*
X227500Y413975D01*
G01X225833D02*
X227500Y412725D01*
G01X225000Y418208D02*
X227500Y419250D01*
X225000Y420292D01*
G01X226042Y423017D02*
X225875Y422725D01*
X225833Y422475D01*
X225917Y422142D01*
X226083Y421892D01*
X226375Y421725D01*
X226667Y421683D01*
X226958Y421725D01*
X227208Y421892D01*
X227417Y422142D01*
X227500Y422475D01*
X227417Y422767D01*
X227250Y423017D01*
G01X226042Y426117D02*
X225875Y425825D01*
X225833Y425575D01*
X225917Y425242D01*
X226083Y424992D01*
X226375Y424825D01*
X226667Y424783D01*
X226958Y424825D01*
X227208Y424992D01*
X227417Y425242D01*
X227500Y425575D01*
X227417Y425867D01*
X227250Y426117D01*
G01X227925Y435833D02*
X228258Y435625D01*
X228633Y435500D01*
X228967D01*
X229300Y435625D01*
X229550Y435833D01*
X229675Y436125D01*
X229592Y436417D01*
X229383Y436667D01*
X229008Y436833D01*
X228508Y436917D01*
X228217Y437083D01*
X228092Y437375D01*
X228175Y437667D01*
X228383Y437875D01*
X228675Y438000D01*
X228967D01*
X229258Y437917D01*
X229508Y437708D01*
G01X231067Y435500D02*
Y438000D01*
X232108D01*
X232442Y437875D01*
X232650Y437708D01*
X232733Y437375D01*
X232650Y437042D01*
X232400Y436833D01*
X232108Y436708D01*
X231067D01*
G01X232108D02*
X232733Y435500D01*
G01X235000D02*
X235292Y435542D01*
X235625Y435667D01*
X235833Y435875D01*
X235917Y436167D01*
X235833Y436458D01*
X235583Y436708D01*
X235208Y436833D01*
X234792D01*
X234542Y436917D01*
X234333Y437125D01*
X234250Y437417D01*
X234375Y437708D01*
X234667Y437917D01*
X235000Y438000D01*
X235333Y437917D01*
X235625Y437708D01*
X235750Y437417D01*
X235667Y437125D01*
X235458Y436917D01*
X235208Y436833D01*
X234792D01*
X234417Y436708D01*
X234167Y436458D01*
X234083Y436167D01*
X234167Y435875D01*
X234375Y435667D01*
X234708Y435542D01*
X235000Y435500D01*
G01X237308Y437583D02*
X237558Y437833D01*
X237850Y437958D01*
X238183Y438000D01*
X238600Y437917D01*
X238892Y437708D01*
X238975Y437458D01*
X238933Y437208D01*
X238767Y437000D01*
X237933Y436583D01*
X237558Y436292D01*
X237308Y435875D01*
X237225Y435500D01*
X238975D01*
G01X241200D02*
Y438000D01*
X240700Y437500D01*
G01Y435500D02*
X241700D01*
G01X227925Y447833D02*
X228258Y447625D01*
X228633Y447500D01*
X228967D01*
X229300Y447625D01*
X229550Y447833D01*
X229675Y448125D01*
X229592Y448417D01*
X229383Y448667D01*
X229008Y448833D01*
X228508Y448917D01*
X228217Y449083D01*
X228092Y449375D01*
X228175Y449667D01*
X228383Y449875D01*
X228675Y450000D01*
X228967D01*
X229258Y449917D01*
X229508Y449708D01*
G01X231067Y447500D02*
Y450000D01*
X232108D01*
X232442Y449875D01*
X232650Y449708D01*
X232733Y449375D01*
X232650Y449042D01*
X232400Y448833D01*
X232108Y448708D01*
X231067D01*
G01X232108D02*
X232733Y447500D01*
G01X235000D02*
X235292Y447542D01*
X235625Y447667D01*
X235833Y447875D01*
X235917Y448167D01*
X235833Y448458D01*
X235583Y448708D01*
X235208Y448833D01*
X234792D01*
X234542Y448917D01*
X234333Y449125D01*
X234250Y449417D01*
X234375Y449708D01*
X234667Y449917D01*
X235000Y450000D01*
X235333Y449917D01*
X235625Y449708D01*
X235750Y449417D01*
X235667Y449125D01*
X235458Y448917D01*
X235208Y448833D01*
X234792D01*
X234417Y448708D01*
X234167Y448458D01*
X234083Y448167D01*
X234167Y447875D01*
X234375Y447667D01*
X234708Y447542D01*
X235000Y447500D01*
G01X237308Y449583D02*
X237558Y449833D01*
X237850Y449958D01*
X238183Y450000D01*
X238600Y449917D01*
X238892Y449708D01*
X238975Y449458D01*
X238933Y449208D01*
X238767Y449000D01*
X237933Y448583D01*
X237558Y448292D01*
X237308Y447875D01*
X237225Y447500D01*
X238975D01*
G01X240283Y448000D02*
X240533Y447708D01*
X240867Y447542D01*
X241242Y447500D01*
X241575Y447542D01*
X241908Y447750D01*
X242117Y448000D01*
X242158Y448250D01*
X242075Y448542D01*
X241783Y448750D01*
X241492Y448833D01*
X241117D01*
G01X241492D02*
X241742Y448958D01*
X241950Y449167D01*
X242033Y449417D01*
X241950Y449667D01*
X241742Y449875D01*
X241367Y450000D01*
X240992Y449958D01*
X240617Y449792D01*
G01X227925Y439833D02*
X228258Y439625D01*
X228633Y439500D01*
X228967D01*
X229300Y439625D01*
X229550Y439833D01*
X229675Y440125D01*
X229592Y440417D01*
X229383Y440667D01*
X229008Y440833D01*
X228508Y440917D01*
X228217Y441083D01*
X228092Y441375D01*
X228175Y441667D01*
X228383Y441875D01*
X228675Y442000D01*
X228967D01*
X229258Y441917D01*
X229508Y441708D01*
G01X231067Y439500D02*
Y442000D01*
X232108D01*
X232442Y441875D01*
X232650Y441708D01*
X232733Y441375D01*
X232650Y441042D01*
X232400Y440833D01*
X232108Y440708D01*
X231067D01*
G01X232108D02*
X232733Y439500D01*
G01X235000D02*
X235292Y439542D01*
X235625Y439667D01*
X235833Y439875D01*
X235917Y440167D01*
X235833Y440458D01*
X235583Y440708D01*
X235208Y440833D01*
X234792D01*
X234542Y440917D01*
X234333Y441125D01*
X234250Y441417D01*
X234375Y441708D01*
X234667Y441917D01*
X235000Y442000D01*
X235333Y441917D01*
X235625Y441708D01*
X235750Y441417D01*
X235667Y441125D01*
X235458Y440917D01*
X235208Y440833D01*
X234792D01*
X234417Y440708D01*
X234167Y440458D01*
X234083Y440167D01*
X234167Y439875D01*
X234375Y439667D01*
X234708Y439542D01*
X235000Y439500D01*
G01X237308Y441583D02*
X237558Y441833D01*
X237850Y441958D01*
X238183Y442000D01*
X238600Y441917D01*
X238892Y441708D01*
X238975Y441458D01*
X238933Y441208D01*
X238767Y441000D01*
X237933Y440583D01*
X237558Y440292D01*
X237308Y439875D01*
X237225Y439500D01*
X238975D01*
G01X241700D02*
Y442000D01*
X240158Y440208D01*
X242242D01*
G01X227925Y443833D02*
X228258Y443625D01*
X228633Y443500D01*
X228967D01*
X229300Y443625D01*
X229550Y443833D01*
X229675Y444125D01*
X229592Y444417D01*
X229383Y444667D01*
X229008Y444833D01*
X228508Y444917D01*
X228217Y445083D01*
X228092Y445375D01*
X228175Y445667D01*
X228383Y445875D01*
X228675Y446000D01*
X228967D01*
X229258Y445917D01*
X229508Y445708D01*
G01X231067Y443500D02*
Y446000D01*
X232108D01*
X232442Y445875D01*
X232650Y445708D01*
X232733Y445375D01*
X232650Y445042D01*
X232400Y444833D01*
X232108Y444708D01*
X231067D01*
G01X232108D02*
X232733Y443500D01*
G01X235000D02*
X235292Y443542D01*
X235625Y443667D01*
X235833Y443875D01*
X235917Y444167D01*
X235833Y444458D01*
X235583Y444708D01*
X235208Y444833D01*
X234792D01*
X234542Y444917D01*
X234333Y445125D01*
X234250Y445417D01*
X234375Y445708D01*
X234667Y445917D01*
X235000Y446000D01*
X235333Y445917D01*
X235625Y445708D01*
X235750Y445417D01*
X235667Y445125D01*
X235458Y444917D01*
X235208Y444833D01*
X234792D01*
X234417Y444708D01*
X234167Y444458D01*
X234083Y444167D01*
X234167Y443875D01*
X234375Y443667D01*
X234708Y443542D01*
X235000Y443500D01*
G01X237308Y445583D02*
X237558Y445833D01*
X237850Y445958D01*
X238183Y446000D01*
X238600Y445917D01*
X238892Y445708D01*
X238975Y445458D01*
X238933Y445208D01*
X238767Y445000D01*
X237933Y444583D01*
X237558Y444292D01*
X237308Y443875D01*
X237225Y443500D01*
X238975D01*
G01X240408Y444542D02*
X240700Y444833D01*
X240950Y445000D01*
X241283Y445083D01*
X241575Y445000D01*
X241783Y444833D01*
X241950Y444583D01*
X241992Y444292D01*
X241950Y444042D01*
X241783Y443792D01*
X241533Y443583D01*
X241242Y443500D01*
X240908Y443583D01*
X240617Y443833D01*
X240450Y444208D01*
X240408Y444625D01*
X240492Y445167D01*
X240617Y445458D01*
X240825Y445750D01*
X241117Y445958D01*
X241408Y446000D01*
X241700Y445917D01*
X241908Y445708D01*
G01X226823Y497283D02*
X294223D01*
G01X226823Y553883D02*
Y497283D01*
G01X294223Y553883D02*
X226823D01*
G01X216355Y562000D02*
Y558000D01*
X223755D01*
G01X216355Y566500D02*
Y562500D01*
X223755D01*
G01X218167Y688425D02*
X218375Y688758D01*
X218500Y689133D01*
Y689467D01*
X218375Y689800D01*
X218167Y690050D01*
X217875Y690175D01*
X217583Y690092D01*
X217333Y689883D01*
X217167Y689508D01*
X217083Y689008D01*
X216917Y688717D01*
X216625Y688592D01*
X216333Y688675D01*
X216125Y688883D01*
X216000Y689175D01*
Y689467D01*
X216083Y689758D01*
X216292Y690008D01*
G01X218500Y691567D02*
X216000D01*
Y692608D01*
X216125Y692942D01*
X216292Y693150D01*
X216625Y693233D01*
X216958Y693150D01*
X217167Y692900D01*
X217292Y692608D01*
Y691567D01*
G01Y692608D02*
X218500Y693233D01*
G01Y695500D02*
X218458Y695792D01*
X218333Y696125D01*
X218125Y696333D01*
X217833Y696417D01*
X217542Y696333D01*
X217292Y696083D01*
X217167Y695708D01*
Y695292D01*
X217083Y695042D01*
X216875Y694833D01*
X216583Y694750D01*
X216292Y694875D01*
X216083Y695167D01*
X216000Y695500D01*
X216083Y695833D01*
X216292Y696125D01*
X216583Y696250D01*
X216875Y696167D01*
X217083Y695958D01*
X217167Y695708D01*
Y695292D01*
X217292Y694917D01*
X217542Y694667D01*
X217833Y694583D01*
X218125Y694667D01*
X218333Y694875D01*
X218458Y695208D01*
X218500Y695500D01*
G01Y698600D02*
X216000D01*
X216500Y698100D01*
G01X218500D02*
Y699100D01*
G01Y701700D02*
X216000D01*
X216500Y701200D01*
G01X218500D02*
Y702200D01*
G01X222667Y688425D02*
X222875Y688758D01*
X223000Y689133D01*
Y689467D01*
X222875Y689800D01*
X222667Y690050D01*
X222375Y690175D01*
X222083Y690092D01*
X221833Y689883D01*
X221667Y689508D01*
X221583Y689008D01*
X221417Y688717D01*
X221125Y688592D01*
X220833Y688675D01*
X220625Y688883D01*
X220500Y689175D01*
Y689467D01*
X220583Y689758D01*
X220792Y690008D01*
G01X223000Y691567D02*
X220500D01*
Y692608D01*
X220625Y692942D01*
X220792Y693150D01*
X221125Y693233D01*
X221458Y693150D01*
X221667Y692900D01*
X221792Y692608D01*
Y691567D01*
G01Y692608D02*
X223000Y693233D01*
G01Y695500D02*
X222958Y695792D01*
X222833Y696125D01*
X222625Y696333D01*
X222333Y696417D01*
X222042Y696333D01*
X221792Y696083D01*
X221667Y695708D01*
Y695292D01*
X221583Y695042D01*
X221375Y694833D01*
X221083Y694750D01*
X220792Y694875D01*
X220583Y695167D01*
X220500Y695500D01*
X220583Y695833D01*
X220792Y696125D01*
X221083Y696250D01*
X221375Y696167D01*
X221583Y695958D01*
X221667Y695708D01*
Y695292D01*
X221792Y694917D01*
X222042Y694667D01*
X222333Y694583D01*
X222625Y694667D01*
X222833Y694875D01*
X222958Y695208D01*
X223000Y695500D01*
G01Y698600D02*
X220500D01*
X221000Y698100D01*
G01X223000D02*
Y699100D01*
G01X220917Y700908D02*
X220667Y701158D01*
X220542Y701450D01*
X220500Y701783D01*
X220583Y702200D01*
X220792Y702492D01*
X221042Y702575D01*
X221292Y702533D01*
X221500Y702367D01*
X221917Y701533D01*
X222208Y701158D01*
X222625Y700908D01*
X223000Y700825D01*
Y702575D01*
G01X219000Y705300D02*
X223000D01*
Y712700D01*
G01X217018Y715909D02*
Y717909D01*
X233218D01*
Y715909D01*
G01X217708Y785217D02*
X217583Y784967D01*
X217500Y784675D01*
Y784342D01*
X217625Y783967D01*
X217833Y783675D01*
X218083Y783467D01*
X218500Y783300D01*
X218875Y783258D01*
X219250Y783342D01*
X219500Y783467D01*
X219750Y783717D01*
X219917Y784008D01*
X220000Y784300D01*
Y784592D01*
X219917Y784883D01*
X219792Y785133D01*
X219625Y785342D01*
G01X220000Y787317D02*
X219458Y787400D01*
X219000Y787525D01*
X218583Y787692D01*
X218125Y787900D01*
X217500Y788233D01*
Y786567D01*
G01X217917Y789708D02*
X217667Y789958D01*
X217542Y790250D01*
X217500Y790583D01*
X217583Y791000D01*
X217792Y791292D01*
X218042Y791375D01*
X218292Y791333D01*
X218500Y791167D01*
X218917Y790333D01*
X219208Y789958D01*
X219625Y789708D01*
X220000Y789625D01*
Y791375D01*
G01Y793517D02*
X219458Y793600D01*
X219000Y793725D01*
X218583Y793892D01*
X218125Y794100D01*
X217500Y794433D01*
Y792767D01*
G01X220000Y797200D02*
X217500D01*
X219292Y795658D01*
Y797742D01*
G01X216017Y801000D02*
Y803500D01*
X217058D01*
X217392Y803375D01*
X217600Y803208D01*
X217683Y802875D01*
X217600Y802542D01*
X217350Y802333D01*
X217058Y802208D01*
X216017D01*
G01X217058D02*
X217683Y801000D01*
G01X219158Y802042D02*
X219450Y802333D01*
X219700Y802500D01*
X220033Y802583D01*
X220325Y802500D01*
X220533Y802333D01*
X220700Y802083D01*
X220742Y801792D01*
X220700Y801542D01*
X220533Y801292D01*
X220283Y801083D01*
X219992Y801000D01*
X219658Y801083D01*
X219367Y801333D01*
X219200Y801708D01*
X219158Y802125D01*
X219242Y802667D01*
X219367Y802958D01*
X219575Y803250D01*
X219867Y803458D01*
X220158Y803500D01*
X220450Y803417D01*
X220658Y803208D01*
G01X222342Y801292D02*
X222633Y801083D01*
X222967Y801000D01*
X223300Y801083D01*
X223592Y801333D01*
X223800Y801708D01*
X223883Y802083D01*
Y802542D01*
X223800Y802917D01*
X223592Y803250D01*
X223342Y803417D01*
X223050Y803500D01*
X222717Y803417D01*
X222467Y803250D01*
X222300Y803000D01*
X222217Y802667D01*
X222300Y802375D01*
X222508Y802083D01*
X222758Y801917D01*
X223050Y801875D01*
X223383Y801958D01*
X223633Y802167D01*
X223883Y802542D01*
G01X226150Y803500D02*
X225817Y803417D01*
X225567Y803208D01*
X225400Y802958D01*
X225275Y802625D01*
X225233Y802250D01*
X225275Y801875D01*
X225400Y801542D01*
X225567Y801292D01*
X225817Y801083D01*
X226150Y801000D01*
X226483Y801083D01*
X226733Y801292D01*
X226900Y801542D01*
X227025Y801875D01*
X227067Y802250D01*
X227025Y802625D01*
X226900Y802958D01*
X226733Y803208D01*
X226483Y803417D01*
X226150Y803500D01*
G01X226000Y806917D02*
X223500D01*
Y807917D01*
X223625Y808250D01*
X223917Y808500D01*
X224250Y808583D01*
X224583Y808500D01*
X224833Y808292D01*
X224958Y807917D01*
Y806917D01*
G01X226000Y810017D02*
X223500D01*
Y811058D01*
X223625Y811392D01*
X223792Y811600D01*
X224125Y811683D01*
X224458Y811600D01*
X224667Y811350D01*
X224792Y811058D01*
Y810017D01*
G01Y811058D02*
X226000Y811683D01*
G01X225708Y813242D02*
X225917Y813533D01*
X226000Y813867D01*
X225917Y814200D01*
X225667Y814492D01*
X225292Y814700D01*
X224917Y814783D01*
X224458D01*
X224083Y814700D01*
X223750Y814492D01*
X223583Y814242D01*
X223500Y813950D01*
X223583Y813617D01*
X223750Y813367D01*
X224000Y813200D01*
X224333Y813117D01*
X224625Y813200D01*
X224917Y813408D01*
X225083Y813658D01*
X225125Y813950D01*
X225042Y814283D01*
X224833Y814533D01*
X224458Y814783D01*
G01X223500Y817050D02*
X223583Y816717D01*
X223792Y816467D01*
X224042Y816300D01*
X224375Y816175D01*
X224750Y816133D01*
X225125Y816175D01*
X225458Y816300D01*
X225708Y816467D01*
X225917Y816717D01*
X226000Y817050D01*
X225917Y817383D01*
X225708Y817633D01*
X225458Y817800D01*
X225125Y817925D01*
X224750Y817967D01*
X224375Y817925D01*
X224042Y817800D01*
X223792Y817633D01*
X223583Y817383D01*
X223500Y817050D01*
G01Y820150D02*
X223583Y819817D01*
X223792Y819567D01*
X224042Y819400D01*
X224375Y819275D01*
X224750Y819233D01*
X225125Y819275D01*
X225458Y819400D01*
X225708Y819567D01*
X225917Y819817D01*
X226000Y820150D01*
X225917Y820483D01*
X225708Y820733D01*
X225458Y820900D01*
X225125Y821025D01*
X224750Y821067D01*
X224375Y821025D01*
X224042Y820900D01*
X223792Y820733D01*
X223583Y820483D01*
X223500Y820150D01*
G01X224958Y822458D02*
X224667Y822750D01*
X224500Y823000D01*
X224417Y823333D01*
X224500Y823625D01*
X224667Y823833D01*
X224917Y824000D01*
X225208Y824042D01*
X225458Y824000D01*
X225708Y823833D01*
X225917Y823583D01*
X226000Y823292D01*
X225917Y822958D01*
X225667Y822667D01*
X225292Y822500D01*
X224875Y822458D01*
X224333Y822542D01*
X224042Y822667D01*
X223750Y822875D01*
X223542Y823167D01*
X223500Y823458D01*
X223583Y823750D01*
X223792Y823958D01*
G01X230000Y806917D02*
X227500D01*
Y807917D01*
X227625Y808250D01*
X227917Y808500D01*
X228250Y808583D01*
X228583Y808500D01*
X228833Y808292D01*
X228958Y807917D01*
Y806917D01*
G01X230000Y810017D02*
X227500D01*
Y811058D01*
X227625Y811392D01*
X227792Y811600D01*
X228125Y811683D01*
X228458Y811600D01*
X228667Y811350D01*
X228792Y811058D01*
Y810017D01*
G01Y811058D02*
X230000Y811683D01*
G01X229708Y813242D02*
X229917Y813533D01*
X230000Y813867D01*
X229917Y814200D01*
X229667Y814492D01*
X229292Y814700D01*
X228917Y814783D01*
X228458D01*
X228083Y814700D01*
X227750Y814492D01*
X227583Y814242D01*
X227500Y813950D01*
X227583Y813617D01*
X227750Y813367D01*
X228000Y813200D01*
X228333Y813117D01*
X228625Y813200D01*
X228917Y813408D01*
X229083Y813658D01*
X229125Y813950D01*
X229042Y814283D01*
X228833Y814533D01*
X228458Y814783D01*
G01X227500Y817050D02*
X227583Y816717D01*
X227792Y816467D01*
X228042Y816300D01*
X228375Y816175D01*
X228750Y816133D01*
X229125Y816175D01*
X229458Y816300D01*
X229708Y816467D01*
X229917Y816717D01*
X230000Y817050D01*
X229917Y817383D01*
X229708Y817633D01*
X229458Y817800D01*
X229125Y817925D01*
X228750Y817967D01*
X228375Y817925D01*
X228042Y817800D01*
X227792Y817633D01*
X227583Y817383D01*
X227500Y817050D01*
G01Y820150D02*
X227583Y819817D01*
X227792Y819567D01*
X228042Y819400D01*
X228375Y819275D01*
X228750Y819233D01*
X229125Y819275D01*
X229458Y819400D01*
X229708Y819567D01*
X229917Y819817D01*
X230000Y820150D01*
X229917Y820483D01*
X229708Y820733D01*
X229458Y820900D01*
X229125Y821025D01*
X228750Y821067D01*
X228375Y821025D01*
X228042Y820900D01*
X227792Y820733D01*
X227583Y820483D01*
X227500Y820150D01*
G01X230000Y823167D02*
X229458Y823250D01*
X229000Y823375D01*
X228583Y823542D01*
X228125Y823750D01*
X227500Y824083D01*
Y822417D01*
G01X234000Y834700D02*
X230000D01*
Y827300D01*
G01Y834700D02*
X226000D01*
Y827300D01*
G01X222000Y834700D02*
X218000D01*
Y827300D01*
G01X226000Y834700D02*
X222000D01*
Y827300D01*
G01X217080Y842550D02*
Y845550D01*
G01X226920Y843550D02*
Y845550D01*
G01X230850Y844650D02*
X235850D01*
Y849650D01*
G01X219048Y874450D02*
Y871450D01*
G01X228888Y873450D02*
Y871450D01*
G01X230850Y872350D02*
X235850D01*
Y867350D01*
G01X227000Y892700D02*
X223000D01*
Y885300D01*
G01X231500Y892700D02*
X227500D01*
Y885300D01*
G01X221000Y918250D02*
X234000D01*
Y902750D01*
X221000D01*
Y918250D01*
G01X227500Y922967D02*
X225000D01*
Y924008D01*
X225125Y924342D01*
X225292Y924550D01*
X225625Y924633D01*
X225958Y924550D01*
X226167Y924300D01*
X226292Y924008D01*
Y922967D01*
G01Y924008D02*
X227500Y924633D01*
G01X227208Y926192D02*
X227417Y926483D01*
X227500Y926817D01*
X227417Y927150D01*
X227167Y927442D01*
X226792Y927650D01*
X226417Y927733D01*
X225958D01*
X225583Y927650D01*
X225250Y927442D01*
X225083Y927192D01*
X225000Y926900D01*
X225083Y926567D01*
X225250Y926317D01*
X225500Y926150D01*
X225833Y926067D01*
X226125Y926150D01*
X226417Y926358D01*
X226583Y926608D01*
X226625Y926900D01*
X226542Y927233D01*
X226333Y927483D01*
X225958Y927733D01*
G01X225000Y930000D02*
X225083Y929667D01*
X225292Y929417D01*
X225542Y929250D01*
X225875Y929125D01*
X226250Y929083D01*
X226625Y929125D01*
X226958Y929250D01*
X227208Y929417D01*
X227417Y929667D01*
X227500Y930000D01*
X227417Y930333D01*
X227208Y930583D01*
X226958Y930750D01*
X226625Y930875D01*
X226250Y930917D01*
X225875Y930875D01*
X225542Y930750D01*
X225292Y930583D01*
X225083Y930333D01*
X225000Y930000D01*
G01X225417Y932308D02*
X225167Y932558D01*
X225042Y932850D01*
X225000Y933183D01*
X225083Y933600D01*
X225292Y933892D01*
X225542Y933975D01*
X225792Y933933D01*
X226000Y933767D01*
X226417Y932933D01*
X226708Y932558D01*
X227125Y932308D01*
X227500Y932225D01*
Y933975D01*
G01X225000Y936200D02*
X225083Y935867D01*
X225292Y935617D01*
X225542Y935450D01*
X225875Y935325D01*
X226250Y935283D01*
X226625Y935325D01*
X226958Y935450D01*
X227208Y935617D01*
X227417Y935867D01*
X227500Y936200D01*
X227417Y936533D01*
X227208Y936783D01*
X226958Y936950D01*
X226625Y937075D01*
X226250Y937117D01*
X225875Y937075D01*
X225542Y936950D01*
X225292Y936783D01*
X225083Y936533D01*
X225000Y936200D01*
G01X247925Y187333D02*
X248258Y187125D01*
X248633Y187000D01*
X248967D01*
X249300Y187125D01*
X249550Y187333D01*
X249675Y187625D01*
X249592Y187917D01*
X249383Y188167D01*
X249008Y188333D01*
X248508Y188417D01*
X248217Y188583D01*
X248092Y188875D01*
X248175Y189167D01*
X248383Y189375D01*
X248675Y189500D01*
X248967D01*
X249258Y189417D01*
X249508Y189208D01*
G01X252817Y189292D02*
X252567Y189417D01*
X252275Y189500D01*
X251942D01*
X251567Y189375D01*
X251275Y189167D01*
X251067Y188917D01*
X250900Y188500D01*
X250858Y188125D01*
X250942Y187750D01*
X251067Y187500D01*
X251317Y187250D01*
X251608Y187083D01*
X251900Y187000D01*
X252192D01*
X252483Y187083D01*
X252733Y187208D01*
X252942Y187375D01*
G01X254292Y187292D02*
X254583Y187083D01*
X254917Y187000D01*
X255250Y187083D01*
X255542Y187333D01*
X255750Y187708D01*
X255833Y188083D01*
Y188542D01*
X255750Y188917D01*
X255542Y189250D01*
X255292Y189417D01*
X255000Y189500D01*
X254667Y189417D01*
X254417Y189250D01*
X254250Y189000D01*
X254167Y188667D01*
X254250Y188375D01*
X254458Y188083D01*
X254708Y187917D01*
X255000Y187875D01*
X255333Y187958D01*
X255583Y188167D01*
X255833Y188542D01*
G01X257183Y187500D02*
X257433Y187208D01*
X257767Y187042D01*
X258142Y187000D01*
X258475Y187042D01*
X258808Y187250D01*
X259017Y187500D01*
X259058Y187750D01*
X258975Y188042D01*
X258683Y188250D01*
X258392Y188333D01*
X258017D01*
G01X258392D02*
X258642Y188458D01*
X258850Y188667D01*
X258933Y188917D01*
X258850Y189167D01*
X258642Y189375D01*
X258267Y189500D01*
X257892Y189458D01*
X257517Y189292D01*
G01X260283Y187375D02*
X260533Y187167D01*
X260825Y187042D01*
X261200Y187000D01*
X261575Y187083D01*
X261867Y187250D01*
X262075Y187542D01*
X262117Y187875D01*
X262033Y188208D01*
X261825Y188417D01*
X261533Y188583D01*
X261242Y188625D01*
X260950Y188583D01*
X260575Y188417D01*
X260700Y189500D01*
X261825D01*
G01X247925Y179333D02*
X248258Y179125D01*
X248633Y179000D01*
X248967D01*
X249300Y179125D01*
X249550Y179333D01*
X249675Y179625D01*
X249592Y179917D01*
X249383Y180167D01*
X249008Y180333D01*
X248508Y180417D01*
X248217Y180583D01*
X248092Y180875D01*
X248175Y181167D01*
X248383Y181375D01*
X248675Y181500D01*
X248967D01*
X249258Y181417D01*
X249508Y181208D01*
G01X252817Y181292D02*
X252567Y181417D01*
X252275Y181500D01*
X251942D01*
X251567Y181375D01*
X251275Y181167D01*
X251067Y180917D01*
X250900Y180500D01*
X250858Y180125D01*
X250942Y179750D01*
X251067Y179500D01*
X251317Y179250D01*
X251608Y179083D01*
X251900Y179000D01*
X252192D01*
X252483Y179083D01*
X252733Y179208D01*
X252942Y179375D01*
G01X254292Y179292D02*
X254583Y179083D01*
X254917Y179000D01*
X255250Y179083D01*
X255542Y179333D01*
X255750Y179708D01*
X255833Y180083D01*
Y180542D01*
X255750Y180917D01*
X255542Y181250D01*
X255292Y181417D01*
X255000Y181500D01*
X254667Y181417D01*
X254417Y181250D01*
X254250Y181000D01*
X254167Y180667D01*
X254250Y180375D01*
X254458Y180083D01*
X254708Y179917D01*
X255000Y179875D01*
X255333Y179958D01*
X255583Y180167D01*
X255833Y180542D01*
G01X257183Y179500D02*
X257433Y179208D01*
X257767Y179042D01*
X258142Y179000D01*
X258475Y179042D01*
X258808Y179250D01*
X259017Y179500D01*
X259058Y179750D01*
X258975Y180042D01*
X258683Y180250D01*
X258392Y180333D01*
X258017D01*
G01X258392D02*
X258642Y180458D01*
X258850Y180667D01*
X258933Y180917D01*
X258850Y181167D01*
X258642Y181375D01*
X258267Y181500D01*
X257892Y181458D01*
X257517Y181292D01*
G01X260408Y180042D02*
X260700Y180333D01*
X260950Y180500D01*
X261283Y180583D01*
X261575Y180500D01*
X261783Y180333D01*
X261950Y180083D01*
X261992Y179792D01*
X261950Y179542D01*
X261783Y179292D01*
X261533Y179083D01*
X261242Y179000D01*
X260908Y179083D01*
X260617Y179333D01*
X260450Y179708D01*
X260408Y180125D01*
X260492Y180667D01*
X260617Y180958D01*
X260825Y181250D01*
X261117Y181458D01*
X261408Y181500D01*
X261700Y181417D01*
X261908Y181208D01*
G01X242700Y417000D02*
Y421000D01*
X235300D01*
G01X242700Y429000D02*
Y433000D01*
X235300D01*
G01Y425000D02*
Y421000D01*
X242700D01*
G01X235300Y429000D02*
Y425000D01*
X242700D01*
G01X245626Y438678D02*
Y441178D01*
X246626D01*
X246959Y441053D01*
X247209Y440761D01*
X247292Y440428D01*
X247209Y440095D01*
X247001Y439845D01*
X246626Y439720D01*
X245626D01*
G01X248726Y438678D02*
Y441178D01*
X249767D01*
X250101Y441053D01*
X250309Y440886D01*
X250392Y440553D01*
X250309Y440220D01*
X250059Y440011D01*
X249767Y439886D01*
X248726D01*
G01X249767D02*
X250392Y438678D01*
G01X252659D02*
Y441178D01*
X252159Y440678D01*
G01Y438678D02*
X253159D01*
G01X254967Y439720D02*
X255259Y440011D01*
X255509Y440178D01*
X255842Y440261D01*
X256134Y440178D01*
X256342Y440011D01*
X256509Y439761D01*
X256551Y439470D01*
X256509Y439220D01*
X256342Y438970D01*
X256092Y438761D01*
X255801Y438678D01*
X255467Y438761D01*
X255176Y439011D01*
X255009Y439386D01*
X254967Y439803D01*
X255051Y440345D01*
X255176Y440636D01*
X255384Y440928D01*
X255676Y441136D01*
X255967Y441178D01*
X256259Y441095D01*
X256467Y440886D01*
G01X258151Y438970D02*
X258442Y438761D01*
X258776Y438678D01*
X259109Y438761D01*
X259401Y439011D01*
X259609Y439386D01*
X259692Y439761D01*
Y440220D01*
X259609Y440595D01*
X259401Y440928D01*
X259151Y441095D01*
X258859Y441178D01*
X258526Y441095D01*
X258276Y440928D01*
X258109Y440678D01*
X258026Y440345D01*
X258109Y440053D01*
X258317Y439761D01*
X258567Y439595D01*
X258859Y439553D01*
X259192Y439636D01*
X259442Y439845D01*
X259692Y440220D01*
G01X245626Y443178D02*
Y445678D01*
X246626D01*
X246959Y445553D01*
X247209Y445261D01*
X247292Y444928D01*
X247209Y444595D01*
X247001Y444345D01*
X246626Y444220D01*
X245626D01*
G01X248726Y443178D02*
Y445678D01*
X249767D01*
X250101Y445553D01*
X250309Y445386D01*
X250392Y445053D01*
X250309Y444720D01*
X250059Y444511D01*
X249767Y444386D01*
X248726D01*
G01X249767D02*
X250392Y443178D01*
G01X252659D02*
Y445678D01*
X252159Y445178D01*
G01Y443178D02*
X253159D01*
G01X254967Y444220D02*
X255259Y444511D01*
X255509Y444678D01*
X255842Y444761D01*
X256134Y444678D01*
X256342Y444511D01*
X256509Y444261D01*
X256551Y443970D01*
X256509Y443720D01*
X256342Y443470D01*
X256092Y443261D01*
X255801Y443178D01*
X255467Y443261D01*
X255176Y443511D01*
X255009Y443886D01*
X254967Y444303D01*
X255051Y444845D01*
X255176Y445136D01*
X255384Y445428D01*
X255676Y445636D01*
X255967Y445678D01*
X256259Y445595D01*
X256467Y445386D01*
G01X258067Y444220D02*
X258359Y444511D01*
X258609Y444678D01*
X258942Y444761D01*
X259234Y444678D01*
X259442Y444511D01*
X259609Y444261D01*
X259651Y443970D01*
X259609Y443720D01*
X259442Y443470D01*
X259192Y443261D01*
X258901Y443178D01*
X258567Y443261D01*
X258276Y443511D01*
X258109Y443886D01*
X258067Y444303D01*
X258151Y444845D01*
X258276Y445136D01*
X258484Y445428D01*
X258776Y445636D01*
X259067Y445678D01*
X259359Y445595D01*
X259567Y445386D01*
G01X245626Y447678D02*
Y450178D01*
X246626D01*
X246959Y450053D01*
X247209Y449761D01*
X247292Y449428D01*
X247209Y449095D01*
X247001Y448845D01*
X246626Y448720D01*
X245626D01*
G01X248726Y447678D02*
Y450178D01*
X249767D01*
X250101Y450053D01*
X250309Y449886D01*
X250392Y449553D01*
X250309Y449220D01*
X250059Y449011D01*
X249767Y448886D01*
X248726D01*
G01X249767D02*
X250392Y447678D01*
G01X252659D02*
Y450178D01*
X252159Y449678D01*
G01Y447678D02*
X253159D01*
G01X254967Y448720D02*
X255259Y449011D01*
X255509Y449178D01*
X255842Y449261D01*
X256134Y449178D01*
X256342Y449011D01*
X256509Y448761D01*
X256551Y448470D01*
X256509Y448220D01*
X256342Y447970D01*
X256092Y447761D01*
X255801Y447678D01*
X255467Y447761D01*
X255176Y448011D01*
X255009Y448386D01*
X254967Y448803D01*
X255051Y449345D01*
X255176Y449636D01*
X255384Y449928D01*
X255676Y450136D01*
X255967Y450178D01*
X256259Y450095D01*
X256467Y449886D01*
G01X258776Y447678D02*
X258859Y448220D01*
X258984Y448678D01*
X259151Y449095D01*
X259359Y449553D01*
X259692Y450178D01*
X258026D01*
G01X236623Y571383D02*
X232623D01*
Y563983D01*
G01X242430Y564833D02*
X242763Y564625D01*
X243138Y564500D01*
X243472D01*
X243805Y564625D01*
X244055Y564833D01*
X244180Y565125D01*
X244097Y565417D01*
X243888Y565667D01*
X243513Y565833D01*
X243013Y565917D01*
X242722Y566083D01*
X242597Y566375D01*
X242680Y566667D01*
X242888Y566875D01*
X243180Y567000D01*
X243472D01*
X243763Y566917D01*
X244013Y566708D01*
G01X247322Y566792D02*
X247072Y566917D01*
X246780Y567000D01*
X246447D01*
X246072Y566875D01*
X245780Y566667D01*
X245572Y566417D01*
X245405Y566000D01*
X245363Y565625D01*
X245447Y565250D01*
X245572Y565000D01*
X245822Y564750D01*
X246113Y564583D01*
X246405Y564500D01*
X246697D01*
X246988Y564583D01*
X247238Y564708D01*
X247447Y564875D01*
G01X249505Y564500D02*
Y567000D01*
X249005Y566500D01*
G01Y564500D02*
X250005D01*
G01X251813Y566583D02*
X252063Y566833D01*
X252355Y566958D01*
X252688Y567000D01*
X253105Y566917D01*
X253397Y566708D01*
X253480Y566458D01*
X253438Y566208D01*
X253272Y566000D01*
X252438Y565583D01*
X252063Y565292D01*
X251813Y564875D01*
X251730Y564500D01*
X253480D01*
G01X255705D02*
X255997Y564542D01*
X256330Y564667D01*
X256538Y564875D01*
X256622Y565167D01*
X256538Y565458D01*
X256288Y565708D01*
X255913Y565833D01*
X255497D01*
X255247Y565917D01*
X255038Y566125D01*
X254955Y566417D01*
X255080Y566708D01*
X255372Y566917D01*
X255705Y567000D01*
X256038Y566917D01*
X256330Y566708D01*
X256455Y566417D01*
X256372Y566125D01*
X256163Y565917D01*
X255913Y565833D01*
X255497D01*
X255122Y565708D01*
X254872Y565458D01*
X254788Y565167D01*
X254872Y564875D01*
X255080Y564667D01*
X255413Y564542D01*
X255705Y564500D01*
G01X257888Y564875D02*
X258138Y564667D01*
X258430Y564542D01*
X258805Y564500D01*
X259180Y564583D01*
X259472Y564750D01*
X259680Y565042D01*
X259722Y565375D01*
X259638Y565708D01*
X259430Y565917D01*
X259138Y566083D01*
X258847Y566125D01*
X258555Y566083D01*
X258180Y565917D01*
X258305Y567000D01*
X259430D01*
G01X242480Y570333D02*
X242813Y570125D01*
X243188Y570000D01*
X243522D01*
X243855Y570125D01*
X244105Y570333D01*
X244230Y570625D01*
X244147Y570917D01*
X243938Y571167D01*
X243563Y571333D01*
X243063Y571417D01*
X242772Y571583D01*
X242647Y571875D01*
X242730Y572167D01*
X242938Y572375D01*
X243230Y572500D01*
X243522D01*
X243813Y572417D01*
X244063Y572208D01*
G01X245622Y570000D02*
Y572500D01*
X246663D01*
X246997Y572375D01*
X247205Y572208D01*
X247288Y571875D01*
X247205Y571542D01*
X246955Y571333D01*
X246663Y571208D01*
X245622D01*
G01X246663D02*
X247288Y570000D01*
G01X249472D02*
X249555Y570542D01*
X249680Y571000D01*
X249847Y571417D01*
X250055Y571875D01*
X250388Y572500D01*
X248722D01*
G01X252655Y570000D02*
X252947Y570042D01*
X253280Y570167D01*
X253488Y570375D01*
X253572Y570667D01*
X253488Y570958D01*
X253238Y571208D01*
X252863Y571333D01*
X252447D01*
X252197Y571417D01*
X251988Y571625D01*
X251905Y571917D01*
X252030Y572208D01*
X252322Y572417D01*
X252655Y572500D01*
X252988Y572417D01*
X253280Y572208D01*
X253405Y571917D01*
X253322Y571625D01*
X253113Y571417D01*
X252863Y571333D01*
X252447D01*
X252072Y571208D01*
X251822Y570958D01*
X251738Y570667D01*
X251822Y570375D01*
X252030Y570167D01*
X252363Y570042D01*
X252655Y570000D01*
G01X254838Y570375D02*
X255088Y570167D01*
X255380Y570042D01*
X255755Y570000D01*
X256130Y570083D01*
X256422Y570250D01*
X256630Y570542D01*
X256672Y570875D01*
X256588Y571208D01*
X256380Y571417D01*
X256088Y571583D01*
X255797Y571625D01*
X255505Y571583D01*
X255130Y571417D01*
X255255Y572500D01*
X256380D01*
G01X242500Y810017D02*
X240000D01*
Y811058D01*
X240125Y811392D01*
X240292Y811600D01*
X240625Y811683D01*
X240958Y811600D01*
X241167Y811350D01*
X241292Y811058D01*
Y810017D01*
G01Y811058D02*
X242500Y811683D01*
G01X241458Y813158D02*
X241167Y813450D01*
X241000Y813700D01*
X240917Y814033D01*
X241000Y814325D01*
X241167Y814533D01*
X241417Y814700D01*
X241708Y814742D01*
X241958Y814700D01*
X242208Y814533D01*
X242417Y814283D01*
X242500Y813992D01*
X242417Y813658D01*
X242167Y813367D01*
X241792Y813200D01*
X241375Y813158D01*
X240833Y813242D01*
X240542Y813367D01*
X240250Y813575D01*
X240042Y813867D01*
X240000Y814158D01*
X240083Y814450D01*
X240292Y814658D01*
G01X242500Y817050D02*
X242458Y817342D01*
X242333Y817675D01*
X242125Y817883D01*
X241833Y817967D01*
X241542Y817883D01*
X241292Y817633D01*
X241167Y817258D01*
Y816842D01*
X241083Y816592D01*
X240875Y816383D01*
X240583Y816300D01*
X240292Y816425D01*
X240083Y816717D01*
X240000Y817050D01*
X240083Y817383D01*
X240292Y817675D01*
X240583Y817800D01*
X240875Y817717D01*
X241083Y817508D01*
X241167Y817258D01*
Y816842D01*
X241292Y816467D01*
X241542Y816217D01*
X241833Y816133D01*
X242125Y816217D01*
X242333Y816425D01*
X242458Y816758D01*
X242500Y817050D01*
G01Y820150D02*
X242458Y820442D01*
X242333Y820775D01*
X242125Y820983D01*
X241833Y821067D01*
X241542Y820983D01*
X241292Y820733D01*
X241167Y820358D01*
Y819942D01*
X241083Y819692D01*
X240875Y819483D01*
X240583Y819400D01*
X240292Y819525D01*
X240083Y819817D01*
X240000Y820150D01*
X240083Y820483D01*
X240292Y820775D01*
X240583Y820900D01*
X240875Y820817D01*
X241083Y820608D01*
X241167Y820358D01*
Y819942D01*
X241292Y819567D01*
X241542Y819317D01*
X241833Y819233D01*
X242125Y819317D01*
X242333Y819525D01*
X242458Y819858D01*
X242500Y820150D01*
G01X238000Y806917D02*
X235500D01*
Y807917D01*
X235625Y808250D01*
X235917Y808500D01*
X236250Y808583D01*
X236583Y808500D01*
X236833Y808292D01*
X236958Y807917D01*
Y806917D01*
G01X238000Y810017D02*
X235500D01*
Y811058D01*
X235625Y811392D01*
X235792Y811600D01*
X236125Y811683D01*
X236458Y811600D01*
X236667Y811350D01*
X236792Y811058D01*
Y810017D01*
G01Y811058D02*
X238000Y811683D01*
G01X237708Y813242D02*
X237917Y813533D01*
X238000Y813867D01*
X237917Y814200D01*
X237667Y814492D01*
X237292Y814700D01*
X236917Y814783D01*
X236458D01*
X236083Y814700D01*
X235750Y814492D01*
X235583Y814242D01*
X235500Y813950D01*
X235583Y813617D01*
X235750Y813367D01*
X236000Y813200D01*
X236333Y813117D01*
X236625Y813200D01*
X236917Y813408D01*
X237083Y813658D01*
X237125Y813950D01*
X237042Y814283D01*
X236833Y814533D01*
X236458Y814783D01*
G01X235500Y817050D02*
X235583Y816717D01*
X235792Y816467D01*
X236042Y816300D01*
X236375Y816175D01*
X236750Y816133D01*
X237125Y816175D01*
X237458Y816300D01*
X237708Y816467D01*
X237917Y816717D01*
X238000Y817050D01*
X237917Y817383D01*
X237708Y817633D01*
X237458Y817800D01*
X237125Y817925D01*
X236750Y817967D01*
X236375Y817925D01*
X236042Y817800D01*
X235792Y817633D01*
X235583Y817383D01*
X235500Y817050D01*
G01Y820150D02*
X235583Y819817D01*
X235792Y819567D01*
X236042Y819400D01*
X236375Y819275D01*
X236750Y819233D01*
X237125Y819275D01*
X237458Y819400D01*
X237708Y819567D01*
X237917Y819817D01*
X238000Y820150D01*
X237917Y820483D01*
X237708Y820733D01*
X237458Y820900D01*
X237125Y821025D01*
X236750Y821067D01*
X236375Y821025D01*
X236042Y820900D01*
X235792Y820733D01*
X235583Y820483D01*
X235500Y820150D01*
G01X238000Y823750D02*
X235500D01*
X237292Y822208D01*
Y824292D01*
G01X234000Y806917D02*
X231500D01*
Y807917D01*
X231625Y808250D01*
X231917Y808500D01*
X232250Y808583D01*
X232583Y808500D01*
X232833Y808292D01*
X232958Y807917D01*
Y806917D01*
G01X234000Y810017D02*
X231500D01*
Y811058D01*
X231625Y811392D01*
X231792Y811600D01*
X232125Y811683D01*
X232458Y811600D01*
X232667Y811350D01*
X232792Y811058D01*
Y810017D01*
G01Y811058D02*
X234000Y811683D01*
G01X233708Y813242D02*
X233917Y813533D01*
X234000Y813867D01*
X233917Y814200D01*
X233667Y814492D01*
X233292Y814700D01*
X232917Y814783D01*
X232458D01*
X232083Y814700D01*
X231750Y814492D01*
X231583Y814242D01*
X231500Y813950D01*
X231583Y813617D01*
X231750Y813367D01*
X232000Y813200D01*
X232333Y813117D01*
X232625Y813200D01*
X232917Y813408D01*
X233083Y813658D01*
X233125Y813950D01*
X233042Y814283D01*
X232833Y814533D01*
X232458Y814783D01*
G01X231500Y817050D02*
X231583Y816717D01*
X231792Y816467D01*
X232042Y816300D01*
X232375Y816175D01*
X232750Y816133D01*
X233125Y816175D01*
X233458Y816300D01*
X233708Y816467D01*
X233917Y816717D01*
X234000Y817050D01*
X233917Y817383D01*
X233708Y817633D01*
X233458Y817800D01*
X233125Y817925D01*
X232750Y817967D01*
X232375Y817925D01*
X232042Y817800D01*
X231792Y817633D01*
X231583Y817383D01*
X231500Y817050D01*
G01Y820150D02*
X231583Y819817D01*
X231792Y819567D01*
X232042Y819400D01*
X232375Y819275D01*
X232750Y819233D01*
X233125Y819275D01*
X233458Y819400D01*
X233708Y819567D01*
X233917Y819817D01*
X234000Y820150D01*
X233917Y820483D01*
X233708Y820733D01*
X233458Y820900D01*
X233125Y821025D01*
X232750Y821067D01*
X232375Y821025D01*
X232042Y820900D01*
X231792Y820733D01*
X231583Y820483D01*
X231500Y820150D01*
G01X233625Y822333D02*
X233833Y822583D01*
X233958Y822875D01*
X234000Y823250D01*
X233917Y823625D01*
X233750Y823917D01*
X233458Y824125D01*
X233125Y824167D01*
X232792Y824083D01*
X232583Y823875D01*
X232417Y823583D01*
X232375Y823292D01*
X232417Y823000D01*
X232583Y822625D01*
X231500Y822750D01*
Y823875D01*
G01X234500Y827300D02*
X238500D01*
Y834700D01*
G01X244467Y829500D02*
Y832000D01*
X245508D01*
X245842Y831875D01*
X246050Y831708D01*
X246133Y831375D01*
X246050Y831042D01*
X245800Y830833D01*
X245508Y830708D01*
X244467D01*
G01X245508D02*
X246133Y829500D01*
G01X247608Y831583D02*
X247858Y831833D01*
X248150Y831958D01*
X248483Y832000D01*
X248900Y831917D01*
X249192Y831708D01*
X249275Y831458D01*
X249233Y831208D01*
X249067Y831000D01*
X248233Y830583D01*
X247858Y830292D01*
X247608Y829875D01*
X247525Y829500D01*
X249275D01*
G01X251500Y832000D02*
X251167Y831917D01*
X250917Y831708D01*
X250750Y831458D01*
X250625Y831125D01*
X250583Y830750D01*
X250625Y830375D01*
X250750Y830042D01*
X250917Y829792D01*
X251167Y829583D01*
X251500Y829500D01*
X251833Y829583D01*
X252083Y829792D01*
X252250Y830042D01*
X252375Y830375D01*
X252417Y830750D01*
X252375Y831125D01*
X252250Y831458D01*
X252083Y831708D01*
X251833Y831917D01*
X251500Y832000D01*
G01X253892Y829792D02*
X254183Y829583D01*
X254517Y829500D01*
X254850Y829583D01*
X255142Y829833D01*
X255350Y830208D01*
X255433Y830583D01*
Y831042D01*
X255350Y831417D01*
X255142Y831750D01*
X254892Y831917D01*
X254600Y832000D01*
X254267Y831917D01*
X254017Y831750D01*
X253850Y831500D01*
X253767Y831167D01*
X253850Y830875D01*
X254058Y830583D01*
X254308Y830417D01*
X254600Y830375D01*
X254933Y830458D01*
X255183Y830667D01*
X255433Y831042D01*
G01X256992Y829792D02*
X257283Y829583D01*
X257617Y829500D01*
X257950Y829583D01*
X258242Y829833D01*
X258450Y830208D01*
X258533Y830583D01*
Y831042D01*
X258450Y831417D01*
X258242Y831750D01*
X257992Y831917D01*
X257700Y832000D01*
X257367Y831917D01*
X257117Y831750D01*
X256950Y831500D01*
X256867Y831167D01*
X256950Y830875D01*
X257158Y830583D01*
X257408Y830417D01*
X257700Y830375D01*
X258033Y830458D01*
X258283Y830667D01*
X258533Y831042D01*
G01X248700Y833500D02*
Y837500D01*
X241300D01*
G01X237950Y857513D02*
X234950D01*
G01X241800Y857500D02*
Y853500D01*
X249200D01*
G01X241800Y861500D02*
Y857500D01*
X249200D01*
G01X241800Y849500D02*
Y845500D01*
X249200D01*
G01X242500Y875017D02*
X240000D01*
Y876017D01*
X240125Y876350D01*
X240417Y876600D01*
X240750Y876683D01*
X241083Y876600D01*
X241333Y876392D01*
X241458Y876017D01*
Y875017D01*
G01X242500Y878950D02*
X242458Y878617D01*
X242292Y878325D01*
X242042Y878075D01*
X241750Y877908D01*
X241417Y877825D01*
X241083D01*
X240750Y877908D01*
X240458Y878075D01*
X240208Y878325D01*
X240042Y878617D01*
X240000Y878950D01*
X240042Y879283D01*
X240208Y879575D01*
X240458Y879825D01*
X240750Y879992D01*
X241083Y880075D01*
X241417D01*
X241750Y879992D01*
X242042Y879825D01*
X242292Y879575D01*
X242458Y879283D01*
X242500Y878950D01*
G01X241833Y879283D02*
X242500Y879783D01*
G01X242000Y881133D02*
X242292Y881383D01*
X242458Y881717D01*
X242500Y882092D01*
X242458Y882425D01*
X242250Y882758D01*
X242000Y882967D01*
X241750Y883008D01*
X241458Y882925D01*
X241250Y882633D01*
X241167Y882342D01*
Y881967D01*
G01Y882342D02*
X241042Y882592D01*
X240833Y882800D01*
X240583Y882883D01*
X240333Y882800D01*
X240125Y882592D01*
X240000Y882217D01*
X240042Y881842D01*
X240208Y881467D01*
G01X242000Y884233D02*
X242292Y884483D01*
X242458Y884817D01*
X242500Y885192D01*
X242458Y885525D01*
X242250Y885858D01*
X242000Y886067D01*
X241750Y886108D01*
X241458Y886025D01*
X241250Y885733D01*
X241167Y885442D01*
Y885067D01*
G01Y885442D02*
X241042Y885692D01*
X240833Y885900D01*
X240583Y885983D01*
X240333Y885900D01*
X240125Y885692D01*
X240000Y885317D01*
X240042Y884942D01*
X240208Y884567D01*
G01X243867Y869500D02*
Y872000D01*
X244908D01*
X245242Y871875D01*
X245450Y871708D01*
X245533Y871375D01*
X245450Y871042D01*
X245200Y870833D01*
X244908Y870708D01*
X243867D01*
G01X244908D02*
X245533Y869500D01*
G01X247008Y871583D02*
X247258Y871833D01*
X247550Y871958D01*
X247883Y872000D01*
X248300Y871917D01*
X248592Y871708D01*
X248675Y871458D01*
X248633Y871208D01*
X248467Y871000D01*
X247633Y870583D01*
X247258Y870292D01*
X247008Y869875D01*
X246925Y869500D01*
X248675D01*
G01X250900D02*
Y872000D01*
X250400Y871500D01*
G01Y869500D02*
X251400D01*
G01X254000D02*
Y872000D01*
X253500Y871500D01*
G01Y869500D02*
X254500D01*
G01X257100Y872000D02*
X256767Y871917D01*
X256517Y871708D01*
X256350Y871458D01*
X256225Y871125D01*
X256183Y870750D01*
X256225Y870375D01*
X256350Y870042D01*
X256517Y869792D01*
X256767Y869583D01*
X257100Y869500D01*
X257433Y869583D01*
X257683Y869792D01*
X257850Y870042D01*
X257975Y870375D01*
X258017Y870750D01*
X257975Y871125D01*
X257850Y871458D01*
X257683Y871708D01*
X257433Y871917D01*
X257100Y872000D01*
G01X249200Y861500D02*
Y865500D01*
X241800D01*
G01X237900Y893000D02*
Y886100D01*
X233100D01*
Y893000D01*
X237900D01*
G01X240650Y889800D02*
X262350D01*
G01X240650Y919800D02*
Y889800D01*
G01X262350Y919800D02*
X240650D01*
G01X251667Y197025D02*
X251875Y197358D01*
X252000Y197733D01*
Y198067D01*
X251875Y198400D01*
X251667Y198650D01*
X251375Y198775D01*
X251083Y198692D01*
X250833Y198483D01*
X250667Y198108D01*
X250583Y197608D01*
X250417Y197317D01*
X250125Y197192D01*
X249833Y197275D01*
X249625Y197483D01*
X249500Y197775D01*
Y198067D01*
X249583Y198358D01*
X249792Y198608D01*
G01X249500Y200167D02*
X252000D01*
Y201833D01*
G01Y204017D02*
X251458Y204100D01*
X251000Y204225D01*
X250583Y204392D01*
X250125Y204600D01*
X249500Y204933D01*
Y203267D01*
G01X271000Y194300D02*
X264000D01*
Y207700D01*
X271000D01*
Y194300D01*
G01X257667Y192425D02*
X257875Y192758D01*
X258000Y193133D01*
Y193467D01*
X257875Y193800D01*
X257667Y194050D01*
X257375Y194175D01*
X257083Y194092D01*
X256833Y193883D01*
X256667Y193508D01*
X256583Y193008D01*
X256417Y192717D01*
X256125Y192592D01*
X255833Y192675D01*
X255625Y192883D01*
X255500Y193175D01*
Y193467D01*
X255583Y193758D01*
X255792Y194008D01*
G01X258000Y195567D02*
X255500D01*
Y196608D01*
X255625Y196942D01*
X255792Y197150D01*
X256125Y197233D01*
X256458Y197150D01*
X256667Y196900D01*
X256792Y196608D01*
Y195567D01*
G01Y196608D02*
X258000Y197233D01*
G01Y199417D02*
X257458Y199500D01*
X257000Y199625D01*
X256583Y199792D01*
X256125Y200000D01*
X255500Y200333D01*
Y198667D01*
G01X258000Y202600D02*
X255500D01*
X256000Y202100D01*
G01X258000D02*
Y203100D01*
G01Y206200D02*
X255500D01*
X257292Y204658D01*
Y206742D01*
G01X261304Y331833D02*
X261637Y331625D01*
X262012Y331500D01*
X262346D01*
X262679Y331625D01*
X262929Y331833D01*
X263054Y332125D01*
X262971Y332417D01*
X262762Y332667D01*
X262387Y332833D01*
X261887Y332917D01*
X261596Y333083D01*
X261471Y333375D01*
X261554Y333667D01*
X261762Y333875D01*
X262054Y334000D01*
X262346D01*
X262637Y333917D01*
X262887Y333708D01*
G01X266196Y333792D02*
X265946Y333917D01*
X265654Y334000D01*
X265321D01*
X264946Y333875D01*
X264654Y333667D01*
X264446Y333417D01*
X264279Y333000D01*
X264237Y332625D01*
X264321Y332250D01*
X264446Y332000D01*
X264696Y331750D01*
X264987Y331583D01*
X265279Y331500D01*
X265571D01*
X265862Y331583D01*
X266112Y331708D01*
X266321Y331875D01*
G01X268379Y331500D02*
Y334000D01*
X267879Y333500D01*
G01Y331500D02*
X268879D01*
G01X270687Y333583D02*
X270937Y333833D01*
X271229Y333958D01*
X271562Y334000D01*
X271979Y333917D01*
X272271Y333708D01*
X272354Y333458D01*
X272312Y333208D01*
X272146Y333000D01*
X271312Y332583D01*
X270937Y332292D01*
X270687Y331875D01*
X270604Y331500D01*
X272354D01*
G01X273787Y333583D02*
X274037Y333833D01*
X274329Y333958D01*
X274662Y334000D01*
X275079Y333917D01*
X275371Y333708D01*
X275454Y333458D01*
X275412Y333208D01*
X275246Y333000D01*
X274412Y332583D01*
X274037Y332292D01*
X273787Y331875D01*
X273704Y331500D01*
X275454D01*
G01X277596D02*
X277679Y332042D01*
X277804Y332500D01*
X277971Y332917D01*
X278179Y333375D01*
X278512Y334000D01*
X276846D01*
G01X261304Y327333D02*
X261637Y327125D01*
X262012Y327000D01*
X262346D01*
X262679Y327125D01*
X262929Y327333D01*
X263054Y327625D01*
X262971Y327917D01*
X262762Y328167D01*
X262387Y328333D01*
X261887Y328417D01*
X261596Y328583D01*
X261471Y328875D01*
X261554Y329167D01*
X261762Y329375D01*
X262054Y329500D01*
X262346D01*
X262637Y329417D01*
X262887Y329208D01*
G01X266196Y329292D02*
X265946Y329417D01*
X265654Y329500D01*
X265321D01*
X264946Y329375D01*
X264654Y329167D01*
X264446Y328917D01*
X264279Y328500D01*
X264237Y328125D01*
X264321Y327750D01*
X264446Y327500D01*
X264696Y327250D01*
X264987Y327083D01*
X265279Y327000D01*
X265571D01*
X265862Y327083D01*
X266112Y327208D01*
X266321Y327375D01*
G01X268379Y327000D02*
Y329500D01*
X267879Y329000D01*
G01Y327000D02*
X268879D01*
G01X270687Y329083D02*
X270937Y329333D01*
X271229Y329458D01*
X271562Y329500D01*
X271979Y329417D01*
X272271Y329208D01*
X272354Y328958D01*
X272312Y328708D01*
X272146Y328500D01*
X271312Y328083D01*
X270937Y327792D01*
X270687Y327375D01*
X270604Y327000D01*
X272354D01*
G01X273787Y329083D02*
X274037Y329333D01*
X274329Y329458D01*
X274662Y329500D01*
X275079Y329417D01*
X275371Y329208D01*
X275454Y328958D01*
X275412Y328708D01*
X275246Y328500D01*
X274412Y328083D01*
X274037Y327792D01*
X273787Y327375D01*
X273704Y327000D01*
X275454D01*
G01X276887Y328042D02*
X277179Y328333D01*
X277429Y328500D01*
X277762Y328583D01*
X278054Y328500D01*
X278262Y328333D01*
X278429Y328083D01*
X278471Y327792D01*
X278429Y327542D01*
X278262Y327292D01*
X278012Y327083D01*
X277721Y327000D01*
X277387Y327083D01*
X277096Y327333D01*
X276929Y327708D01*
X276887Y328125D01*
X276971Y328667D01*
X277096Y328958D01*
X277304Y329250D01*
X277596Y329458D01*
X277887Y329500D01*
X278179Y329417D01*
X278387Y329208D01*
G01X261304Y335833D02*
X261637Y335625D01*
X262012Y335500D01*
X262346D01*
X262679Y335625D01*
X262929Y335833D01*
X263054Y336125D01*
X262971Y336417D01*
X262762Y336667D01*
X262387Y336833D01*
X261887Y336917D01*
X261596Y337083D01*
X261471Y337375D01*
X261554Y337667D01*
X261762Y337875D01*
X262054Y338000D01*
X262346D01*
X262637Y337917D01*
X262887Y337708D01*
G01X266196Y337792D02*
X265946Y337917D01*
X265654Y338000D01*
X265321D01*
X264946Y337875D01*
X264654Y337667D01*
X264446Y337417D01*
X264279Y337000D01*
X264237Y336625D01*
X264321Y336250D01*
X264446Y336000D01*
X264696Y335750D01*
X264987Y335583D01*
X265279Y335500D01*
X265571D01*
X265862Y335583D01*
X266112Y335708D01*
X266321Y335875D01*
G01X268379Y335500D02*
Y338000D01*
X267879Y337500D01*
G01Y335500D02*
X268879D01*
G01X270687Y337583D02*
X270937Y337833D01*
X271229Y337958D01*
X271562Y338000D01*
X271979Y337917D01*
X272271Y337708D01*
X272354Y337458D01*
X272312Y337208D01*
X272146Y337000D01*
X271312Y336583D01*
X270937Y336292D01*
X270687Y335875D01*
X270604Y335500D01*
X272354D01*
G01X274579Y338000D02*
X274246Y337917D01*
X273996Y337708D01*
X273829Y337458D01*
X273704Y337125D01*
X273662Y336750D01*
X273704Y336375D01*
X273829Y336042D01*
X273996Y335792D01*
X274246Y335583D01*
X274579Y335500D01*
X274912Y335583D01*
X275162Y335792D01*
X275329Y336042D01*
X275454Y336375D01*
X275496Y336750D01*
X275454Y337125D01*
X275329Y337458D01*
X275162Y337708D01*
X274912Y337917D01*
X274579Y338000D01*
G01X278179Y335500D02*
Y338000D01*
X276637Y336208D01*
X278721D01*
G01X266359Y423678D02*
Y427678D01*
X258959D01*
G01X266359Y428178D02*
Y432178D01*
X258959D01*
G01X266359Y432678D02*
Y436678D01*
X258959D01*
G01X255530Y489333D02*
X255863Y489125D01*
X256238Y489000D01*
X256572D01*
X256905Y489125D01*
X257155Y489333D01*
X257280Y489625D01*
X257197Y489917D01*
X256988Y490167D01*
X256613Y490333D01*
X256113Y490417D01*
X255822Y490583D01*
X255697Y490875D01*
X255780Y491167D01*
X255988Y491375D01*
X256280Y491500D01*
X256572D01*
X256863Y491417D01*
X257113Y491208D01*
G01X258588Y491500D02*
Y489708D01*
X258755Y489333D01*
X259088Y489083D01*
X259505Y489000D01*
X259922Y489083D01*
X260255Y489333D01*
X260422Y489708D01*
Y491500D01*
G01X262522Y489000D02*
X262605Y489542D01*
X262730Y490000D01*
X262897Y490417D01*
X263105Y490875D01*
X263438Y491500D01*
X261772D01*
G01X264788Y489500D02*
X265038Y489208D01*
X265372Y489042D01*
X265747Y489000D01*
X266080Y489042D01*
X266413Y489250D01*
X266622Y489500D01*
X266663Y489750D01*
X266580Y490042D01*
X266288Y490250D01*
X265997Y490333D01*
X265622D01*
G01X265997D02*
X266247Y490458D01*
X266455Y490667D01*
X266538Y490917D01*
X266455Y491167D01*
X266247Y491375D01*
X265872Y491500D01*
X265497Y491458D01*
X265122Y491292D01*
G01X262223Y553883D02*
X260523Y552183D01*
G01D02*
X258823Y553883D01*
G01X251667Y688425D02*
X251875Y688758D01*
X252000Y689133D01*
Y689467D01*
X251875Y689800D01*
X251667Y690050D01*
X251375Y690175D01*
X251083Y690092D01*
X250833Y689883D01*
X250667Y689508D01*
X250583Y689008D01*
X250417Y688717D01*
X250125Y688592D01*
X249833Y688675D01*
X249625Y688883D01*
X249500Y689175D01*
Y689467D01*
X249583Y689758D01*
X249792Y690008D01*
G01X252000Y691567D02*
X249500D01*
Y692608D01*
X249625Y692942D01*
X249792Y693150D01*
X250125Y693233D01*
X250458Y693150D01*
X250667Y692900D01*
X250792Y692608D01*
Y691567D01*
G01Y692608D02*
X252000Y693233D01*
G01Y695500D02*
X251958Y695792D01*
X251833Y696125D01*
X251625Y696333D01*
X251333Y696417D01*
X251042Y696333D01*
X250792Y696083D01*
X250667Y695708D01*
Y695292D01*
X250583Y695042D01*
X250375Y694833D01*
X250083Y694750D01*
X249792Y694875D01*
X249583Y695167D01*
X249500Y695500D01*
X249583Y695833D01*
X249792Y696125D01*
X250083Y696250D01*
X250375Y696167D01*
X250583Y695958D01*
X250667Y695708D01*
Y695292D01*
X250792Y694917D01*
X251042Y694667D01*
X251333Y694583D01*
X251625Y694667D01*
X251833Y694875D01*
X251958Y695208D01*
X252000Y695500D01*
G01Y698600D02*
X249500D01*
X250000Y698100D01*
G01X252000D02*
Y699100D01*
G01X251500Y700783D02*
X251792Y701033D01*
X251958Y701367D01*
X252000Y701742D01*
X251958Y702075D01*
X251750Y702408D01*
X251500Y702617D01*
X251250Y702658D01*
X250958Y702575D01*
X250750Y702283D01*
X250667Y701992D01*
Y701617D01*
G01Y701992D02*
X250542Y702242D01*
X250333Y702450D01*
X250083Y702533D01*
X249833Y702450D01*
X249625Y702242D01*
X249500Y701867D01*
X249542Y701492D01*
X249708Y701117D01*
G01X248000Y705300D02*
X252000D01*
Y712700D01*
G01X260317Y842792D02*
X260067Y842917D01*
X259775Y843000D01*
X259442D01*
X259067Y842875D01*
X258775Y842667D01*
X258567Y842417D01*
X258400Y842000D01*
X258358Y841625D01*
X258442Y841250D01*
X258567Y841000D01*
X258817Y840750D01*
X259108Y840583D01*
X259400Y840500D01*
X259692D01*
X259983Y840583D01*
X260233Y840708D01*
X260442Y840875D01*
G01X261458Y840500D02*
X262500Y843000D01*
X263542Y840500D01*
G01X263167Y841375D02*
X261833D01*
G01X265600Y840500D02*
Y843000D01*
X265100Y842500D01*
G01Y840500D02*
X266100D01*
G01X262467Y858500D02*
Y861000D01*
X263508D01*
X263842Y860875D01*
X264050Y860708D01*
X264133Y860375D01*
X264050Y860042D01*
X263800Y859833D01*
X263508Y859708D01*
X262467D01*
G01X263508D02*
X264133Y858500D01*
G01X266400D02*
Y861000D01*
X265900Y860500D01*
G01Y858500D02*
X266900D01*
G01X268708Y860583D02*
X268958Y860833D01*
X269250Y860958D01*
X269583Y861000D01*
X270000Y860917D01*
X270292Y860708D01*
X270375Y860458D01*
X270333Y860208D01*
X270167Y860000D01*
X269333Y859583D01*
X268958Y859292D01*
X268708Y858875D01*
X268625Y858500D01*
X270375D01*
G01X271808Y860583D02*
X272058Y860833D01*
X272350Y860958D01*
X272683Y861000D01*
X273100Y860917D01*
X273392Y860708D01*
X273475Y860458D01*
X273433Y860208D01*
X273267Y860000D01*
X272433Y859583D01*
X272058Y859292D01*
X271808Y858875D01*
X271725Y858500D01*
X273475D01*
G01X274908Y859542D02*
X275200Y859833D01*
X275450Y860000D01*
X275783Y860083D01*
X276075Y860000D01*
X276283Y859833D01*
X276450Y859583D01*
X276492Y859292D01*
X276450Y859042D01*
X276283Y858792D01*
X276033Y858583D01*
X275742Y858500D01*
X275408Y858583D01*
X275117Y858833D01*
X274950Y859208D01*
X274908Y859625D01*
X274992Y860167D01*
X275117Y860458D01*
X275325Y860750D01*
X275617Y860958D01*
X275908Y861000D01*
X276200Y860917D01*
X276408Y860708D01*
G01X253467Y847000D02*
Y849500D01*
X254508D01*
X254842Y849375D01*
X255050Y849208D01*
X255133Y848875D01*
X255050Y848542D01*
X254800Y848333D01*
X254508Y848208D01*
X253467D01*
G01X254508D02*
X255133Y847000D01*
G01X256608Y849083D02*
X256858Y849333D01*
X257150Y849458D01*
X257483Y849500D01*
X257900Y849417D01*
X258192Y849208D01*
X258275Y848958D01*
X258233Y848708D01*
X258067Y848500D01*
X257233Y848083D01*
X256858Y847792D01*
X256608Y847375D01*
X256525Y847000D01*
X258275D01*
G01X260500D02*
Y849500D01*
X260000Y849000D01*
G01Y847000D02*
X261000D01*
G01X263600Y849500D02*
X263267Y849417D01*
X263017Y849208D01*
X262850Y848958D01*
X262725Y848625D01*
X262683Y848250D01*
X262725Y847875D01*
X262850Y847542D01*
X263017Y847292D01*
X263267Y847083D01*
X263600Y847000D01*
X263933Y847083D01*
X264183Y847292D01*
X264350Y847542D01*
X264475Y847875D01*
X264517Y848250D01*
X264475Y848625D01*
X264350Y848958D01*
X264183Y849208D01*
X263933Y849417D01*
X263600Y849500D01*
G01X265908Y849083D02*
X266158Y849333D01*
X266450Y849458D01*
X266783Y849500D01*
X267200Y849417D01*
X267492Y849208D01*
X267575Y848958D01*
X267533Y848708D01*
X267367Y848500D01*
X266533Y848083D01*
X266158Y847792D01*
X265908Y847375D01*
X265825Y847000D01*
X267575D01*
G01X255217Y853292D02*
X254967Y853417D01*
X254675Y853500D01*
X254342D01*
X253967Y853375D01*
X253675Y853167D01*
X253467Y852917D01*
X253300Y852500D01*
X253258Y852125D01*
X253342Y851750D01*
X253467Y851500D01*
X253717Y851250D01*
X254008Y851083D01*
X254300Y851000D01*
X254592D01*
X254883Y851083D01*
X255133Y851208D01*
X255342Y851375D01*
G01X257317Y851000D02*
X257400Y851542D01*
X257525Y852000D01*
X257692Y852417D01*
X257900Y852875D01*
X258233Y853500D01*
X256567D01*
G01X259708Y853083D02*
X259958Y853333D01*
X260250Y853458D01*
X260583Y853500D01*
X261000Y853417D01*
X261292Y853208D01*
X261375Y852958D01*
X261333Y852708D01*
X261167Y852500D01*
X260333Y852083D01*
X259958Y851792D01*
X259708Y851375D01*
X259625Y851000D01*
X261375D01*
G01X263517D02*
X263600Y851542D01*
X263725Y852000D01*
X263892Y852417D01*
X264100Y852875D01*
X264433Y853500D01*
X262767D01*
G01X265908Y853083D02*
X266158Y853333D01*
X266450Y853458D01*
X266783Y853500D01*
X267200Y853417D01*
X267492Y853208D01*
X267575Y852958D01*
X267533Y852708D01*
X267367Y852500D01*
X266533Y852083D01*
X266158Y851792D01*
X265908Y851375D01*
X265825Y851000D01*
X267575D01*
G01X262467Y862500D02*
Y865000D01*
X263508D01*
X263842Y864875D01*
X264050Y864708D01*
X264133Y864375D01*
X264050Y864042D01*
X263800Y863833D01*
X263508Y863708D01*
X262467D01*
G01X263508D02*
X264133Y862500D01*
G01X266400D02*
Y865000D01*
X265900Y864500D01*
G01Y862500D02*
X266900D01*
G01X268708Y864583D02*
X268958Y864833D01*
X269250Y864958D01*
X269583Y865000D01*
X270000Y864917D01*
X270292Y864708D01*
X270375Y864458D01*
X270333Y864208D01*
X270167Y864000D01*
X269333Y863583D01*
X268958Y863292D01*
X268708Y862875D01*
X268625Y862500D01*
X270375D01*
G01X271808Y864583D02*
X272058Y864833D01*
X272350Y864958D01*
X272683Y865000D01*
X273100Y864917D01*
X273392Y864708D01*
X273475Y864458D01*
X273433Y864208D01*
X273267Y864000D01*
X272433Y863583D01*
X272058Y863292D01*
X271808Y862875D01*
X271725Y862500D01*
X273475D01*
G01X275617D02*
X275700Y863042D01*
X275825Y863500D01*
X275992Y863917D01*
X276200Y864375D01*
X276533Y865000D01*
X274867D01*
G01X249900Y884000D02*
X249567Y884042D01*
X249275Y884208D01*
X249025Y884458D01*
X248858Y884750D01*
X248775Y885083D01*
Y885417D01*
X248858Y885750D01*
X249025Y886042D01*
X249275Y886292D01*
X249567Y886458D01*
X249900Y886500D01*
X250233Y886458D01*
X250525Y886292D01*
X250775Y886042D01*
X250942Y885750D01*
X251025Y885417D01*
Y885083D01*
X250942Y884750D01*
X250775Y884458D01*
X250525Y884208D01*
X250233Y884042D01*
X249900Y884000D01*
G01X250233Y884667D02*
X250733Y884000D01*
G01X252208Y886083D02*
X252458Y886333D01*
X252750Y886458D01*
X253083Y886500D01*
X253500Y886417D01*
X253792Y886208D01*
X253875Y885958D01*
X253833Y885708D01*
X253667Y885500D01*
X252833Y885083D01*
X252458Y884792D01*
X252208Y884375D01*
X252125Y884000D01*
X253875D01*
G01X255183Y884500D02*
X255433Y884208D01*
X255767Y884042D01*
X256142Y884000D01*
X256475Y884042D01*
X256808Y884250D01*
X257017Y884500D01*
X257058Y884750D01*
X256975Y885042D01*
X256683Y885250D01*
X256392Y885333D01*
X256017D01*
G01X256392D02*
X256642Y885458D01*
X256850Y885667D01*
X256933Y885917D01*
X256850Y886167D01*
X256642Y886375D01*
X256267Y886500D01*
X255892Y886458D01*
X255517Y886292D01*
G01X262350Y889800D02*
Y919800D01*
G01X263500Y895800D02*
X267500D01*
Y903200D01*
G01X280017Y87000D02*
Y89500D01*
X281017D01*
X281350Y89375D01*
X281600Y89083D01*
X281683Y88750D01*
X281600Y88417D01*
X281392Y88167D01*
X281017Y88042D01*
X280017D01*
G01X283075Y87333D02*
X283408Y87125D01*
X283783Y87000D01*
X284117D01*
X284450Y87125D01*
X284700Y87333D01*
X284825Y87625D01*
X284742Y87917D01*
X284533Y88167D01*
X284158Y88333D01*
X283658Y88417D01*
X283367Y88583D01*
X283242Y88875D01*
X283325Y89167D01*
X283533Y89375D01*
X283825Y89500D01*
X284117D01*
X284408Y89417D01*
X284658Y89208D01*
G01X286217Y87000D02*
Y89500D01*
X287217D01*
X287550Y89375D01*
X287800Y89083D01*
X287883Y88750D01*
X287800Y88417D01*
X287592Y88167D01*
X287217Y88042D01*
X286217D01*
G01X289233Y87500D02*
X289483Y87208D01*
X289817Y87042D01*
X290192Y87000D01*
X290525Y87042D01*
X290858Y87250D01*
X291067Y87500D01*
X291108Y87750D01*
X291025Y88042D01*
X290733Y88250D01*
X290442Y88333D01*
X290067D01*
G01X290442D02*
X290692Y88458D01*
X290900Y88667D01*
X290983Y88917D01*
X290900Y89167D01*
X290692Y89375D01*
X290317Y89500D01*
X289942Y89458D01*
X289567Y89292D01*
G01X283000Y99467D02*
X280500D01*
Y100467D01*
X280625Y100800D01*
X280917Y101050D01*
X281250Y101133D01*
X281583Y101050D01*
X281833Y100842D01*
X281958Y100467D01*
Y99467D01*
G01X283000Y102567D02*
X280500D01*
Y103608D01*
X280625Y103942D01*
X280792Y104150D01*
X281125Y104233D01*
X281458Y104150D01*
X281667Y103900D01*
X281792Y103608D01*
Y102567D01*
G01Y103608D02*
X283000Y104233D01*
G01Y106500D02*
X280500D01*
X281000Y106000D01*
G01X283000D02*
Y107000D01*
G01X282708Y108892D02*
X282917Y109183D01*
X283000Y109517D01*
X282917Y109850D01*
X282667Y110142D01*
X282292Y110350D01*
X281917Y110433D01*
X281458D01*
X281083Y110350D01*
X280750Y110142D01*
X280583Y109892D01*
X280500Y109600D01*
X280583Y109267D01*
X280750Y109017D01*
X281000Y108850D01*
X281333Y108767D01*
X281625Y108850D01*
X281917Y109058D01*
X282083Y109308D01*
X282125Y109600D01*
X282042Y109933D01*
X281833Y110183D01*
X281458Y110433D01*
G01X280917Y111908D02*
X280667Y112158D01*
X280542Y112450D01*
X280500Y112783D01*
X280583Y113200D01*
X280792Y113492D01*
X281042Y113575D01*
X281292Y113533D01*
X281500Y113367D01*
X281917Y112533D01*
X282208Y112158D01*
X282625Y111908D01*
X283000Y111825D01*
Y113575D01*
G01X279000Y99467D02*
X276500D01*
Y100467D01*
X276625Y100800D01*
X276917Y101050D01*
X277250Y101133D01*
X277583Y101050D01*
X277833Y100842D01*
X277958Y100467D01*
Y99467D01*
G01X279000Y102567D02*
X276500D01*
Y103608D01*
X276625Y103942D01*
X276792Y104150D01*
X277125Y104233D01*
X277458Y104150D01*
X277667Y103900D01*
X277792Y103608D01*
Y102567D01*
G01Y103608D02*
X279000Y104233D01*
G01Y106500D02*
X276500D01*
X277000Y106000D01*
G01X279000D02*
Y107000D01*
G01X278708Y108892D02*
X278917Y109183D01*
X279000Y109517D01*
X278917Y109850D01*
X278667Y110142D01*
X278292Y110350D01*
X277917Y110433D01*
X277458D01*
X277083Y110350D01*
X276750Y110142D01*
X276583Y109892D01*
X276500Y109600D01*
X276583Y109267D01*
X276750Y109017D01*
X277000Y108850D01*
X277333Y108767D01*
X277625Y108850D01*
X277917Y109058D01*
X278083Y109308D01*
X278125Y109600D01*
X278042Y109933D01*
X277833Y110183D01*
X277458Y110433D01*
G01X278625Y111783D02*
X278833Y112033D01*
X278958Y112325D01*
X279000Y112700D01*
X278917Y113075D01*
X278750Y113367D01*
X278458Y113575D01*
X278125Y113617D01*
X277792Y113533D01*
X277583Y113325D01*
X277417Y113033D01*
X277375Y112742D01*
X277417Y112450D01*
X277583Y112075D01*
X276500Y112200D01*
Y113325D01*
G01X280667Y122925D02*
X280875Y123258D01*
X281000Y123633D01*
Y123967D01*
X280875Y124300D01*
X280667Y124550D01*
X280375Y124675D01*
X280083Y124592D01*
X279833Y124383D01*
X279667Y124008D01*
X279583Y123508D01*
X279417Y123217D01*
X279125Y123092D01*
X278833Y123175D01*
X278625Y123383D01*
X278500Y123675D01*
Y123967D01*
X278583Y124258D01*
X278792Y124508D01*
G01X281000Y126067D02*
X278500D01*
Y127108D01*
X278625Y127442D01*
X278792Y127650D01*
X279125Y127733D01*
X279458Y127650D01*
X279667Y127400D01*
X279792Y127108D01*
Y126067D01*
G01Y127108D02*
X281000Y127733D01*
G01Y129917D02*
X280458Y130000D01*
X280000Y130125D01*
X279583Y130292D01*
X279125Y130500D01*
X278500Y130833D01*
Y129167D01*
G01X281000Y133100D02*
X278500D01*
X279000Y132600D01*
G01X281000D02*
Y133600D01*
G01X279958Y135408D02*
X279667Y135700D01*
X279500Y135950D01*
X279417Y136283D01*
X279500Y136575D01*
X279667Y136783D01*
X279917Y136950D01*
X280208Y136992D01*
X280458Y136950D01*
X280708Y136783D01*
X280917Y136533D01*
X281000Y136242D01*
X280917Y135908D01*
X280667Y135617D01*
X280292Y135450D01*
X279875Y135408D01*
X279333Y135492D01*
X279042Y135617D01*
X278750Y135825D01*
X278542Y136117D01*
X278500Y136408D01*
X278583Y136700D01*
X278792Y136908D01*
G01X275500Y203200D02*
X271500D01*
Y195800D01*
G01X267167Y217925D02*
X267375Y218258D01*
X267500Y218633D01*
Y218967D01*
X267375Y219300D01*
X267167Y219550D01*
X266875Y219675D01*
X266583Y219592D01*
X266333Y219383D01*
X266167Y219008D01*
X266083Y218508D01*
X265917Y218217D01*
X265625Y218092D01*
X265333Y218175D01*
X265125Y218383D01*
X265000Y218675D01*
Y218967D01*
X265083Y219258D01*
X265292Y219508D01*
G01X265208Y222817D02*
X265083Y222567D01*
X265000Y222275D01*
Y221942D01*
X265125Y221567D01*
X265333Y221275D01*
X265583Y221067D01*
X266000Y220900D01*
X266375Y220858D01*
X266750Y220942D01*
X267000Y221067D01*
X267250Y221317D01*
X267417Y221608D01*
X267500Y221900D01*
Y222192D01*
X267417Y222483D01*
X267292Y222733D01*
X267125Y222942D01*
G01X267208Y224292D02*
X267417Y224583D01*
X267500Y224917D01*
X267417Y225250D01*
X267167Y225542D01*
X266792Y225750D01*
X266417Y225833D01*
X265958D01*
X265583Y225750D01*
X265250Y225542D01*
X265083Y225292D01*
X265000Y225000D01*
X265083Y224667D01*
X265250Y224417D01*
X265500Y224250D01*
X265833Y224167D01*
X266125Y224250D01*
X266417Y224458D01*
X266583Y224708D01*
X266625Y225000D01*
X266542Y225333D01*
X266333Y225583D01*
X265958Y225833D01*
G01X267500Y228100D02*
X267458Y228392D01*
X267333Y228725D01*
X267125Y228933D01*
X266833Y229017D01*
X266542Y228933D01*
X266292Y228683D01*
X266167Y228308D01*
Y227892D01*
X266083Y227642D01*
X265875Y227433D01*
X265583Y227350D01*
X265292Y227475D01*
X265083Y227767D01*
X265000Y228100D01*
X265083Y228433D01*
X265292Y228725D01*
X265583Y228850D01*
X265875Y228767D01*
X266083Y228558D01*
X266167Y228308D01*
Y227892D01*
X266292Y227517D01*
X266542Y227267D01*
X266833Y227183D01*
X267125Y227267D01*
X267333Y227475D01*
X267458Y227808D01*
X267500Y228100D01*
G01X265417Y230408D02*
X265167Y230658D01*
X265042Y230950D01*
X265000Y231283D01*
X265083Y231700D01*
X265292Y231992D01*
X265542Y232075D01*
X265792Y232033D01*
X266000Y231867D01*
X266417Y231033D01*
X266708Y230658D01*
X267125Y230408D01*
X267500Y230325D01*
Y232075D01*
G01X271167Y217925D02*
X271375Y218258D01*
X271500Y218633D01*
Y218967D01*
X271375Y219300D01*
X271167Y219550D01*
X270875Y219675D01*
X270583Y219592D01*
X270333Y219383D01*
X270167Y219008D01*
X270083Y218508D01*
X269917Y218217D01*
X269625Y218092D01*
X269333Y218175D01*
X269125Y218383D01*
X269000Y218675D01*
Y218967D01*
X269083Y219258D01*
X269292Y219508D01*
G01X269208Y222817D02*
X269083Y222567D01*
X269000Y222275D01*
Y221942D01*
X269125Y221567D01*
X269333Y221275D01*
X269583Y221067D01*
X270000Y220900D01*
X270375Y220858D01*
X270750Y220942D01*
X271000Y221067D01*
X271250Y221317D01*
X271417Y221608D01*
X271500Y221900D01*
Y222192D01*
X271417Y222483D01*
X271292Y222733D01*
X271125Y222942D01*
G01X271208Y224292D02*
X271417Y224583D01*
X271500Y224917D01*
X271417Y225250D01*
X271167Y225542D01*
X270792Y225750D01*
X270417Y225833D01*
X269958D01*
X269583Y225750D01*
X269250Y225542D01*
X269083Y225292D01*
X269000Y225000D01*
X269083Y224667D01*
X269250Y224417D01*
X269500Y224250D01*
X269833Y224167D01*
X270125Y224250D01*
X270417Y224458D01*
X270583Y224708D01*
X270625Y225000D01*
X270542Y225333D01*
X270333Y225583D01*
X269958Y225833D01*
G01X270458Y227308D02*
X270167Y227600D01*
X270000Y227850D01*
X269917Y228183D01*
X270000Y228475D01*
X270167Y228683D01*
X270417Y228850D01*
X270708Y228892D01*
X270958Y228850D01*
X271208Y228683D01*
X271417Y228433D01*
X271500Y228142D01*
X271417Y227808D01*
X271167Y227517D01*
X270792Y227350D01*
X270375Y227308D01*
X269833Y227392D01*
X269542Y227517D01*
X269250Y227725D01*
X269042Y228017D01*
X269000Y228308D01*
X269083Y228600D01*
X269292Y228808D01*
G01X271500Y231117D02*
X270958Y231200D01*
X270500Y231325D01*
X270083Y231492D01*
X269625Y231700D01*
X269000Y232033D01*
Y230367D01*
G01X316500Y431500D02*
Y411500D01*
X319500Y414500D01*
X313500D01*
X316500Y411500D01*
X267500D01*
Y391000D01*
X322500D01*
Y411500D01*
X316500D01*
G01X276222Y392375D02*
X276430Y392708D01*
X276555Y393083D01*
Y393417D01*
X276430Y393750D01*
X276222Y394000D01*
X275930Y394125D01*
X275638Y394042D01*
X275388Y393833D01*
X275222Y393458D01*
X275138Y392958D01*
X274972Y392667D01*
X274680Y392542D01*
X274388Y392625D01*
X274180Y392833D01*
X274055Y393125D01*
Y393417D01*
X274138Y393708D01*
X274347Y393958D01*
G01X274263Y397267D02*
X274138Y397017D01*
X274055Y396725D01*
Y396392D01*
X274180Y396017D01*
X274388Y395725D01*
X274638Y395517D01*
X275055Y395350D01*
X275430Y395308D01*
X275805Y395392D01*
X276055Y395517D01*
X276305Y395767D01*
X276472Y396058D01*
X276555Y396350D01*
Y396642D01*
X276472Y396933D01*
X276347Y397183D01*
X276180Y397392D01*
G01X276555Y399450D02*
X274055D01*
X274555Y398950D01*
G01X276555D02*
Y399950D01*
G01X274472Y401758D02*
X274222Y402008D01*
X274097Y402300D01*
X274055Y402633D01*
X274138Y403050D01*
X274347Y403342D01*
X274597Y403425D01*
X274847Y403383D01*
X275055Y403217D01*
X275472Y402383D01*
X275763Y402008D01*
X276180Y401758D01*
X276555Y401675D01*
Y403425D01*
G01X274055Y405650D02*
X274138Y405317D01*
X274347Y405067D01*
X274597Y404900D01*
X274930Y404775D01*
X275305Y404733D01*
X275680Y404775D01*
X276013Y404900D01*
X276263Y405067D01*
X276472Y405317D01*
X276555Y405650D01*
X276472Y405983D01*
X276263Y406233D01*
X276013Y406400D01*
X275680Y406525D01*
X275305Y406567D01*
X274930Y406525D01*
X274597Y406400D01*
X274347Y406233D01*
X274138Y405983D01*
X274055Y405650D01*
G01X276180Y407833D02*
X276388Y408083D01*
X276513Y408375D01*
X276555Y408750D01*
X276472Y409125D01*
X276305Y409417D01*
X276013Y409625D01*
X275680Y409667D01*
X275347Y409583D01*
X275138Y409375D01*
X274972Y409083D01*
X274930Y408792D01*
X274972Y408500D01*
X275138Y408125D01*
X274055Y408250D01*
Y409375D01*
G01X280222Y392375D02*
X280430Y392708D01*
X280555Y393083D01*
Y393417D01*
X280430Y393750D01*
X280222Y394000D01*
X279930Y394125D01*
X279638Y394042D01*
X279388Y393833D01*
X279222Y393458D01*
X279138Y392958D01*
X278972Y392667D01*
X278680Y392542D01*
X278388Y392625D01*
X278180Y392833D01*
X278055Y393125D01*
Y393417D01*
X278138Y393708D01*
X278347Y393958D01*
G01X278263Y397267D02*
X278138Y397017D01*
X278055Y396725D01*
Y396392D01*
X278180Y396017D01*
X278388Y395725D01*
X278638Y395517D01*
X279055Y395350D01*
X279430Y395308D01*
X279805Y395392D01*
X280055Y395517D01*
X280305Y395767D01*
X280472Y396058D01*
X280555Y396350D01*
Y396642D01*
X280472Y396933D01*
X280347Y397183D01*
X280180Y397392D01*
G01X280555Y399450D02*
X278055D01*
X278555Y398950D01*
G01X280555D02*
Y399950D01*
G01X278472Y401758D02*
X278222Y402008D01*
X278097Y402300D01*
X278055Y402633D01*
X278138Y403050D01*
X278347Y403342D01*
X278597Y403425D01*
X278847Y403383D01*
X279055Y403217D01*
X279472Y402383D01*
X279763Y402008D01*
X280180Y401758D01*
X280555Y401675D01*
Y403425D01*
G01X278055Y405650D02*
X278138Y405317D01*
X278347Y405067D01*
X278597Y404900D01*
X278930Y404775D01*
X279305Y404733D01*
X279680Y404775D01*
X280013Y404900D01*
X280263Y405067D01*
X280472Y405317D01*
X280555Y405650D01*
X280472Y405983D01*
X280263Y406233D01*
X280013Y406400D01*
X279680Y406525D01*
X279305Y406567D01*
X278930Y406525D01*
X278597Y406400D01*
X278347Y406233D01*
X278138Y405983D01*
X278055Y405650D01*
G01X279513Y407958D02*
X279222Y408250D01*
X279055Y408500D01*
X278972Y408833D01*
X279055Y409125D01*
X279222Y409333D01*
X279472Y409500D01*
X279763Y409542D01*
X280013Y409500D01*
X280263Y409333D01*
X280472Y409083D01*
X280555Y408792D01*
X280472Y408458D01*
X280222Y408167D01*
X279847Y408000D01*
X279430Y407958D01*
X278888Y408042D01*
X278597Y408167D01*
X278305Y408375D01*
X278097Y408667D01*
X278055Y408958D01*
X278138Y409250D01*
X278347Y409458D01*
G01X272555Y392967D02*
X270055D01*
Y393967D01*
X270180Y394300D01*
X270472Y394550D01*
X270805Y394633D01*
X271138Y394550D01*
X271388Y394342D01*
X271513Y393967D01*
Y392967D01*
G01X272555Y396067D02*
X270055D01*
Y397108D01*
X270180Y397442D01*
X270347Y397650D01*
X270680Y397733D01*
X271013Y397650D01*
X271222Y397400D01*
X271347Y397108D01*
Y396067D01*
G01Y397108D02*
X272555Y397733D01*
G01Y400000D02*
X270055D01*
X270555Y399500D01*
G01X272555D02*
Y400500D01*
G01Y403017D02*
X272013Y403100D01*
X271555Y403225D01*
X271138Y403392D01*
X270680Y403600D01*
X270055Y403933D01*
Y402267D01*
G01X272555Y406200D02*
X270055D01*
X270555Y405700D01*
G01X272555D02*
Y406700D01*
G01X267659Y424178D02*
X281659D01*
G01X267659Y437178D02*
Y424178D01*
G01X271067Y439000D02*
Y441500D01*
X272067D01*
X272400Y441375D01*
X272650Y441083D01*
X272733Y440750D01*
X272650Y440417D01*
X272442Y440167D01*
X272067Y440042D01*
X271067D01*
G01X275000Y439000D02*
X274667Y439042D01*
X274375Y439208D01*
X274125Y439458D01*
X273958Y439750D01*
X273875Y440083D01*
Y440417D01*
X273958Y440750D01*
X274125Y441042D01*
X274375Y441292D01*
X274667Y441458D01*
X275000Y441500D01*
X275333Y441458D01*
X275625Y441292D01*
X275875Y441042D01*
X276042Y440750D01*
X276125Y440417D01*
Y440083D01*
X276042Y439750D01*
X275875Y439458D01*
X275625Y439208D01*
X275333Y439042D01*
X275000Y439000D01*
G01X275333Y439667D02*
X275833Y439000D01*
G01X278600D02*
Y441500D01*
X277058Y439708D01*
X279142D01*
G01X281659Y437178D02*
X267659D01*
G01X279967Y858500D02*
Y861000D01*
X280967D01*
X281300Y860875D01*
X281550Y860583D01*
X281633Y860250D01*
X281550Y859917D01*
X281342Y859667D01*
X280967Y859542D01*
X279967D01*
G01X283108Y860583D02*
X283358Y860833D01*
X283650Y860958D01*
X283983Y861000D01*
X284400Y860917D01*
X284692Y860708D01*
X284775Y860458D01*
X284733Y860208D01*
X284567Y860000D01*
X283733Y859583D01*
X283358Y859292D01*
X283108Y858875D01*
X283025Y858500D01*
X284775D01*
G01X287000D02*
Y861000D01*
X286500Y860500D01*
G01Y858500D02*
X287500D01*
G01X289308Y860583D02*
X289558Y860833D01*
X289850Y860958D01*
X290183Y861000D01*
X290600Y860917D01*
X290892Y860708D01*
X290975Y860458D01*
X290933Y860208D01*
X290767Y860000D01*
X289933Y859583D01*
X289558Y859292D01*
X289308Y858875D01*
X289225Y858500D01*
X290975D01*
G01X293200D02*
Y861000D01*
X292700Y860500D01*
G01Y858500D02*
X293700D01*
G01X269467Y876500D02*
Y879000D01*
X270508D01*
X270842Y878875D01*
X271050Y878708D01*
X271133Y878375D01*
X271050Y878042D01*
X270800Y877833D01*
X270508Y877708D01*
X269467D01*
G01X270508D02*
X271133Y876500D01*
G01X272608Y878583D02*
X272858Y878833D01*
X273150Y878958D01*
X273483Y879000D01*
X273900Y878917D01*
X274192Y878708D01*
X274275Y878458D01*
X274233Y878208D01*
X274067Y878000D01*
X273233Y877583D01*
X272858Y877292D01*
X272608Y876875D01*
X272525Y876500D01*
X274275D01*
G01X276500D02*
Y879000D01*
X276000Y878500D01*
G01Y876500D02*
X277000D01*
G01X279600D02*
Y879000D01*
X279100Y878500D01*
G01Y876500D02*
X280100D01*
G01X281783Y876875D02*
X282033Y876667D01*
X282325Y876542D01*
X282700Y876500D01*
X283075Y876583D01*
X283367Y876750D01*
X283575Y877042D01*
X283617Y877375D01*
X283533Y877708D01*
X283325Y877917D01*
X283033Y878083D01*
X282742Y878125D01*
X282450Y878083D01*
X282075Y877917D01*
X282200Y879000D01*
X283325D01*
G01X275000Y906500D02*
Y890400D01*
G01X268000D02*
Y906500D01*
G01X275000Y890400D02*
X268000D01*
G01X275500Y893800D02*
X279500D01*
Y901200D01*
G01X274700Y882500D02*
Y886500D01*
X267300D01*
G01X268000Y906500D02*
X275000D01*
G01X273500Y920467D02*
X271000D01*
Y921508D01*
X271125Y921842D01*
X271292Y922050D01*
X271625Y922133D01*
X271958Y922050D01*
X272167Y921800D01*
X272292Y921508D01*
Y920467D01*
G01Y921508D02*
X273500Y922133D01*
G01X271417Y923608D02*
X271167Y923858D01*
X271042Y924150D01*
X271000Y924483D01*
X271083Y924900D01*
X271292Y925192D01*
X271542Y925275D01*
X271792Y925233D01*
X272000Y925067D01*
X272417Y924233D01*
X272708Y923858D01*
X273125Y923608D01*
X273500Y923525D01*
Y925275D01*
G01Y927500D02*
X271000D01*
X271500Y927000D01*
G01X273500D02*
Y928000D01*
G01Y930600D02*
X271000D01*
X271500Y930100D01*
G01X273500D02*
Y931100D01*
G01Y933700D02*
X273458Y933992D01*
X273333Y934325D01*
X273125Y934533D01*
X272833Y934617D01*
X272542Y934533D01*
X272292Y934283D01*
X272167Y933908D01*
Y933492D01*
X272083Y933242D01*
X271875Y933033D01*
X271583Y932950D01*
X271292Y933075D01*
X271083Y933367D01*
X271000Y933700D01*
X271083Y934033D01*
X271292Y934325D01*
X271583Y934450D01*
X271875Y934367D01*
X272083Y934158D01*
X272167Y933908D01*
Y933492D01*
X272292Y933117D01*
X272542Y932867D01*
X272833Y932783D01*
X273125Y932867D01*
X273333Y933075D01*
X273458Y933408D01*
X273500Y933700D01*
G01X266208Y922217D02*
X266083Y921967D01*
X266000Y921675D01*
Y921342D01*
X266125Y920967D01*
X266333Y920675D01*
X266583Y920467D01*
X267000Y920300D01*
X267375Y920258D01*
X267750Y920342D01*
X268000Y920467D01*
X268250Y920717D01*
X268417Y921008D01*
X268500Y921300D01*
Y921592D01*
X268417Y921883D01*
X268292Y922133D01*
X268125Y922342D01*
G01X268500Y924317D02*
X267958Y924400D01*
X267500Y924525D01*
X267083Y924692D01*
X266625Y924900D01*
X266000Y925233D01*
Y923567D01*
G01X266417Y926708D02*
X266167Y926958D01*
X266042Y927250D01*
X266000Y927583D01*
X266083Y928000D01*
X266292Y928292D01*
X266542Y928375D01*
X266792Y928333D01*
X267000Y928167D01*
X267417Y927333D01*
X267708Y926958D01*
X268125Y926708D01*
X268500Y926625D01*
Y928375D01*
G01Y930517D02*
X267958Y930600D01*
X267500Y930725D01*
X267083Y930892D01*
X266625Y931100D01*
X266000Y931433D01*
Y929767D01*
G01X268208Y932992D02*
X268417Y933283D01*
X268500Y933617D01*
X268417Y933950D01*
X268167Y934242D01*
X267792Y934450D01*
X267417Y934533D01*
X266958D01*
X266583Y934450D01*
X266250Y934242D01*
X266083Y933992D01*
X266000Y933700D01*
X266083Y933367D01*
X266250Y933117D01*
X266500Y932950D01*
X266833Y932867D01*
X267125Y932950D01*
X267417Y933158D01*
X267583Y933408D01*
X267625Y933700D01*
X267542Y934033D01*
X267333Y934283D01*
X266958Y934533D01*
G01X297500Y3017D02*
X295000D01*
Y4017D01*
X295125Y4350D01*
X295417Y4600D01*
X295750Y4683D01*
X296083Y4600D01*
X296333Y4392D01*
X296458Y4017D01*
Y3017D01*
G01X295000Y6117D02*
X297500D01*
Y7783D01*
G01Y10050D02*
X295000D01*
X295500Y9550D01*
G01X297500D02*
Y10550D01*
G01X295000Y13150D02*
X295083Y12817D01*
X295292Y12567D01*
X295542Y12400D01*
X295875Y12275D01*
X296250Y12233D01*
X296625Y12275D01*
X296958Y12400D01*
X297208Y12567D01*
X297417Y12817D01*
X297500Y13150D01*
X297417Y13483D01*
X297208Y13733D01*
X296958Y13900D01*
X296625Y14025D01*
X296250Y14067D01*
X295875Y14025D01*
X295542Y13900D01*
X295292Y13733D01*
X295083Y13483D01*
X295000Y13150D01*
G01X297500Y16467D02*
X295000D01*
Y17467D01*
X295125Y17800D01*
X295417Y18050D01*
X295750Y18133D01*
X296083Y18050D01*
X296333Y17842D01*
X296458Y17467D01*
Y16467D01*
G01X295208Y21317D02*
X295083Y21067D01*
X295000Y20775D01*
Y20442D01*
X295125Y20067D01*
X295333Y19775D01*
X295583Y19567D01*
X296000Y19400D01*
X296375Y19358D01*
X296750Y19442D01*
X297000Y19567D01*
X297250Y19817D01*
X297417Y20108D01*
X297500Y20400D01*
Y20692D01*
X297417Y20983D01*
X297292Y21233D01*
X297125Y21442D01*
G01X295417Y22708D02*
X295167Y22958D01*
X295042Y23250D01*
X295000Y23583D01*
X295083Y24000D01*
X295292Y24292D01*
X295542Y24375D01*
X295792Y24333D01*
X296000Y24167D01*
X296417Y23333D01*
X296708Y22958D01*
X297125Y22708D01*
X297500Y22625D01*
Y24375D01*
G01X295000Y26600D02*
X295083Y26267D01*
X295292Y26017D01*
X295542Y25850D01*
X295875Y25725D01*
X296250Y25683D01*
X296625Y25725D01*
X296958Y25850D01*
X297208Y26017D01*
X297417Y26267D01*
X297500Y26600D01*
X297417Y26933D01*
X297208Y27183D01*
X296958Y27350D01*
X296625Y27475D01*
X296250Y27517D01*
X295875Y27475D01*
X295542Y27350D01*
X295292Y27183D01*
X295083Y26933D01*
X295000Y26600D01*
G01X297125Y28783D02*
X297333Y29033D01*
X297458Y29325D01*
X297500Y29700D01*
X297417Y30075D01*
X297250Y30367D01*
X296958Y30575D01*
X296625Y30617D01*
X296292Y30533D01*
X296083Y30325D01*
X295917Y30033D01*
X295875Y29742D01*
X295917Y29450D01*
X296083Y29075D01*
X295000Y29200D01*
Y30325D01*
G01X299000Y32967D02*
X296500D01*
Y33967D01*
X296625Y34300D01*
X296917Y34550D01*
X297250Y34633D01*
X297583Y34550D01*
X297833Y34342D01*
X297958Y33967D01*
Y32967D01*
G01X296708Y37817D02*
X296583Y37567D01*
X296500Y37275D01*
Y36942D01*
X296625Y36567D01*
X296833Y36275D01*
X297083Y36067D01*
X297500Y35900D01*
X297875Y35858D01*
X298250Y35942D01*
X298500Y36067D01*
X298750Y36317D01*
X298917Y36608D01*
X299000Y36900D01*
Y37192D01*
X298917Y37483D01*
X298792Y37733D01*
X298625Y37942D01*
G01X296917Y39208D02*
X296667Y39458D01*
X296542Y39750D01*
X296500Y40083D01*
X296583Y40500D01*
X296792Y40792D01*
X297042Y40875D01*
X297292Y40833D01*
X297500Y40667D01*
X297917Y39833D01*
X298208Y39458D01*
X298625Y39208D01*
X299000Y39125D01*
Y40875D01*
G01X296500Y43100D02*
X296583Y42767D01*
X296792Y42517D01*
X297042Y42350D01*
X297375Y42225D01*
X297750Y42183D01*
X298125Y42225D01*
X298458Y42350D01*
X298708Y42517D01*
X298917Y42767D01*
X299000Y43100D01*
X298917Y43433D01*
X298708Y43683D01*
X298458Y43850D01*
X298125Y43975D01*
X297750Y44017D01*
X297375Y43975D01*
X297042Y43850D01*
X296792Y43683D01*
X296583Y43433D01*
X296500Y43100D01*
G01X299000Y46700D02*
X296500D01*
X298292Y45158D01*
Y47242D01*
G01X299000Y49967D02*
X296500D01*
Y50967D01*
X296625Y51300D01*
X296917Y51550D01*
X297250Y51633D01*
X297583Y51550D01*
X297833Y51342D01*
X297958Y50967D01*
Y49967D01*
G01X296708Y54817D02*
X296583Y54567D01*
X296500Y54275D01*
Y53942D01*
X296625Y53567D01*
X296833Y53275D01*
X297083Y53067D01*
X297500Y52900D01*
X297875Y52858D01*
X298250Y52942D01*
X298500Y53067D01*
X298750Y53317D01*
X298917Y53608D01*
X299000Y53900D01*
Y54192D01*
X298917Y54483D01*
X298792Y54733D01*
X298625Y54942D01*
G01X296917Y56208D02*
X296667Y56458D01*
X296542Y56750D01*
X296500Y57083D01*
X296583Y57500D01*
X296792Y57792D01*
X297042Y57875D01*
X297292Y57833D01*
X297500Y57667D01*
X297917Y56833D01*
X298208Y56458D01*
X298625Y56208D01*
X299000Y56125D01*
Y57875D01*
G01Y60100D02*
X296500D01*
X297000Y59600D01*
G01X299000D02*
Y60600D01*
G01Y63200D02*
X296500D01*
X297000Y62700D01*
G01X299000D02*
Y63700D01*
G01X296500Y69517D02*
X294000D01*
Y70517D01*
X294125Y70850D01*
X294417Y71100D01*
X294750Y71183D01*
X295083Y71100D01*
X295333Y70892D01*
X295458Y70517D01*
Y69517D01*
G01X294000Y72533D02*
X295792D01*
X296167Y72700D01*
X296417Y73033D01*
X296500Y73450D01*
X296417Y73867D01*
X296167Y74200D01*
X295792Y74367D01*
X294000D01*
G01X296500Y76550D02*
X294000D01*
X294500Y76050D01*
G01X296500D02*
Y77050D01*
G01X296000Y78733D02*
X296292Y78983D01*
X296458Y79317D01*
X296500Y79692D01*
X296458Y80025D01*
X296250Y80358D01*
X296000Y80567D01*
X295750Y80608D01*
X295458Y80525D01*
X295250Y80233D01*
X295167Y79942D01*
Y79567D01*
G01Y79942D02*
X295042Y80192D01*
X294833Y80400D01*
X294583Y80483D01*
X294333Y80400D01*
X294125Y80192D01*
X294000Y79817D01*
X294042Y79442D01*
X294208Y79067D01*
G01X290400Y70867D02*
X287900D01*
Y71867D01*
X288025Y72200D01*
X288317Y72450D01*
X288650Y72533D01*
X288983Y72450D01*
X289233Y72242D01*
X289358Y71867D01*
Y70867D01*
G01X288108Y75717D02*
X287983Y75467D01*
X287900Y75175D01*
Y74842D01*
X288025Y74467D01*
X288233Y74175D01*
X288483Y73967D01*
X288900Y73800D01*
X289275Y73758D01*
X289650Y73842D01*
X289900Y73967D01*
X290150Y74217D01*
X290317Y74508D01*
X290400Y74800D01*
Y75092D01*
X290317Y75383D01*
X290192Y75633D01*
X290025Y75842D01*
G01X288317Y77108D02*
X288067Y77358D01*
X287942Y77650D01*
X287900Y77983D01*
X287983Y78400D01*
X288192Y78692D01*
X288442Y78775D01*
X288692Y78733D01*
X288900Y78567D01*
X289317Y77733D01*
X289608Y77358D01*
X290025Y77108D01*
X290400Y77025D01*
Y78775D01*
G01X287900Y81000D02*
X287983Y80667D01*
X288192Y80417D01*
X288442Y80250D01*
X288775Y80125D01*
X289150Y80083D01*
X289525Y80125D01*
X289858Y80250D01*
X290108Y80417D01*
X290317Y80667D01*
X290400Y81000D01*
X290317Y81333D01*
X290108Y81583D01*
X289858Y81750D01*
X289525Y81875D01*
X289150Y81917D01*
X288775Y81875D01*
X288442Y81750D01*
X288192Y81583D01*
X287983Y81333D01*
X287900Y81000D01*
G01X290400Y84017D02*
X289858Y84100D01*
X289400Y84225D01*
X288983Y84392D01*
X288525Y84600D01*
X287900Y84933D01*
Y83267D01*
G01X285400Y70867D02*
X282900D01*
Y71867D01*
X283025Y72200D01*
X283317Y72450D01*
X283650Y72533D01*
X283983Y72450D01*
X284233Y72242D01*
X284358Y71867D01*
Y70867D01*
G01X283108Y75717D02*
X282983Y75467D01*
X282900Y75175D01*
Y74842D01*
X283025Y74467D01*
X283233Y74175D01*
X283483Y73967D01*
X283900Y73800D01*
X284275Y73758D01*
X284650Y73842D01*
X284900Y73967D01*
X285150Y74217D01*
X285317Y74508D01*
X285400Y74800D01*
Y75092D01*
X285317Y75383D01*
X285192Y75633D01*
X285025Y75842D01*
G01X283317Y77108D02*
X283067Y77358D01*
X282942Y77650D01*
X282900Y77983D01*
X282983Y78400D01*
X283192Y78692D01*
X283442Y78775D01*
X283692Y78733D01*
X283900Y78567D01*
X284317Y77733D01*
X284608Y77358D01*
X285025Y77108D01*
X285400Y77025D01*
Y78775D01*
G01X282900Y81000D02*
X282983Y80667D01*
X283192Y80417D01*
X283442Y80250D01*
X283775Y80125D01*
X284150Y80083D01*
X284525Y80125D01*
X284858Y80250D01*
X285108Y80417D01*
X285317Y80667D01*
X285400Y81000D01*
X285317Y81333D01*
X285108Y81583D01*
X284858Y81750D01*
X284525Y81875D01*
X284150Y81917D01*
X283775Y81875D01*
X283442Y81750D01*
X283192Y81583D01*
X282983Y81333D01*
X282900Y81000D01*
G01X285400Y84100D02*
X285358Y84392D01*
X285233Y84725D01*
X285025Y84933D01*
X284733Y85017D01*
X284442Y84933D01*
X284192Y84683D01*
X284067Y84308D01*
Y83892D01*
X283983Y83642D01*
X283775Y83433D01*
X283483Y83350D01*
X283192Y83475D01*
X282983Y83767D01*
X282900Y84100D01*
X282983Y84433D01*
X283192Y84725D01*
X283483Y84850D01*
X283775Y84767D01*
X283983Y84558D01*
X284067Y84308D01*
Y83892D01*
X284192Y83517D01*
X284442Y83267D01*
X284733Y83183D01*
X285025Y83267D01*
X285233Y83475D01*
X285358Y83808D01*
X285400Y84100D01*
G01X294000Y85800D02*
X298000D01*
Y93200D01*
G01X338300Y101000D02*
Y121000D01*
X293700D01*
Y101000D01*
X338300D01*
G01X287000Y99467D02*
X284500D01*
Y100467D01*
X284625Y100800D01*
X284917Y101050D01*
X285250Y101133D01*
X285583Y101050D01*
X285833Y100842D01*
X285958Y100467D01*
Y99467D01*
G01X287000Y102567D02*
X284500D01*
Y103608D01*
X284625Y103942D01*
X284792Y104150D01*
X285125Y104233D01*
X285458Y104150D01*
X285667Y103900D01*
X285792Y103608D01*
Y102567D01*
G01Y103608D02*
X287000Y104233D01*
G01Y106500D02*
X284500D01*
X285000Y106000D01*
G01X287000D02*
Y107000D01*
G01Y109600D02*
X286958Y109892D01*
X286833Y110225D01*
X286625Y110433D01*
X286333Y110517D01*
X286042Y110433D01*
X285792Y110183D01*
X285667Y109808D01*
Y109392D01*
X285583Y109142D01*
X285375Y108933D01*
X285083Y108850D01*
X284792Y108975D01*
X284583Y109267D01*
X284500Y109600D01*
X284583Y109933D01*
X284792Y110225D01*
X285083Y110350D01*
X285375Y110267D01*
X285583Y110058D01*
X285667Y109808D01*
Y109392D01*
X285792Y109017D01*
X286042Y108767D01*
X286333Y108683D01*
X286625Y108767D01*
X286833Y108975D01*
X286958Y109308D01*
X287000Y109600D01*
G01X286708Y111992D02*
X286917Y112283D01*
X287000Y112617D01*
X286917Y112950D01*
X286667Y113242D01*
X286292Y113450D01*
X285917Y113533D01*
X285458D01*
X285083Y113450D01*
X284750Y113242D01*
X284583Y112992D01*
X284500Y112700D01*
X284583Y112367D01*
X284750Y112117D01*
X285000Y111950D01*
X285333Y111867D01*
X285625Y111950D01*
X285917Y112158D01*
X286083Y112408D01*
X286125Y112700D01*
X286042Y113033D01*
X285833Y113283D01*
X285458Y113533D01*
G01X291000Y99467D02*
X288500D01*
Y100467D01*
X288625Y100800D01*
X288917Y101050D01*
X289250Y101133D01*
X289583Y101050D01*
X289833Y100842D01*
X289958Y100467D01*
Y99467D01*
G01X288708Y104317D02*
X288583Y104067D01*
X288500Y103775D01*
Y103442D01*
X288625Y103067D01*
X288833Y102775D01*
X289083Y102567D01*
X289500Y102400D01*
X289875Y102358D01*
X290250Y102442D01*
X290500Y102567D01*
X290750Y102817D01*
X290917Y103108D01*
X291000Y103400D01*
Y103692D01*
X290917Y103983D01*
X290792Y104233D01*
X290625Y104442D01*
G01X288917Y105708D02*
X288667Y105958D01*
X288542Y106250D01*
X288500Y106583D01*
X288583Y107000D01*
X288792Y107292D01*
X289042Y107375D01*
X289292Y107333D01*
X289500Y107167D01*
X289917Y106333D01*
X290208Y105958D01*
X290625Y105708D01*
X291000Y105625D01*
Y107375D01*
G01X288917Y108808D02*
X288667Y109058D01*
X288542Y109350D01*
X288500Y109683D01*
X288583Y110100D01*
X288792Y110392D01*
X289042Y110475D01*
X289292Y110433D01*
X289500Y110267D01*
X289917Y109433D01*
X290208Y109058D01*
X290625Y108808D01*
X291000Y108725D01*
Y110475D01*
G01X288500Y112700D02*
X288583Y112367D01*
X288792Y112117D01*
X289042Y111950D01*
X289375Y111825D01*
X289750Y111783D01*
X290125Y111825D01*
X290458Y111950D01*
X290708Y112117D01*
X290917Y112367D01*
X291000Y112700D01*
X290917Y113033D01*
X290708Y113283D01*
X290458Y113450D01*
X290125Y113575D01*
X289750Y113617D01*
X289375Y113575D01*
X289042Y113450D01*
X288792Y113283D01*
X288583Y113033D01*
X288500Y112700D01*
G01X285167Y122925D02*
X285375Y123258D01*
X285500Y123633D01*
Y123967D01*
X285375Y124300D01*
X285167Y124550D01*
X284875Y124675D01*
X284583Y124592D01*
X284333Y124383D01*
X284167Y124008D01*
X284083Y123508D01*
X283917Y123217D01*
X283625Y123092D01*
X283333Y123175D01*
X283125Y123383D01*
X283000Y123675D01*
Y123967D01*
X283083Y124258D01*
X283292Y124508D01*
G01X283208Y127817D02*
X283083Y127567D01*
X283000Y127275D01*
Y126942D01*
X283125Y126567D01*
X283333Y126275D01*
X283583Y126067D01*
X284000Y125900D01*
X284375Y125858D01*
X284750Y125942D01*
X285000Y126067D01*
X285250Y126317D01*
X285417Y126608D01*
X285500Y126900D01*
Y127192D01*
X285417Y127483D01*
X285292Y127733D01*
X285125Y127942D01*
G01X285208Y129292D02*
X285417Y129583D01*
X285500Y129917D01*
X285417Y130250D01*
X285167Y130542D01*
X284792Y130750D01*
X284417Y130833D01*
X283958D01*
X283583Y130750D01*
X283250Y130542D01*
X283083Y130292D01*
X283000Y130000D01*
X283083Y129667D01*
X283250Y129417D01*
X283500Y129250D01*
X283833Y129167D01*
X284125Y129250D01*
X284417Y129458D01*
X284583Y129708D01*
X284625Y130000D01*
X284542Y130333D01*
X284333Y130583D01*
X283958Y130833D01*
G01X285125Y132183D02*
X285333Y132433D01*
X285458Y132725D01*
X285500Y133100D01*
X285417Y133475D01*
X285250Y133767D01*
X284958Y133975D01*
X284625Y134017D01*
X284292Y133933D01*
X284083Y133725D01*
X283917Y133433D01*
X283875Y133142D01*
X283917Y132850D01*
X284083Y132475D01*
X283000Y132600D01*
Y133725D01*
G01X284458Y135408D02*
X284167Y135700D01*
X284000Y135950D01*
X283917Y136283D01*
X284000Y136575D01*
X284167Y136783D01*
X284417Y136950D01*
X284708Y136992D01*
X284958Y136950D01*
X285208Y136783D01*
X285417Y136533D01*
X285500Y136242D01*
X285417Y135908D01*
X285167Y135617D01*
X284792Y135450D01*
X284375Y135408D01*
X283833Y135492D01*
X283542Y135617D01*
X283250Y135825D01*
X283042Y136117D01*
X283000Y136408D01*
X283083Y136700D01*
X283292Y136908D01*
G01X289657Y123245D02*
X289865Y123578D01*
X289990Y123953D01*
Y124287D01*
X289865Y124620D01*
X289657Y124870D01*
X289365Y124995D01*
X289073Y124912D01*
X288823Y124703D01*
X288657Y124328D01*
X288573Y123828D01*
X288407Y123537D01*
X288115Y123412D01*
X287823Y123495D01*
X287615Y123703D01*
X287490Y123995D01*
Y124287D01*
X287573Y124578D01*
X287782Y124828D01*
G01X287698Y128137D02*
X287573Y127887D01*
X287490Y127595D01*
Y127262D01*
X287615Y126887D01*
X287823Y126595D01*
X288073Y126387D01*
X288490Y126220D01*
X288865Y126178D01*
X289240Y126262D01*
X289490Y126387D01*
X289740Y126637D01*
X289907Y126928D01*
X289990Y127220D01*
Y127512D01*
X289907Y127803D01*
X289782Y128053D01*
X289615Y128262D01*
G01X289698Y129612D02*
X289907Y129903D01*
X289990Y130237D01*
X289907Y130570D01*
X289657Y130862D01*
X289282Y131070D01*
X288907Y131153D01*
X288448D01*
X288073Y131070D01*
X287740Y130862D01*
X287573Y130612D01*
X287490Y130320D01*
X287573Y129987D01*
X287740Y129737D01*
X287990Y129570D01*
X288323Y129487D01*
X288615Y129570D01*
X288907Y129778D01*
X289073Y130028D01*
X289115Y130320D01*
X289032Y130653D01*
X288823Y130903D01*
X288448Y131153D01*
G01X289615Y132503D02*
X289823Y132753D01*
X289948Y133045D01*
X289990Y133420D01*
X289907Y133795D01*
X289740Y134087D01*
X289448Y134295D01*
X289115Y134337D01*
X288782Y134253D01*
X288573Y134045D01*
X288407Y133753D01*
X288365Y133462D01*
X288407Y133170D01*
X288573Y132795D01*
X287490Y132920D01*
Y134045D01*
G01X289990Y136437D02*
X289448Y136520D01*
X288990Y136645D01*
X288573Y136812D01*
X288115Y137020D01*
X287490Y137353D01*
Y135687D01*
G01X290910Y220705D02*
X291243Y220497D01*
X291618Y220372D01*
X291952D01*
X292285Y220497D01*
X292535Y220705D01*
X292660Y220997D01*
X292577Y221289D01*
X292368Y221539D01*
X291993Y221705D01*
X291493Y221789D01*
X291202Y221955D01*
X291077Y222247D01*
X291160Y222539D01*
X291368Y222747D01*
X291660Y222872D01*
X291952D01*
X292243Y222789D01*
X292493Y222580D01*
G01X295802Y222664D02*
X295552Y222789D01*
X295260Y222872D01*
X294927D01*
X294552Y222747D01*
X294260Y222539D01*
X294052Y222289D01*
X293885Y221872D01*
X293843Y221497D01*
X293927Y221122D01*
X294052Y220872D01*
X294302Y220622D01*
X294593Y220455D01*
X294885Y220372D01*
X295177D01*
X295468Y220455D01*
X295718Y220580D01*
X295927Y220747D01*
G01X297277Y220664D02*
X297568Y220455D01*
X297902Y220372D01*
X298235Y220455D01*
X298527Y220705D01*
X298735Y221080D01*
X298818Y221455D01*
Y221914D01*
X298735Y222289D01*
X298527Y222622D01*
X298277Y222789D01*
X297985Y222872D01*
X297652Y222789D01*
X297402Y222622D01*
X297235Y222372D01*
X297152Y222039D01*
X297235Y221747D01*
X297443Y221455D01*
X297693Y221289D01*
X297985Y221247D01*
X298318Y221330D01*
X298568Y221539D01*
X298818Y221914D01*
G01X300293Y222455D02*
X300543Y222705D01*
X300835Y222830D01*
X301168Y222872D01*
X301585Y222789D01*
X301877Y222580D01*
X301960Y222330D01*
X301918Y222080D01*
X301752Y221872D01*
X300918Y221455D01*
X300543Y221164D01*
X300293Y220747D01*
X300210Y220372D01*
X301960D01*
G01X303477Y220664D02*
X303768Y220455D01*
X304102Y220372D01*
X304435Y220455D01*
X304727Y220705D01*
X304935Y221080D01*
X305018Y221455D01*
Y221914D01*
X304935Y222289D01*
X304727Y222622D01*
X304477Y222789D01*
X304185Y222872D01*
X303852Y222789D01*
X303602Y222622D01*
X303435Y222372D01*
X303352Y222039D01*
X303435Y221747D01*
X303643Y221455D01*
X303893Y221289D01*
X304185Y221247D01*
X304518Y221330D01*
X304768Y221539D01*
X305018Y221914D01*
G01X290854Y216333D02*
X291187Y216125D01*
X291562Y216000D01*
X291896D01*
X292229Y216125D01*
X292479Y216333D01*
X292604Y216625D01*
X292521Y216917D01*
X292312Y217167D01*
X291937Y217333D01*
X291437Y217417D01*
X291146Y217583D01*
X291021Y217875D01*
X291104Y218167D01*
X291312Y218375D01*
X291604Y218500D01*
X291896D01*
X292187Y218417D01*
X292437Y218208D01*
G01X295746Y218292D02*
X295496Y218417D01*
X295204Y218500D01*
X294871D01*
X294496Y218375D01*
X294204Y218167D01*
X293996Y217917D01*
X293829Y217500D01*
X293787Y217125D01*
X293871Y216750D01*
X293996Y216500D01*
X294246Y216250D01*
X294537Y216083D01*
X294829Y216000D01*
X295121D01*
X295412Y216083D01*
X295662Y216208D01*
X295871Y216375D01*
G01X297221Y216292D02*
X297512Y216083D01*
X297846Y216000D01*
X298179Y216083D01*
X298471Y216333D01*
X298679Y216708D01*
X298762Y217083D01*
Y217542D01*
X298679Y217917D01*
X298471Y218250D01*
X298221Y218417D01*
X297929Y218500D01*
X297596Y218417D01*
X297346Y218250D01*
X297179Y218000D01*
X297096Y217667D01*
X297179Y217375D01*
X297387Y217083D01*
X297637Y216917D01*
X297929Y216875D01*
X298262Y216958D01*
X298512Y217167D01*
X298762Y217542D01*
G01X300112Y216500D02*
X300362Y216208D01*
X300696Y216042D01*
X301071Y216000D01*
X301404Y216042D01*
X301737Y216250D01*
X301946Y216500D01*
X301987Y216750D01*
X301904Y217042D01*
X301612Y217250D01*
X301321Y217333D01*
X300946D01*
G01X301321D02*
X301571Y217458D01*
X301779Y217667D01*
X301862Y217917D01*
X301779Y218167D01*
X301571Y218375D01*
X301196Y218500D01*
X300821Y218458D01*
X300446Y218292D01*
G01X304129Y218500D02*
X303796Y218417D01*
X303546Y218208D01*
X303379Y217958D01*
X303254Y217625D01*
X303212Y217250D01*
X303254Y216875D01*
X303379Y216542D01*
X303546Y216292D01*
X303796Y216083D01*
X304129Y216000D01*
X304462Y216083D01*
X304712Y216292D01*
X304879Y216542D01*
X305004Y216875D01*
X305046Y217250D01*
X305004Y217625D01*
X304879Y217958D01*
X304712Y218208D01*
X304462Y218417D01*
X304129Y218500D01*
G01X286910Y227705D02*
X287243Y227497D01*
X287618Y227372D01*
X287952D01*
X288285Y227497D01*
X288535Y227705D01*
X288660Y227997D01*
X288577Y228289D01*
X288368Y228539D01*
X287993Y228705D01*
X287493Y228789D01*
X287202Y228955D01*
X287077Y229247D01*
X287160Y229539D01*
X287368Y229747D01*
X287660Y229872D01*
X287952D01*
X288243Y229789D01*
X288493Y229580D01*
G01X291802Y229664D02*
X291552Y229789D01*
X291260Y229872D01*
X290927D01*
X290552Y229747D01*
X290260Y229539D01*
X290052Y229289D01*
X289885Y228872D01*
X289843Y228497D01*
X289927Y228122D01*
X290052Y227872D01*
X290302Y227622D01*
X290593Y227455D01*
X290885Y227372D01*
X291177D01*
X291468Y227455D01*
X291718Y227580D01*
X291927Y227747D01*
G01X293277Y227664D02*
X293568Y227455D01*
X293902Y227372D01*
X294235Y227455D01*
X294527Y227705D01*
X294735Y228080D01*
X294818Y228455D01*
Y228914D01*
X294735Y229289D01*
X294527Y229622D01*
X294277Y229789D01*
X293985Y229872D01*
X293652Y229789D01*
X293402Y229622D01*
X293235Y229372D01*
X293152Y229039D01*
X293235Y228747D01*
X293443Y228455D01*
X293693Y228289D01*
X293985Y228247D01*
X294318Y228330D01*
X294568Y228539D01*
X294818Y228914D01*
G01X296293Y229455D02*
X296543Y229705D01*
X296835Y229830D01*
X297168Y229872D01*
X297585Y229789D01*
X297877Y229580D01*
X297960Y229330D01*
X297918Y229080D01*
X297752Y228872D01*
X296918Y228455D01*
X296543Y228164D01*
X296293Y227747D01*
X296210Y227372D01*
X297960D01*
G01X300102D02*
X300185Y227914D01*
X300310Y228372D01*
X300477Y228789D01*
X300685Y229247D01*
X301018Y229872D01*
X299352D01*
G01X286910Y235705D02*
X287243Y235497D01*
X287618Y235372D01*
X287952D01*
X288285Y235497D01*
X288535Y235705D01*
X288660Y235997D01*
X288577Y236289D01*
X288368Y236539D01*
X287993Y236705D01*
X287493Y236789D01*
X287202Y236955D01*
X287077Y237247D01*
X287160Y237539D01*
X287368Y237747D01*
X287660Y237872D01*
X287952D01*
X288243Y237789D01*
X288493Y237580D01*
G01X291802Y237664D02*
X291552Y237789D01*
X291260Y237872D01*
X290927D01*
X290552Y237747D01*
X290260Y237539D01*
X290052Y237289D01*
X289885Y236872D01*
X289843Y236497D01*
X289927Y236122D01*
X290052Y235872D01*
X290302Y235622D01*
X290593Y235455D01*
X290885Y235372D01*
X291177D01*
X291468Y235455D01*
X291718Y235580D01*
X291927Y235747D01*
G01X293277Y235664D02*
X293568Y235455D01*
X293902Y235372D01*
X294235Y235455D01*
X294527Y235705D01*
X294735Y236080D01*
X294818Y236455D01*
Y236914D01*
X294735Y237289D01*
X294527Y237622D01*
X294277Y237789D01*
X293985Y237872D01*
X293652Y237789D01*
X293402Y237622D01*
X293235Y237372D01*
X293152Y237039D01*
X293235Y236747D01*
X293443Y236455D01*
X293693Y236289D01*
X293985Y236247D01*
X294318Y236330D01*
X294568Y236539D01*
X294818Y236914D01*
G01X296293Y237455D02*
X296543Y237705D01*
X296835Y237830D01*
X297168Y237872D01*
X297585Y237789D01*
X297877Y237580D01*
X297960Y237330D01*
X297918Y237080D01*
X297752Y236872D01*
X296918Y236455D01*
X296543Y236164D01*
X296293Y235747D01*
X296210Y235372D01*
X297960D01*
G01X300185D02*
X300477Y235414D01*
X300810Y235539D01*
X301018Y235747D01*
X301102Y236039D01*
X301018Y236330D01*
X300768Y236580D01*
X300393Y236705D01*
X299977D01*
X299727Y236789D01*
X299518Y236997D01*
X299435Y237289D01*
X299560Y237580D01*
X299852Y237789D01*
X300185Y237872D01*
X300518Y237789D01*
X300810Y237580D01*
X300935Y237289D01*
X300852Y236997D01*
X300643Y236789D01*
X300393Y236705D01*
X299977D01*
X299602Y236580D01*
X299352Y236330D01*
X299268Y236039D01*
X299352Y235747D01*
X299560Y235539D01*
X299893Y235414D01*
X300185Y235372D01*
G01X299152Y240897D02*
X299360Y241230D01*
X299485Y241605D01*
Y241939D01*
X299360Y242272D01*
X299152Y242522D01*
X298860Y242647D01*
X298568Y242564D01*
X298318Y242355D01*
X298152Y241980D01*
X298068Y241480D01*
X297902Y241189D01*
X297610Y241064D01*
X297318Y241147D01*
X297110Y241355D01*
X296985Y241647D01*
Y241939D01*
X297068Y242230D01*
X297277Y242480D01*
G01X296985Y244039D02*
X299485D01*
Y245705D01*
G01X297402Y247180D02*
X297152Y247430D01*
X297027Y247722D01*
X296985Y248055D01*
X297068Y248472D01*
X297277Y248764D01*
X297527Y248847D01*
X297777Y248805D01*
X297985Y248639D01*
X298402Y247805D01*
X298693Y247430D01*
X299110Y247180D01*
X299485Y247097D01*
Y248847D01*
G01X286096Y241025D02*
X286304Y241358D01*
X286429Y241733D01*
Y242067D01*
X286304Y242400D01*
X286096Y242650D01*
X285804Y242775D01*
X285512Y242692D01*
X285262Y242483D01*
X285096Y242108D01*
X285012Y241608D01*
X284846Y241317D01*
X284554Y241192D01*
X284262Y241275D01*
X284054Y241483D01*
X283929Y241775D01*
Y242067D01*
X284012Y242358D01*
X284221Y242608D01*
G01X283929Y244167D02*
X286429D01*
Y245833D01*
G01X286054Y247183D02*
X286262Y247433D01*
X286387Y247725D01*
X286429Y248100D01*
X286346Y248475D01*
X286179Y248767D01*
X285887Y248975D01*
X285554Y249017D01*
X285221Y248933D01*
X285012Y248725D01*
X284846Y248433D01*
X284804Y248142D01*
X284846Y247850D01*
X285012Y247475D01*
X283929Y247600D01*
Y248725D01*
G01X295152Y241297D02*
X295360Y241630D01*
X295485Y242005D01*
Y242339D01*
X295360Y242672D01*
X295152Y242922D01*
X294860Y243047D01*
X294568Y242964D01*
X294318Y242755D01*
X294152Y242380D01*
X294068Y241880D01*
X293902Y241589D01*
X293610Y241464D01*
X293318Y241547D01*
X293110Y241755D01*
X292985Y242047D01*
Y242339D01*
X293068Y242630D01*
X293277Y242880D01*
G01X295485Y244439D02*
X292985D01*
Y245480D01*
X293110Y245814D01*
X293277Y246022D01*
X293610Y246105D01*
X293943Y246022D01*
X294152Y245772D01*
X294277Y245480D01*
Y244439D01*
G01Y245480D02*
X295485Y246105D01*
G01Y248289D02*
X294943Y248372D01*
X294485Y248497D01*
X294068Y248664D01*
X293610Y248872D01*
X292985Y249205D01*
Y247539D01*
G01X295485Y251472D02*
X292985D01*
X293485Y250972D01*
G01X295485D02*
Y251972D01*
G01X292985Y254572D02*
X293068Y254239D01*
X293277Y253989D01*
X293527Y253822D01*
X293860Y253697D01*
X294235Y253655D01*
X294610Y253697D01*
X294943Y253822D01*
X295193Y253989D01*
X295402Y254239D01*
X295485Y254572D01*
X295402Y254905D01*
X295193Y255155D01*
X294943Y255322D01*
X294610Y255447D01*
X294235Y255489D01*
X293860Y255447D01*
X293527Y255322D01*
X293277Y255155D01*
X293068Y254905D01*
X292985Y254572D01*
G01X290652Y241297D02*
X290860Y241630D01*
X290985Y242005D01*
Y242339D01*
X290860Y242672D01*
X290652Y242922D01*
X290360Y243047D01*
X290068Y242964D01*
X289818Y242755D01*
X289652Y242380D01*
X289568Y241880D01*
X289402Y241589D01*
X289110Y241464D01*
X288818Y241547D01*
X288610Y241755D01*
X288485Y242047D01*
Y242339D01*
X288568Y242630D01*
X288777Y242880D01*
G01X290985Y244439D02*
X288485D01*
Y245480D01*
X288610Y245814D01*
X288777Y246022D01*
X289110Y246105D01*
X289443Y246022D01*
X289652Y245772D01*
X289777Y245480D01*
Y244439D01*
G01Y245480D02*
X290985Y246105D01*
G01Y248289D02*
X290443Y248372D01*
X289985Y248497D01*
X289568Y248664D01*
X289110Y248872D01*
X288485Y249205D01*
Y247539D01*
G01X290985Y251472D02*
X288485D01*
X288985Y250972D01*
G01X290985D02*
Y251972D01*
G01X288902Y253780D02*
X288652Y254030D01*
X288527Y254322D01*
X288485Y254655D01*
X288568Y255072D01*
X288777Y255364D01*
X289027Y255447D01*
X289277Y255405D01*
X289485Y255239D01*
X289902Y254405D01*
X290193Y254030D01*
X290610Y253780D01*
X290985Y253697D01*
Y255447D01*
G01X296596Y256925D02*
X296804Y257258D01*
X296929Y257633D01*
Y257967D01*
X296804Y258300D01*
X296596Y258550D01*
X296304Y258675D01*
X296012Y258592D01*
X295762Y258383D01*
X295596Y258008D01*
X295512Y257508D01*
X295346Y257217D01*
X295054Y257092D01*
X294762Y257175D01*
X294554Y257383D01*
X294429Y257675D01*
Y257967D01*
X294512Y258258D01*
X294721Y258508D01*
G01X294637Y261817D02*
X294512Y261567D01*
X294429Y261275D01*
Y260942D01*
X294554Y260567D01*
X294762Y260275D01*
X295012Y260067D01*
X295429Y259900D01*
X295804Y259858D01*
X296179Y259942D01*
X296429Y260067D01*
X296679Y260317D01*
X296846Y260608D01*
X296929Y260900D01*
Y261192D01*
X296846Y261483D01*
X296721Y261733D01*
X296554Y261942D01*
G01X296637Y263292D02*
X296846Y263583D01*
X296929Y263917D01*
X296846Y264250D01*
X296596Y264542D01*
X296221Y264750D01*
X295846Y264833D01*
X295387D01*
X295012Y264750D01*
X294679Y264542D01*
X294512Y264292D01*
X294429Y264000D01*
X294512Y263667D01*
X294679Y263417D01*
X294929Y263250D01*
X295262Y263167D01*
X295554Y263250D01*
X295846Y263458D01*
X296012Y263708D01*
X296054Y264000D01*
X295971Y264333D01*
X295762Y264583D01*
X295387Y264833D01*
G01X296929Y267100D02*
X296887Y267392D01*
X296762Y267725D01*
X296554Y267933D01*
X296262Y268017D01*
X295971Y267933D01*
X295721Y267683D01*
X295596Y267308D01*
Y266892D01*
X295512Y266642D01*
X295304Y266433D01*
X295012Y266350D01*
X294721Y266475D01*
X294512Y266767D01*
X294429Y267100D01*
X294512Y267433D01*
X294721Y267725D01*
X295012Y267850D01*
X295304Y267767D01*
X295512Y267558D01*
X295596Y267308D01*
Y266892D01*
X295721Y266517D01*
X295971Y266267D01*
X296262Y266183D01*
X296554Y266267D01*
X296762Y266475D01*
X296887Y266808D01*
X296929Y267100D01*
G01X296429Y269283D02*
X296721Y269533D01*
X296887Y269867D01*
X296929Y270242D01*
X296887Y270575D01*
X296679Y270908D01*
X296429Y271117D01*
X296179Y271158D01*
X295887Y271075D01*
X295679Y270783D01*
X295596Y270492D01*
Y270117D01*
G01Y270492D02*
X295471Y270742D01*
X295262Y270950D01*
X295012Y271033D01*
X294762Y270950D01*
X294554Y270742D01*
X294429Y270367D01*
X294471Y269992D01*
X294637Y269617D01*
G01X296404Y319333D02*
X296737Y319125D01*
X297112Y319000D01*
X297446D01*
X297779Y319125D01*
X298029Y319333D01*
X298154Y319625D01*
X298071Y319917D01*
X297862Y320167D01*
X297487Y320333D01*
X296987Y320417D01*
X296696Y320583D01*
X296571Y320875D01*
X296654Y321167D01*
X296862Y321375D01*
X297154Y321500D01*
X297446D01*
X297737Y321417D01*
X297987Y321208D01*
G01X299546Y321500D02*
Y319000D01*
X301212D01*
G01X302687Y321083D02*
X302937Y321333D01*
X303229Y321458D01*
X303562Y321500D01*
X303979Y321417D01*
X304271Y321208D01*
X304354Y320958D01*
X304312Y320708D01*
X304146Y320500D01*
X303312Y320083D01*
X302937Y319792D01*
X302687Y319375D01*
X302604Y319000D01*
X304354D01*
G01X306579D02*
Y321500D01*
X306079Y321000D01*
G01Y319000D02*
X307079D01*
G01X294354Y314833D02*
X294687Y314625D01*
X295062Y314500D01*
X295396D01*
X295729Y314625D01*
X295979Y314833D01*
X296104Y315125D01*
X296021Y315417D01*
X295812Y315667D01*
X295437Y315833D01*
X294937Y315917D01*
X294646Y316083D01*
X294521Y316375D01*
X294604Y316667D01*
X294812Y316875D01*
X295104Y317000D01*
X295396D01*
X295687Y316917D01*
X295937Y316708D01*
G01X297496Y314500D02*
Y317000D01*
X298537D01*
X298871Y316875D01*
X299079Y316708D01*
X299162Y316375D01*
X299079Y316042D01*
X298829Y315833D01*
X298537Y315708D01*
X297496D01*
G01X298537D02*
X299162Y314500D01*
G01X301429D02*
X301721Y314542D01*
X302054Y314667D01*
X302262Y314875D01*
X302346Y315167D01*
X302262Y315458D01*
X302012Y315708D01*
X301637Y315833D01*
X301221D01*
X300971Y315917D01*
X300762Y316125D01*
X300679Y316417D01*
X300804Y316708D01*
X301096Y316917D01*
X301429Y317000D01*
X301762Y316917D01*
X302054Y316708D01*
X302179Y316417D01*
X302096Y316125D01*
X301887Y315917D01*
X301637Y315833D01*
X301221D01*
X300846Y315708D01*
X300596Y315458D01*
X300512Y315167D01*
X300596Y314875D01*
X300804Y314667D01*
X301137Y314542D01*
X301429Y314500D01*
G01X303612Y315000D02*
X303862Y314708D01*
X304196Y314542D01*
X304571Y314500D01*
X304904Y314542D01*
X305237Y314750D01*
X305446Y315000D01*
X305487Y315250D01*
X305404Y315542D01*
X305112Y315750D01*
X304821Y315833D01*
X304446D01*
G01X304821D02*
X305071Y315958D01*
X305279Y316167D01*
X305362Y316417D01*
X305279Y316667D01*
X305071Y316875D01*
X304696Y317000D01*
X304321Y316958D01*
X303946Y316792D01*
G01X307546Y314500D02*
X307629Y315042D01*
X307754Y315500D01*
X307921Y315917D01*
X308129Y316375D01*
X308462Y317000D01*
X306796D01*
G01X282904Y335333D02*
X283237Y335125D01*
X283612Y335000D01*
X283946D01*
X284279Y335125D01*
X284529Y335333D01*
X284654Y335625D01*
X284571Y335917D01*
X284362Y336167D01*
X283987Y336333D01*
X283487Y336417D01*
X283196Y336583D01*
X283071Y336875D01*
X283154Y337167D01*
X283362Y337375D01*
X283654Y337500D01*
X283946D01*
X284237Y337417D01*
X284487Y337208D01*
G01X286046Y337500D02*
Y335000D01*
X287712D01*
G01X289979D02*
Y337500D01*
X289479Y337000D01*
G01Y335000D02*
X290479D01*
G01X292287Y337083D02*
X292537Y337333D01*
X292829Y337458D01*
X293162Y337500D01*
X293579Y337417D01*
X293871Y337208D01*
X293954Y336958D01*
X293912Y336708D01*
X293746Y336500D01*
X292912Y336083D01*
X292537Y335792D01*
X292287Y335375D01*
X292204Y335000D01*
X293954D01*
G01X282404Y327333D02*
X282737Y327125D01*
X283112Y327000D01*
X283446D01*
X283779Y327125D01*
X284029Y327333D01*
X284154Y327625D01*
X284071Y327917D01*
X283862Y328167D01*
X283487Y328333D01*
X282987Y328417D01*
X282696Y328583D01*
X282571Y328875D01*
X282654Y329167D01*
X282862Y329375D01*
X283154Y329500D01*
X283446D01*
X283737Y329417D01*
X283987Y329208D01*
G01X285546Y329500D02*
Y327000D01*
X287212D01*
G01X289479D02*
Y329500D01*
X288979Y329000D01*
G01Y327000D02*
X289979D01*
G01X293079D02*
Y329500D01*
X291537Y327708D01*
X293621D01*
G01X282854Y331333D02*
X283187Y331125D01*
X283562Y331000D01*
X283896D01*
X284229Y331125D01*
X284479Y331333D01*
X284604Y331625D01*
X284521Y331917D01*
X284312Y332167D01*
X283937Y332333D01*
X283437Y332417D01*
X283146Y332583D01*
X283021Y332875D01*
X283104Y333167D01*
X283312Y333375D01*
X283604Y333500D01*
X283896D01*
X284187Y333417D01*
X284437Y333208D01*
G01X285996Y331000D02*
Y333500D01*
X287037D01*
X287371Y333375D01*
X287579Y333208D01*
X287662Y332875D01*
X287579Y332542D01*
X287329Y332333D01*
X287037Y332208D01*
X285996D01*
G01X287037D02*
X287662Y331000D01*
G01X289929D02*
X290221Y331042D01*
X290554Y331167D01*
X290762Y331375D01*
X290846Y331667D01*
X290762Y331958D01*
X290512Y332208D01*
X290137Y332333D01*
X289721D01*
X289471Y332417D01*
X289262Y332625D01*
X289179Y332917D01*
X289304Y333208D01*
X289596Y333417D01*
X289929Y333500D01*
X290262Y333417D01*
X290554Y333208D01*
X290679Y332917D01*
X290596Y332625D01*
X290387Y332417D01*
X290137Y332333D01*
X289721D01*
X289346Y332208D01*
X289096Y331958D01*
X289012Y331667D01*
X289096Y331375D01*
X289304Y331167D01*
X289637Y331042D01*
X289929Y331000D01*
G01X292112Y331500D02*
X292362Y331208D01*
X292696Y331042D01*
X293071Y331000D01*
X293404Y331042D01*
X293737Y331250D01*
X293946Y331500D01*
X293987Y331750D01*
X293904Y332042D01*
X293612Y332250D01*
X293321Y332333D01*
X292946D01*
G01X293321D02*
X293571Y332458D01*
X293779Y332667D01*
X293862Y332917D01*
X293779Y333167D01*
X293571Y333375D01*
X293196Y333500D01*
X292821Y333458D01*
X292446Y333292D01*
G01X296129Y333500D02*
X295796Y333417D01*
X295546Y333208D01*
X295379Y332958D01*
X295254Y332625D01*
X295212Y332250D01*
X295254Y331875D01*
X295379Y331542D01*
X295546Y331292D01*
X295796Y331083D01*
X296129Y331000D01*
X296462Y331083D01*
X296712Y331292D01*
X296879Y331542D01*
X297004Y331875D01*
X297046Y332250D01*
X297004Y332625D01*
X296879Y332958D01*
X296712Y333208D01*
X296462Y333417D01*
X296129Y333500D01*
G01X293854Y350333D02*
X294187Y350125D01*
X294562Y350000D01*
X294896D01*
X295229Y350125D01*
X295479Y350333D01*
X295604Y350625D01*
X295521Y350917D01*
X295312Y351167D01*
X294937Y351333D01*
X294437Y351417D01*
X294146Y351583D01*
X294021Y351875D01*
X294104Y352167D01*
X294312Y352375D01*
X294604Y352500D01*
X294896D01*
X295187Y352417D01*
X295437Y352208D01*
G01X296996Y350000D02*
Y352500D01*
X298037D01*
X298371Y352375D01*
X298579Y352208D01*
X298662Y351875D01*
X298579Y351542D01*
X298329Y351333D01*
X298037Y351208D01*
X296996D01*
G01X298037D02*
X298662Y350000D01*
G01X300929D02*
X301221Y350042D01*
X301554Y350167D01*
X301762Y350375D01*
X301846Y350667D01*
X301762Y350958D01*
X301512Y351208D01*
X301137Y351333D01*
X300721D01*
X300471Y351417D01*
X300262Y351625D01*
X300179Y351917D01*
X300304Y352208D01*
X300596Y352417D01*
X300929Y352500D01*
X301262Y352417D01*
X301554Y352208D01*
X301679Y351917D01*
X301596Y351625D01*
X301387Y351417D01*
X301137Y351333D01*
X300721D01*
X300346Y351208D01*
X300096Y350958D01*
X300012Y350667D01*
X300096Y350375D01*
X300304Y350167D01*
X300637Y350042D01*
X300929Y350000D01*
G01X303237Y352083D02*
X303487Y352333D01*
X303779Y352458D01*
X304112Y352500D01*
X304529Y352417D01*
X304821Y352208D01*
X304904Y351958D01*
X304862Y351708D01*
X304696Y351500D01*
X303862Y351083D01*
X303487Y350792D01*
X303237Y350375D01*
X303154Y350000D01*
X304904D01*
G01X307129D02*
X307421Y350042D01*
X307754Y350167D01*
X307962Y350375D01*
X308046Y350667D01*
X307962Y350958D01*
X307712Y351208D01*
X307337Y351333D01*
X306921D01*
X306671Y351417D01*
X306462Y351625D01*
X306379Y351917D01*
X306504Y352208D01*
X306796Y352417D01*
X307129Y352500D01*
X307462Y352417D01*
X307754Y352208D01*
X307879Y351917D01*
X307796Y351625D01*
X307587Y351417D01*
X307337Y351333D01*
X306921D01*
X306546Y351208D01*
X306296Y350958D01*
X306212Y350667D01*
X306296Y350375D01*
X306504Y350167D01*
X306837Y350042D01*
X307129Y350000D01*
G01X295404Y359333D02*
X295737Y359125D01*
X296112Y359000D01*
X296446D01*
X296779Y359125D01*
X297029Y359333D01*
X297154Y359625D01*
X297071Y359917D01*
X296862Y360167D01*
X296487Y360333D01*
X295987Y360417D01*
X295696Y360583D01*
X295571Y360875D01*
X295654Y361167D01*
X295862Y361375D01*
X296154Y361500D01*
X296446D01*
X296737Y361417D01*
X296987Y361208D01*
G01X298546Y361500D02*
Y359000D01*
X300212D01*
G01X301687Y361083D02*
X301937Y361333D01*
X302229Y361458D01*
X302562Y361500D01*
X302979Y361417D01*
X303271Y361208D01*
X303354Y360958D01*
X303312Y360708D01*
X303146Y360500D01*
X302312Y360083D01*
X301937Y359792D01*
X301687Y359375D01*
X301604Y359000D01*
X303354D01*
G01X304787Y361083D02*
X305037Y361333D01*
X305329Y361458D01*
X305662Y361500D01*
X306079Y361417D01*
X306371Y361208D01*
X306454Y360958D01*
X306412Y360708D01*
X306246Y360500D01*
X305412Y360083D01*
X305037Y359792D01*
X304787Y359375D01*
X304704Y359000D01*
X306454D01*
G01X293854Y354833D02*
X294187Y354625D01*
X294562Y354500D01*
X294896D01*
X295229Y354625D01*
X295479Y354833D01*
X295604Y355125D01*
X295521Y355417D01*
X295312Y355667D01*
X294937Y355833D01*
X294437Y355917D01*
X294146Y356083D01*
X294021Y356375D01*
X294104Y356667D01*
X294312Y356875D01*
X294604Y357000D01*
X294896D01*
X295187Y356917D01*
X295437Y356708D01*
G01X296996Y354500D02*
Y357000D01*
X298037D01*
X298371Y356875D01*
X298579Y356708D01*
X298662Y356375D01*
X298579Y356042D01*
X298329Y355833D01*
X298037Y355708D01*
X296996D01*
G01X298037D02*
X298662Y354500D01*
G01X300929D02*
X301221Y354542D01*
X301554Y354667D01*
X301762Y354875D01*
X301846Y355167D01*
X301762Y355458D01*
X301512Y355708D01*
X301137Y355833D01*
X300721D01*
X300471Y355917D01*
X300262Y356125D01*
X300179Y356417D01*
X300304Y356708D01*
X300596Y356917D01*
X300929Y357000D01*
X301262Y356917D01*
X301554Y356708D01*
X301679Y356417D01*
X301596Y356125D01*
X301387Y355917D01*
X301137Y355833D01*
X300721D01*
X300346Y355708D01*
X300096Y355458D01*
X300012Y355167D01*
X300096Y354875D01*
X300304Y354667D01*
X300637Y354542D01*
X300929Y354500D01*
G01X303112Y355000D02*
X303362Y354708D01*
X303696Y354542D01*
X304071Y354500D01*
X304404Y354542D01*
X304737Y354750D01*
X304946Y355000D01*
X304987Y355250D01*
X304904Y355542D01*
X304612Y355750D01*
X304321Y355833D01*
X303946D01*
G01X304321D02*
X304571Y355958D01*
X304779Y356167D01*
X304862Y356417D01*
X304779Y356667D01*
X304571Y356875D01*
X304196Y357000D01*
X303821Y356958D01*
X303446Y356792D01*
G01X307129Y354500D02*
X307421Y354542D01*
X307754Y354667D01*
X307962Y354875D01*
X308046Y355167D01*
X307962Y355458D01*
X307712Y355708D01*
X307337Y355833D01*
X306921D01*
X306671Y355917D01*
X306462Y356125D01*
X306379Y356417D01*
X306504Y356708D01*
X306796Y356917D01*
X307129Y357000D01*
X307462Y356917D01*
X307754Y356708D01*
X307879Y356417D01*
X307796Y356125D01*
X307587Y355917D01*
X307337Y355833D01*
X306921D01*
X306546Y355708D01*
X306296Y355458D01*
X306212Y355167D01*
X306296Y354875D01*
X306504Y354667D01*
X306837Y354542D01*
X307129Y354500D01*
G01X296222Y392375D02*
X296430Y392708D01*
X296555Y393083D01*
Y393417D01*
X296430Y393750D01*
X296222Y394000D01*
X295930Y394125D01*
X295638Y394042D01*
X295388Y393833D01*
X295222Y393458D01*
X295138Y392958D01*
X294972Y392667D01*
X294680Y392542D01*
X294388Y392625D01*
X294180Y392833D01*
X294055Y393125D01*
Y393417D01*
X294138Y393708D01*
X294347Y393958D01*
G01X294263Y397267D02*
X294138Y397017D01*
X294055Y396725D01*
Y396392D01*
X294180Y396017D01*
X294388Y395725D01*
X294638Y395517D01*
X295055Y395350D01*
X295430Y395308D01*
X295805Y395392D01*
X296055Y395517D01*
X296305Y395767D01*
X296472Y396058D01*
X296555Y396350D01*
Y396642D01*
X296472Y396933D01*
X296347Y397183D01*
X296180Y397392D01*
G01X296555Y399450D02*
X294055D01*
X294555Y398950D01*
G01X296555D02*
Y399950D01*
G01X294472Y401758D02*
X294222Y402008D01*
X294097Y402300D01*
X294055Y402633D01*
X294138Y403050D01*
X294347Y403342D01*
X294597Y403425D01*
X294847Y403383D01*
X295055Y403217D01*
X295472Y402383D01*
X295763Y402008D01*
X296180Y401758D01*
X296555Y401675D01*
Y403425D01*
G01X296055Y404733D02*
X296347Y404983D01*
X296513Y405317D01*
X296555Y405692D01*
X296513Y406025D01*
X296305Y406358D01*
X296055Y406567D01*
X295805Y406608D01*
X295513Y406525D01*
X295305Y406233D01*
X295222Y405942D01*
Y405567D01*
G01Y405942D02*
X295097Y406192D01*
X294888Y406400D01*
X294638Y406483D01*
X294388Y406400D01*
X294180Y406192D01*
X294055Y405817D01*
X294097Y405442D01*
X294263Y405067D01*
G01X295513Y407958D02*
X295222Y408250D01*
X295055Y408500D01*
X294972Y408833D01*
X295055Y409125D01*
X295222Y409333D01*
X295472Y409500D01*
X295763Y409542D01*
X296013Y409500D01*
X296263Y409333D01*
X296472Y409083D01*
X296555Y408792D01*
X296472Y408458D01*
X296222Y408167D01*
X295847Y408000D01*
X295430Y407958D01*
X294888Y408042D01*
X294597Y408167D01*
X294305Y408375D01*
X294097Y408667D01*
X294055Y408958D01*
X294138Y409250D01*
X294347Y409458D01*
G01X292222Y392375D02*
X292430Y392708D01*
X292555Y393083D01*
Y393417D01*
X292430Y393750D01*
X292222Y394000D01*
X291930Y394125D01*
X291638Y394042D01*
X291388Y393833D01*
X291222Y393458D01*
X291138Y392958D01*
X290972Y392667D01*
X290680Y392542D01*
X290388Y392625D01*
X290180Y392833D01*
X290055Y393125D01*
Y393417D01*
X290138Y393708D01*
X290347Y393958D01*
G01X290263Y397267D02*
X290138Y397017D01*
X290055Y396725D01*
Y396392D01*
X290180Y396017D01*
X290388Y395725D01*
X290638Y395517D01*
X291055Y395350D01*
X291430Y395308D01*
X291805Y395392D01*
X292055Y395517D01*
X292305Y395767D01*
X292472Y396058D01*
X292555Y396350D01*
Y396642D01*
X292472Y396933D01*
X292347Y397183D01*
X292180Y397392D01*
G01X292555Y399450D02*
X290055D01*
X290555Y398950D01*
G01X292555D02*
Y399950D01*
G01X290472Y401758D02*
X290222Y402008D01*
X290097Y402300D01*
X290055Y402633D01*
X290138Y403050D01*
X290347Y403342D01*
X290597Y403425D01*
X290847Y403383D01*
X291055Y403217D01*
X291472Y402383D01*
X291763Y402008D01*
X292180Y401758D01*
X292555Y401675D01*
Y403425D01*
G01X292055Y404733D02*
X292347Y404983D01*
X292513Y405317D01*
X292555Y405692D01*
X292513Y406025D01*
X292305Y406358D01*
X292055Y406567D01*
X291805Y406608D01*
X291513Y406525D01*
X291305Y406233D01*
X291222Y405942D01*
Y405567D01*
G01Y405942D02*
X291097Y406192D01*
X290888Y406400D01*
X290638Y406483D01*
X290388Y406400D01*
X290180Y406192D01*
X290055Y405817D01*
X290097Y405442D01*
X290263Y405067D01*
G01X290055Y408750D02*
X290138Y408417D01*
X290347Y408167D01*
X290597Y408000D01*
X290930Y407875D01*
X291305Y407833D01*
X291680Y407875D01*
X292013Y408000D01*
X292263Y408167D01*
X292472Y408417D01*
X292555Y408750D01*
X292472Y409083D01*
X292263Y409333D01*
X292013Y409500D01*
X291680Y409625D01*
X291305Y409667D01*
X290930Y409625D01*
X290597Y409500D01*
X290347Y409333D01*
X290138Y409083D01*
X290055Y408750D01*
G01X288222Y392375D02*
X288430Y392708D01*
X288555Y393083D01*
Y393417D01*
X288430Y393750D01*
X288222Y394000D01*
X287930Y394125D01*
X287638Y394042D01*
X287388Y393833D01*
X287222Y393458D01*
X287138Y392958D01*
X286972Y392667D01*
X286680Y392542D01*
X286388Y392625D01*
X286180Y392833D01*
X286055Y393125D01*
Y393417D01*
X286138Y393708D01*
X286347Y393958D01*
G01X286263Y397267D02*
X286138Y397017D01*
X286055Y396725D01*
Y396392D01*
X286180Y396017D01*
X286388Y395725D01*
X286638Y395517D01*
X287055Y395350D01*
X287430Y395308D01*
X287805Y395392D01*
X288055Y395517D01*
X288305Y395767D01*
X288472Y396058D01*
X288555Y396350D01*
Y396642D01*
X288472Y396933D01*
X288347Y397183D01*
X288180Y397392D01*
G01X288555Y399450D02*
X286055D01*
X286555Y398950D01*
G01X288555D02*
Y399950D01*
G01X286472Y401758D02*
X286222Y402008D01*
X286097Y402300D01*
X286055Y402633D01*
X286138Y403050D01*
X286347Y403342D01*
X286597Y403425D01*
X286847Y403383D01*
X287055Y403217D01*
X287472Y402383D01*
X287763Y402008D01*
X288180Y401758D01*
X288555Y401675D01*
Y403425D01*
G01X286472Y404858D02*
X286222Y405108D01*
X286097Y405400D01*
X286055Y405733D01*
X286138Y406150D01*
X286347Y406442D01*
X286597Y406525D01*
X286847Y406483D01*
X287055Y406317D01*
X287472Y405483D01*
X287763Y405108D01*
X288180Y404858D01*
X288555Y404775D01*
Y406525D01*
G01X288263Y408042D02*
X288472Y408333D01*
X288555Y408667D01*
X288472Y409000D01*
X288222Y409292D01*
X287847Y409500D01*
X287472Y409583D01*
X287013D01*
X286638Y409500D01*
X286305Y409292D01*
X286138Y409042D01*
X286055Y408750D01*
X286138Y408417D01*
X286305Y408167D01*
X286555Y408000D01*
X286888Y407917D01*
X287180Y408000D01*
X287472Y408208D01*
X287638Y408458D01*
X287680Y408750D01*
X287597Y409083D01*
X287388Y409333D01*
X287013Y409583D01*
G01X284222Y392375D02*
X284430Y392708D01*
X284555Y393083D01*
Y393417D01*
X284430Y393750D01*
X284222Y394000D01*
X283930Y394125D01*
X283638Y394042D01*
X283388Y393833D01*
X283222Y393458D01*
X283138Y392958D01*
X282972Y392667D01*
X282680Y392542D01*
X282388Y392625D01*
X282180Y392833D01*
X282055Y393125D01*
Y393417D01*
X282138Y393708D01*
X282347Y393958D01*
G01X282263Y397267D02*
X282138Y397017D01*
X282055Y396725D01*
Y396392D01*
X282180Y396017D01*
X282388Y395725D01*
X282638Y395517D01*
X283055Y395350D01*
X283430Y395308D01*
X283805Y395392D01*
X284055Y395517D01*
X284305Y395767D01*
X284472Y396058D01*
X284555Y396350D01*
Y396642D01*
X284472Y396933D01*
X284347Y397183D01*
X284180Y397392D01*
G01X284555Y399450D02*
X282055D01*
X282555Y398950D01*
G01X284555D02*
Y399950D01*
G01X282472Y401758D02*
X282222Y402008D01*
X282097Y402300D01*
X282055Y402633D01*
X282138Y403050D01*
X282347Y403342D01*
X282597Y403425D01*
X282847Y403383D01*
X283055Y403217D01*
X283472Y402383D01*
X283763Y402008D01*
X284180Y401758D01*
X284555Y401675D01*
Y403425D01*
G01X282472Y404858D02*
X282222Y405108D01*
X282097Y405400D01*
X282055Y405733D01*
X282138Y406150D01*
X282347Y406442D01*
X282597Y406525D01*
X282847Y406483D01*
X283055Y406317D01*
X283472Y405483D01*
X283763Y405108D01*
X284180Y404858D01*
X284555Y404775D01*
Y406525D01*
G01Y408750D02*
X284513Y409042D01*
X284388Y409375D01*
X284180Y409583D01*
X283888Y409667D01*
X283597Y409583D01*
X283347Y409333D01*
X283222Y408958D01*
Y408542D01*
X283138Y408292D01*
X282930Y408083D01*
X282638Y408000D01*
X282347Y408125D01*
X282138Y408417D01*
X282055Y408750D01*
X282138Y409083D01*
X282347Y409375D01*
X282638Y409500D01*
X282930Y409417D01*
X283138Y409208D01*
X283222Y408958D01*
Y408542D01*
X283347Y408167D01*
X283597Y407917D01*
X283888Y407833D01*
X284180Y407917D01*
X284388Y408125D01*
X284513Y408458D01*
X284555Y408750D01*
G01X289459Y421678D02*
Y417678D01*
X296859D01*
G01X283159Y423978D02*
Y437378D01*
G01X298159Y423978D02*
X283159D01*
G01X281659Y424178D02*
Y437178D01*
G01X286067Y444500D02*
Y447000D01*
X287067D01*
X287400Y446875D01*
X287650Y446583D01*
X287733Y446250D01*
X287650Y445917D01*
X287442Y445667D01*
X287067Y445542D01*
X286067D01*
G01X290000Y444500D02*
X289667Y444542D01*
X289375Y444708D01*
X289125Y444958D01*
X288958Y445250D01*
X288875Y445583D01*
Y445917D01*
X288958Y446250D01*
X289125Y446542D01*
X289375Y446792D01*
X289667Y446958D01*
X290000Y447000D01*
X290333Y446958D01*
X290625Y446792D01*
X290875Y446542D01*
X291042Y446250D01*
X291125Y445917D01*
Y445583D01*
X291042Y445250D01*
X290875Y444958D01*
X290625Y444708D01*
X290333Y444542D01*
X290000Y444500D01*
G01X290333Y445167D02*
X290833Y444500D01*
G01X292183Y445000D02*
X292433Y444708D01*
X292767Y444542D01*
X293142Y444500D01*
X293475Y444542D01*
X293808Y444750D01*
X294017Y445000D01*
X294058Y445250D01*
X293975Y445542D01*
X293683Y445750D01*
X293392Y445833D01*
X293017D01*
G01X293392D02*
X293642Y445958D01*
X293850Y446167D01*
X293933Y446417D01*
X293850Y446667D01*
X293642Y446875D01*
X293267Y447000D01*
X292892Y446958D01*
X292517Y446792D01*
G01X283159Y437378D02*
X298159D01*
G01X282967Y440500D02*
Y443000D01*
X283967D01*
X284300Y442875D01*
X284550Y442583D01*
X284633Y442250D01*
X284550Y441917D01*
X284342Y441667D01*
X283967Y441542D01*
X282967D01*
G01X286067Y440500D02*
Y443000D01*
X287108D01*
X287442Y442875D01*
X287650Y442708D01*
X287733Y442375D01*
X287650Y442042D01*
X287400Y441833D01*
X287108Y441708D01*
X286067D01*
G01X287108D02*
X287733Y440500D01*
G01X290000D02*
Y443000D01*
X289500Y442500D01*
G01Y440500D02*
X290500D01*
G01X292308Y441542D02*
X292600Y441833D01*
X292850Y442000D01*
X293183Y442083D01*
X293475Y442000D01*
X293683Y441833D01*
X293850Y441583D01*
X293892Y441292D01*
X293850Y441042D01*
X293683Y440792D01*
X293433Y440583D01*
X293142Y440500D01*
X292808Y440583D01*
X292517Y440833D01*
X292350Y441208D01*
X292308Y441625D01*
X292392Y442167D01*
X292517Y442458D01*
X292725Y442750D01*
X293017Y442958D01*
X293308Y443000D01*
X293600Y442917D01*
X293808Y442708D01*
G01X296200Y440500D02*
X296492Y440542D01*
X296825Y440667D01*
X297033Y440875D01*
X297117Y441167D01*
X297033Y441458D01*
X296783Y441708D01*
X296408Y441833D01*
X295992D01*
X295742Y441917D01*
X295533Y442125D01*
X295450Y442417D01*
X295575Y442708D01*
X295867Y442917D01*
X296200Y443000D01*
X296533Y442917D01*
X296825Y442708D01*
X296950Y442417D01*
X296867Y442125D01*
X296658Y441917D01*
X296408Y441833D01*
X295992D01*
X295617Y441708D01*
X295367Y441458D01*
X295283Y441167D01*
X295367Y440875D01*
X295575Y440667D01*
X295908Y440542D01*
X296200Y440500D01*
G01X296930Y451333D02*
X297263Y451125D01*
X297638Y451000D01*
X297972D01*
X298305Y451125D01*
X298555Y451333D01*
X298680Y451625D01*
X298597Y451917D01*
X298388Y452167D01*
X298013Y452333D01*
X297513Y452417D01*
X297222Y452583D01*
X297097Y452875D01*
X297180Y453167D01*
X297388Y453375D01*
X297680Y453500D01*
X297972D01*
X298263Y453417D01*
X298513Y453208D01*
G01X301822Y453292D02*
X301572Y453417D01*
X301280Y453500D01*
X300947D01*
X300572Y453375D01*
X300280Y453167D01*
X300072Y452917D01*
X299905Y452500D01*
X299863Y452125D01*
X299947Y451750D01*
X300072Y451500D01*
X300322Y451250D01*
X300613Y451083D01*
X300905Y451000D01*
X301197D01*
X301488Y451083D01*
X301738Y451208D01*
X301947Y451375D01*
G01X304005Y451000D02*
Y453500D01*
X303505Y453000D01*
G01Y451000D02*
X304505D01*
G01X306313Y453083D02*
X306563Y453333D01*
X306855Y453458D01*
X307188Y453500D01*
X307605Y453417D01*
X307897Y453208D01*
X307980Y452958D01*
X307938Y452708D01*
X307772Y452500D01*
X306938Y452083D01*
X306563Y451792D01*
X306313Y451375D01*
X306230Y451000D01*
X307980D01*
G01X310205D02*
X310497Y451042D01*
X310830Y451167D01*
X311038Y451375D01*
X311122Y451667D01*
X311038Y451958D01*
X310788Y452208D01*
X310413Y452333D01*
X309997D01*
X309747Y452417D01*
X309538Y452625D01*
X309455Y452917D01*
X309580Y453208D01*
X309872Y453417D01*
X310205Y453500D01*
X310538Y453417D01*
X310830Y453208D01*
X310955Y452917D01*
X310872Y452625D01*
X310663Y452417D01*
X310413Y452333D01*
X309997D01*
X309622Y452208D01*
X309372Y451958D01*
X309288Y451667D01*
X309372Y451375D01*
X309580Y451167D01*
X309913Y451042D01*
X310205Y451000D01*
G01X313805D02*
Y453500D01*
X312263Y451708D01*
X314347D01*
G01X297448Y465616D02*
X297781Y465408D01*
X298156Y465283D01*
X298490D01*
X298823Y465408D01*
X299073Y465616D01*
X299198Y465908D01*
X299115Y466200D01*
X298906Y466450D01*
X298531Y466616D01*
X298031Y466700D01*
X297740Y466866D01*
X297615Y467158D01*
X297698Y467450D01*
X297906Y467658D01*
X298198Y467783D01*
X298490D01*
X298781Y467700D01*
X299031Y467491D01*
G01X300590Y465283D02*
Y467783D01*
X301631D01*
X301965Y467658D01*
X302173Y467491D01*
X302256Y467158D01*
X302173Y466825D01*
X301923Y466616D01*
X301631Y466491D01*
X300590D01*
G01X301631D02*
X302256Y465283D01*
G01X304440D02*
X304523Y465825D01*
X304648Y466283D01*
X304815Y466700D01*
X305023Y467158D01*
X305356Y467783D01*
X303690D01*
G01X306706Y465658D02*
X306956Y465450D01*
X307248Y465325D01*
X307623Y465283D01*
X307998Y465366D01*
X308290Y465533D01*
X308498Y465825D01*
X308540Y466158D01*
X308456Y466491D01*
X308248Y466700D01*
X307956Y466866D01*
X307665Y466908D01*
X307373Y466866D01*
X306998Y466700D01*
X307123Y467783D01*
X308248D01*
G01X309806Y465658D02*
X310056Y465450D01*
X310348Y465325D01*
X310723Y465283D01*
X311098Y465366D01*
X311390Y465533D01*
X311598Y465825D01*
X311640Y466158D01*
X311556Y466491D01*
X311348Y466700D01*
X311056Y466866D01*
X310765Y466908D01*
X310473Y466866D01*
X310098Y466700D01*
X310223Y467783D01*
X311348D01*
G01X297448Y461116D02*
X297781Y460908D01*
X298156Y460783D01*
X298490D01*
X298823Y460908D01*
X299073Y461116D01*
X299198Y461408D01*
X299115Y461700D01*
X298906Y461950D01*
X298531Y462116D01*
X298031Y462200D01*
X297740Y462366D01*
X297615Y462658D01*
X297698Y462950D01*
X297906Y463158D01*
X298198Y463283D01*
X298490D01*
X298781Y463200D01*
X299031Y462991D01*
G01X300590Y460783D02*
Y463283D01*
X301631D01*
X301965Y463158D01*
X302173Y462991D01*
X302256Y462658D01*
X302173Y462325D01*
X301923Y462116D01*
X301631Y461991D01*
X300590D01*
G01X301631D02*
X302256Y460783D01*
G01X304440D02*
X304523Y461325D01*
X304648Y461783D01*
X304815Y462200D01*
X305023Y462658D01*
X305356Y463283D01*
X303690D01*
G01X306706Y461158D02*
X306956Y460950D01*
X307248Y460825D01*
X307623Y460783D01*
X307998Y460866D01*
X308290Y461033D01*
X308498Y461325D01*
X308540Y461658D01*
X308456Y461991D01*
X308248Y462200D01*
X307956Y462366D01*
X307665Y462408D01*
X307373Y462366D01*
X306998Y462200D01*
X307123Y463283D01*
X308248D01*
G01X309931Y461825D02*
X310223Y462116D01*
X310473Y462283D01*
X310806Y462366D01*
X311098Y462283D01*
X311306Y462116D01*
X311473Y461866D01*
X311515Y461575D01*
X311473Y461325D01*
X311306Y461075D01*
X311056Y460866D01*
X310765Y460783D01*
X310431Y460866D01*
X310140Y461116D01*
X309973Y461491D01*
X309931Y461908D01*
X310015Y462450D01*
X310140Y462741D01*
X310348Y463033D01*
X310640Y463241D01*
X310931Y463283D01*
X311223Y463200D01*
X311431Y462991D01*
G01X296980Y456333D02*
X297313Y456125D01*
X297688Y456000D01*
X298022D01*
X298355Y456125D01*
X298605Y456333D01*
X298730Y456625D01*
X298647Y456917D01*
X298438Y457167D01*
X298063Y457333D01*
X297563Y457417D01*
X297272Y457583D01*
X297147Y457875D01*
X297230Y458167D01*
X297438Y458375D01*
X297730Y458500D01*
X298022D01*
X298313Y458417D01*
X298563Y458208D01*
G01X300122Y456000D02*
Y458500D01*
X301163D01*
X301497Y458375D01*
X301705Y458208D01*
X301788Y457875D01*
X301705Y457542D01*
X301455Y457333D01*
X301163Y457208D01*
X300122D01*
G01X301163D02*
X301788Y456000D01*
G01X303972D02*
X304055Y456542D01*
X304180Y457000D01*
X304347Y457417D01*
X304555Y457875D01*
X304888Y458500D01*
X303222D01*
G01X306238Y456375D02*
X306488Y456167D01*
X306780Y456042D01*
X307155Y456000D01*
X307530Y456083D01*
X307822Y456250D01*
X308030Y456542D01*
X308072Y456875D01*
X307988Y457208D01*
X307780Y457417D01*
X307488Y457583D01*
X307197Y457625D01*
X306905Y457583D01*
X306530Y457417D01*
X306655Y458500D01*
X307780D01*
G01X310755Y456000D02*
Y458500D01*
X309213Y456708D01*
X311297D01*
G01X297448Y478616D02*
X297781Y478408D01*
X298156Y478283D01*
X298490D01*
X298823Y478408D01*
X299073Y478616D01*
X299198Y478908D01*
X299115Y479200D01*
X298906Y479450D01*
X298531Y479616D01*
X298031Y479700D01*
X297740Y479866D01*
X297615Y480158D01*
X297698Y480450D01*
X297906Y480658D01*
X298198Y480783D01*
X298490D01*
X298781Y480700D01*
X299031Y480491D01*
G01X300590Y478283D02*
Y480783D01*
X301631D01*
X301965Y480658D01*
X302173Y480491D01*
X302256Y480158D01*
X302173Y479825D01*
X301923Y479616D01*
X301631Y479491D01*
X300590D01*
G01X301631D02*
X302256Y478283D01*
G01X304440D02*
X304523Y478825D01*
X304648Y479283D01*
X304815Y479700D01*
X305023Y480158D01*
X305356Y480783D01*
X303690D01*
G01X308123Y478283D02*
Y480783D01*
X306581Y478991D01*
X308665D01*
G01X310723Y480783D02*
X310390Y480700D01*
X310140Y480491D01*
X309973Y480241D01*
X309848Y479908D01*
X309806Y479533D01*
X309848Y479158D01*
X309973Y478825D01*
X310140Y478575D01*
X310390Y478366D01*
X310723Y478283D01*
X311056Y478366D01*
X311306Y478575D01*
X311473Y478825D01*
X311598Y479158D01*
X311640Y479533D01*
X311598Y479908D01*
X311473Y480241D01*
X311306Y480491D01*
X311056Y480700D01*
X310723Y480783D01*
G01X297448Y474116D02*
X297781Y473908D01*
X298156Y473783D01*
X298490D01*
X298823Y473908D01*
X299073Y474116D01*
X299198Y474408D01*
X299115Y474700D01*
X298906Y474950D01*
X298531Y475116D01*
X298031Y475200D01*
X297740Y475366D01*
X297615Y475658D01*
X297698Y475950D01*
X297906Y476158D01*
X298198Y476283D01*
X298490D01*
X298781Y476200D01*
X299031Y475991D01*
G01X300590Y473783D02*
Y476283D01*
X301631D01*
X301965Y476158D01*
X302173Y475991D01*
X302256Y475658D01*
X302173Y475325D01*
X301923Y475116D01*
X301631Y474991D01*
X300590D01*
G01X301631D02*
X302256Y473783D01*
G01X304440D02*
X304523Y474325D01*
X304648Y474783D01*
X304815Y475200D01*
X305023Y475658D01*
X305356Y476283D01*
X303690D01*
G01X308123Y473783D02*
Y476283D01*
X306581Y474491D01*
X308665D01*
G01X310723Y473783D02*
Y476283D01*
X310223Y475783D01*
G01Y473783D02*
X311223D01*
G01X295930Y483833D02*
X296263Y483625D01*
X296638Y483500D01*
X296972D01*
X297305Y483625D01*
X297555Y483833D01*
X297680Y484125D01*
X297597Y484417D01*
X297388Y484667D01*
X297013Y484833D01*
X296513Y484917D01*
X296222Y485083D01*
X296097Y485375D01*
X296180Y485667D01*
X296388Y485875D01*
X296680Y486000D01*
X296972D01*
X297263Y485917D01*
X297513Y485708D01*
G01X300822Y485792D02*
X300572Y485917D01*
X300280Y486000D01*
X299947D01*
X299572Y485875D01*
X299280Y485667D01*
X299072Y485417D01*
X298905Y485000D01*
X298863Y484625D01*
X298947Y484250D01*
X299072Y484000D01*
X299322Y483750D01*
X299613Y483583D01*
X299905Y483500D01*
X300197D01*
X300488Y483583D01*
X300738Y483708D01*
X300947Y483875D01*
G01X303005Y483500D02*
Y486000D01*
X302505Y485500D01*
G01Y483500D02*
X303505D01*
G01X306105D02*
Y486000D01*
X305605Y485500D01*
G01Y483500D02*
X306605D01*
G01X309205Y486000D02*
X308872Y485917D01*
X308622Y485708D01*
X308455Y485458D01*
X308330Y485125D01*
X308288Y484750D01*
X308330Y484375D01*
X308455Y484042D01*
X308622Y483792D01*
X308872Y483583D01*
X309205Y483500D01*
X309538Y483583D01*
X309788Y483792D01*
X309955Y484042D01*
X310080Y484375D01*
X310122Y484750D01*
X310080Y485125D01*
X309955Y485458D01*
X309788Y485708D01*
X309538Y485917D01*
X309205Y486000D01*
G01X311513Y484542D02*
X311805Y484833D01*
X312055Y485000D01*
X312388Y485083D01*
X312680Y485000D01*
X312888Y484833D01*
X313055Y484583D01*
X313097Y484292D01*
X313055Y484042D01*
X312888Y483792D01*
X312638Y483583D01*
X312347Y483500D01*
X312013Y483583D01*
X311722Y483833D01*
X311555Y484208D01*
X311513Y484625D01*
X311597Y485167D01*
X311722Y485458D01*
X311930Y485750D01*
X312222Y485958D01*
X312513Y486000D01*
X312805Y485917D01*
X313013Y485708D01*
G01X294223Y497283D02*
Y553883D01*
G01X289500Y892983D02*
X287000D01*
Y893817D01*
X287125Y894150D01*
X287292Y894400D01*
X287542Y894608D01*
X287833Y894775D01*
X288250Y894817D01*
X288667Y894775D01*
X288958Y894608D01*
X289208Y894400D01*
X289375Y894150D01*
X289500Y893817D01*
Y892983D01*
G01X289000Y896083D02*
X289292Y896333D01*
X289458Y896667D01*
X289500Y897042D01*
X289458Y897375D01*
X289250Y897708D01*
X289000Y897917D01*
X288750Y897958D01*
X288458Y897875D01*
X288250Y897583D01*
X288167Y897292D01*
Y896917D01*
G01Y897292D02*
X288042Y897542D01*
X287833Y897750D01*
X287583Y897833D01*
X287333Y897750D01*
X287125Y897542D01*
X287000Y897167D01*
X287042Y896792D01*
X287208Y896417D01*
G01X288458Y899308D02*
X288167Y899600D01*
X288000Y899850D01*
X287917Y900183D01*
X288000Y900475D01*
X288167Y900683D01*
X288417Y900850D01*
X288708Y900892D01*
X288958Y900850D01*
X289208Y900683D01*
X289417Y900433D01*
X289500Y900142D01*
X289417Y899808D01*
X289167Y899517D01*
X288792Y899350D01*
X288375Y899308D01*
X287833Y899392D01*
X287542Y899517D01*
X287250Y899725D01*
X287042Y900017D01*
X287000Y900308D01*
X287083Y900600D01*
X287292Y900808D01*
G01X284500Y892967D02*
X282000D01*
Y894008D01*
X282125Y894342D01*
X282292Y894550D01*
X282625Y894633D01*
X282958Y894550D01*
X283167Y894300D01*
X283292Y894008D01*
Y892967D01*
G01Y894008D02*
X284500Y894633D01*
G01X282417Y896108D02*
X282167Y896358D01*
X282042Y896650D01*
X282000Y896983D01*
X282083Y897400D01*
X282292Y897692D01*
X282542Y897775D01*
X282792Y897733D01*
X283000Y897567D01*
X283417Y896733D01*
X283708Y896358D01*
X284125Y896108D01*
X284500Y896025D01*
Y897775D01*
G01Y900000D02*
X282000D01*
X282500Y899500D01*
G01X284500D02*
Y900500D01*
G01Y903100D02*
X282000D01*
X282500Y902600D01*
G01X284500D02*
Y903600D01*
G01Y906200D02*
X282000D01*
X282500Y905700D01*
G01X284500D02*
Y906700D01*
G01X294000Y892967D02*
X291500D01*
Y894008D01*
X291625Y894342D01*
X291792Y894550D01*
X292125Y894633D01*
X292458Y894550D01*
X292667Y894300D01*
X292792Y894008D01*
Y892967D01*
G01Y894008D02*
X294000Y894633D01*
G01X291917Y896108D02*
X291667Y896358D01*
X291542Y896650D01*
X291500Y896983D01*
X291583Y897400D01*
X291792Y897692D01*
X292042Y897775D01*
X292292Y897733D01*
X292500Y897567D01*
X292917Y896733D01*
X293208Y896358D01*
X293625Y896108D01*
X294000Y896025D01*
Y897775D01*
G01Y900000D02*
X291500D01*
X292000Y899500D01*
G01X294000D02*
Y900500D01*
G01Y903100D02*
X291500D01*
X292000Y902600D01*
G01X294000D02*
Y903600D01*
G01Y906700D02*
X291500D01*
X293292Y905158D01*
Y907242D01*
G01X321800Y23100D02*
X299200D01*
G01Y12900D02*
X321800D01*
G01X299200Y23100D02*
Y12900D01*
G01X321800Y23100D02*
X299200D01*
G01Y12900D02*
X321800D01*
G01X299200Y23100D02*
Y12900D01*
G01X301800Y23500D02*
Y31500D01*
G01X307300Y23500D02*
X301800D01*
G01Y40200D02*
X307300D01*
G01X301800Y32200D02*
Y40200D01*
G01X307300Y32200D02*
X301800D01*
G01Y31500D02*
X307300D01*
G01X301800Y48800D02*
X307300D01*
G01X301800Y40800D02*
Y48800D01*
G01X307300Y40800D02*
X301800D01*
G01X304000Y51467D02*
X301500D01*
Y52467D01*
X301625Y52800D01*
X301917Y53050D01*
X302250Y53133D01*
X302583Y53050D01*
X302833Y52842D01*
X302958Y52467D01*
Y51467D01*
G01X301708Y56317D02*
X301583Y56067D01*
X301500Y55775D01*
Y55442D01*
X301625Y55067D01*
X301833Y54775D01*
X302083Y54567D01*
X302500Y54400D01*
X302875Y54358D01*
X303250Y54442D01*
X303500Y54567D01*
X303750Y54817D01*
X303917Y55108D01*
X304000Y55400D01*
Y55692D01*
X303917Y55983D01*
X303792Y56233D01*
X303625Y56442D01*
G01X301917Y57708D02*
X301667Y57958D01*
X301542Y58250D01*
X301500Y58583D01*
X301583Y59000D01*
X301792Y59292D01*
X302042Y59375D01*
X302292Y59333D01*
X302500Y59167D01*
X302917Y58333D01*
X303208Y57958D01*
X303625Y57708D01*
X304000Y57625D01*
Y59375D01*
G01Y61600D02*
X301500D01*
X302000Y61100D01*
G01X304000D02*
Y62100D01*
G01X301500Y64700D02*
X301583Y64367D01*
X301792Y64117D01*
X302042Y63950D01*
X302375Y63825D01*
X302750Y63783D01*
X303125Y63825D01*
X303458Y63950D01*
X303708Y64117D01*
X303917Y64367D01*
X304000Y64700D01*
X303917Y65033D01*
X303708Y65283D01*
X303458Y65450D01*
X303125Y65575D01*
X302750Y65617D01*
X302375Y65575D01*
X302042Y65450D01*
X301792Y65283D01*
X301583Y65033D01*
X301500Y64700D01*
G01X314814Y70340D02*
X312814D01*
G01X298500Y85800D02*
X302500D01*
Y93200D01*
G01X303000Y85800D02*
X307000D01*
Y93200D01*
G01X298300Y128500D02*
Y122300D01*
X310700D01*
Y128500D01*
G01X311800D02*
Y122300D01*
X324200D01*
Y128500D01*
G01X310700Y134500D02*
Y140700D01*
X298300D01*
Y134500D01*
G01X324200D02*
Y140700D01*
X311800D01*
Y134500D01*
G01X312854Y147833D02*
X313187Y147625D01*
X313562Y147500D01*
X313896D01*
X314229Y147625D01*
X314479Y147833D01*
X314604Y148125D01*
X314521Y148417D01*
X314312Y148667D01*
X313937Y148833D01*
X313437Y148917D01*
X313146Y149083D01*
X313021Y149375D01*
X313104Y149667D01*
X313312Y149875D01*
X313604Y150000D01*
X313896D01*
X314187Y149917D01*
X314437Y149708D01*
G01X317746Y149792D02*
X317496Y149917D01*
X317204Y150000D01*
X316871D01*
X316496Y149875D01*
X316204Y149667D01*
X315996Y149417D01*
X315829Y149000D01*
X315787Y148625D01*
X315871Y148250D01*
X315996Y148000D01*
X316246Y147750D01*
X316537Y147583D01*
X316829Y147500D01*
X317121D01*
X317412Y147583D01*
X317662Y147708D01*
X317871Y147875D01*
G01X319929Y147500D02*
X320221Y147542D01*
X320554Y147667D01*
X320762Y147875D01*
X320846Y148167D01*
X320762Y148458D01*
X320512Y148708D01*
X320137Y148833D01*
X319721D01*
X319471Y148917D01*
X319262Y149125D01*
X319179Y149417D01*
X319304Y149708D01*
X319596Y149917D01*
X319929Y150000D01*
X320262Y149917D01*
X320554Y149708D01*
X320679Y149417D01*
X320596Y149125D01*
X320387Y148917D01*
X320137Y148833D01*
X319721D01*
X319346Y148708D01*
X319096Y148458D01*
X319012Y148167D01*
X319096Y147875D01*
X319304Y147667D01*
X319637Y147542D01*
X319929Y147500D01*
G01X322946D02*
X323029Y148042D01*
X323154Y148500D01*
X323321Y148917D01*
X323529Y149375D01*
X323862Y150000D01*
X322196D01*
G01X326129Y147500D02*
X326421Y147542D01*
X326754Y147667D01*
X326962Y147875D01*
X327046Y148167D01*
X326962Y148458D01*
X326712Y148708D01*
X326337Y148833D01*
X325921D01*
X325671Y148917D01*
X325462Y149125D01*
X325379Y149417D01*
X325504Y149708D01*
X325796Y149917D01*
X326129Y150000D01*
X326462Y149917D01*
X326754Y149708D01*
X326879Y149417D01*
X326796Y149125D01*
X326587Y148917D01*
X326337Y148833D01*
X325921D01*
X325546Y148708D01*
X325296Y148458D01*
X325212Y148167D01*
X325296Y147875D01*
X325504Y147667D01*
X325837Y147542D01*
X326129Y147500D01*
G01X312854Y143833D02*
X313187Y143625D01*
X313562Y143500D01*
X313896D01*
X314229Y143625D01*
X314479Y143833D01*
X314604Y144125D01*
X314521Y144417D01*
X314312Y144667D01*
X313937Y144833D01*
X313437Y144917D01*
X313146Y145083D01*
X313021Y145375D01*
X313104Y145667D01*
X313312Y145875D01*
X313604Y146000D01*
X313896D01*
X314187Y145917D01*
X314437Y145708D01*
G01X317746Y145792D02*
X317496Y145917D01*
X317204Y146000D01*
X316871D01*
X316496Y145875D01*
X316204Y145667D01*
X315996Y145417D01*
X315829Y145000D01*
X315787Y144625D01*
X315871Y144250D01*
X315996Y144000D01*
X316246Y143750D01*
X316537Y143583D01*
X316829Y143500D01*
X317121D01*
X317412Y143583D01*
X317662Y143708D01*
X317871Y143875D01*
G01X319929Y143500D02*
X320221Y143542D01*
X320554Y143667D01*
X320762Y143875D01*
X320846Y144167D01*
X320762Y144458D01*
X320512Y144708D01*
X320137Y144833D01*
X319721D01*
X319471Y144917D01*
X319262Y145125D01*
X319179Y145417D01*
X319304Y145708D01*
X319596Y145917D01*
X319929Y146000D01*
X320262Y145917D01*
X320554Y145708D01*
X320679Y145417D01*
X320596Y145125D01*
X320387Y144917D01*
X320137Y144833D01*
X319721D01*
X319346Y144708D01*
X319096Y144458D01*
X319012Y144167D01*
X319096Y143875D01*
X319304Y143667D01*
X319637Y143542D01*
X319929Y143500D01*
G01X322946D02*
X323029Y144042D01*
X323154Y144500D01*
X323321Y144917D01*
X323529Y145375D01*
X323862Y146000D01*
X322196D01*
G01X325421Y143792D02*
X325712Y143583D01*
X326046Y143500D01*
X326379Y143583D01*
X326671Y143833D01*
X326879Y144208D01*
X326962Y144583D01*
Y145042D01*
X326879Y145417D01*
X326671Y145750D01*
X326421Y145917D01*
X326129Y146000D01*
X325796Y145917D01*
X325546Y145750D01*
X325379Y145500D01*
X325296Y145167D01*
X325379Y144875D01*
X325587Y144583D01*
X325837Y144417D01*
X326129Y144375D01*
X326462Y144458D01*
X326712Y144667D01*
X326962Y145042D01*
G01X312854Y151833D02*
X313187Y151625D01*
X313562Y151500D01*
X313896D01*
X314229Y151625D01*
X314479Y151833D01*
X314604Y152125D01*
X314521Y152417D01*
X314312Y152667D01*
X313937Y152833D01*
X313437Y152917D01*
X313146Y153083D01*
X313021Y153375D01*
X313104Y153667D01*
X313312Y153875D01*
X313604Y154000D01*
X313896D01*
X314187Y153917D01*
X314437Y153708D01*
G01X317746Y153792D02*
X317496Y153917D01*
X317204Y154000D01*
X316871D01*
X316496Y153875D01*
X316204Y153667D01*
X315996Y153417D01*
X315829Y153000D01*
X315787Y152625D01*
X315871Y152250D01*
X315996Y152000D01*
X316246Y151750D01*
X316537Y151583D01*
X316829Y151500D01*
X317121D01*
X317412Y151583D01*
X317662Y151708D01*
X317871Y151875D01*
G01X319929Y151500D02*
X320221Y151542D01*
X320554Y151667D01*
X320762Y151875D01*
X320846Y152167D01*
X320762Y152458D01*
X320512Y152708D01*
X320137Y152833D01*
X319721D01*
X319471Y152917D01*
X319262Y153125D01*
X319179Y153417D01*
X319304Y153708D01*
X319596Y153917D01*
X319929Y154000D01*
X320262Y153917D01*
X320554Y153708D01*
X320679Y153417D01*
X320596Y153125D01*
X320387Y152917D01*
X320137Y152833D01*
X319721D01*
X319346Y152708D01*
X319096Y152458D01*
X319012Y152167D01*
X319096Y151875D01*
X319304Y151667D01*
X319637Y151542D01*
X319929Y151500D01*
G01X323029D02*
X323321Y151542D01*
X323654Y151667D01*
X323862Y151875D01*
X323946Y152167D01*
X323862Y152458D01*
X323612Y152708D01*
X323237Y152833D01*
X322821D01*
X322571Y152917D01*
X322362Y153125D01*
X322279Y153417D01*
X322404Y153708D01*
X322696Y153917D01*
X323029Y154000D01*
X323362Y153917D01*
X323654Y153708D01*
X323779Y153417D01*
X323696Y153125D01*
X323487Y152917D01*
X323237Y152833D01*
X322821D01*
X322446Y152708D01*
X322196Y152458D01*
X322112Y152167D01*
X322196Y151875D01*
X322404Y151667D01*
X322737Y151542D01*
X323029Y151500D01*
G01X326129Y154000D02*
X325796Y153917D01*
X325546Y153708D01*
X325379Y153458D01*
X325254Y153125D01*
X325212Y152750D01*
X325254Y152375D01*
X325379Y152042D01*
X325546Y151792D01*
X325796Y151583D01*
X326129Y151500D01*
X326462Y151583D01*
X326712Y151792D01*
X326879Y152042D01*
X327004Y152375D01*
X327046Y152750D01*
X327004Y153125D01*
X326879Y153458D01*
X326712Y153708D01*
X326462Y153917D01*
X326129Y154000D01*
G01X312925Y155833D02*
X313258Y155625D01*
X313633Y155500D01*
X313967D01*
X314300Y155625D01*
X314550Y155833D01*
X314675Y156125D01*
X314592Y156417D01*
X314383Y156667D01*
X314008Y156833D01*
X313508Y156917D01*
X313217Y157083D01*
X313092Y157375D01*
X313175Y157667D01*
X313383Y157875D01*
X313675Y158000D01*
X313967D01*
X314258Y157917D01*
X314508Y157708D01*
G01X317817Y157792D02*
X317567Y157917D01*
X317275Y158000D01*
X316942D01*
X316567Y157875D01*
X316275Y157667D01*
X316067Y157417D01*
X315900Y157000D01*
X315858Y156625D01*
X315942Y156250D01*
X316067Y156000D01*
X316317Y155750D01*
X316608Y155583D01*
X316900Y155500D01*
X317192D01*
X317483Y155583D01*
X317733Y155708D01*
X317942Y155875D01*
G01X320000Y155500D02*
X320292Y155542D01*
X320625Y155667D01*
X320833Y155875D01*
X320917Y156167D01*
X320833Y156458D01*
X320583Y156708D01*
X320208Y156833D01*
X319792D01*
X319542Y156917D01*
X319333Y157125D01*
X319250Y157417D01*
X319375Y157708D01*
X319667Y157917D01*
X320000Y158000D01*
X320333Y157917D01*
X320625Y157708D01*
X320750Y157417D01*
X320667Y157125D01*
X320458Y156917D01*
X320208Y156833D01*
X319792D01*
X319417Y156708D01*
X319167Y156458D01*
X319083Y156167D01*
X319167Y155875D01*
X319375Y155667D01*
X319708Y155542D01*
X320000Y155500D01*
G01X323100D02*
X323392Y155542D01*
X323725Y155667D01*
X323933Y155875D01*
X324017Y156167D01*
X323933Y156458D01*
X323683Y156708D01*
X323308Y156833D01*
X322892D01*
X322642Y156917D01*
X322433Y157125D01*
X322350Y157417D01*
X322475Y157708D01*
X322767Y157917D01*
X323100Y158000D01*
X323433Y157917D01*
X323725Y157708D01*
X323850Y157417D01*
X323767Y157125D01*
X323558Y156917D01*
X323308Y156833D01*
X322892D01*
X322517Y156708D01*
X322267Y156458D01*
X322183Y156167D01*
X322267Y155875D01*
X322475Y155667D01*
X322808Y155542D01*
X323100Y155500D01*
G01X326200D02*
Y158000D01*
X325700Y157500D01*
G01Y155500D02*
X326700D01*
G01X312854Y159833D02*
X313187Y159625D01*
X313562Y159500D01*
X313896D01*
X314229Y159625D01*
X314479Y159833D01*
X314604Y160125D01*
X314521Y160417D01*
X314312Y160667D01*
X313937Y160833D01*
X313437Y160917D01*
X313146Y161083D01*
X313021Y161375D01*
X313104Y161667D01*
X313312Y161875D01*
X313604Y162000D01*
X313896D01*
X314187Y161917D01*
X314437Y161708D01*
G01X317746Y161792D02*
X317496Y161917D01*
X317204Y162000D01*
X316871D01*
X316496Y161875D01*
X316204Y161667D01*
X315996Y161417D01*
X315829Y161000D01*
X315787Y160625D01*
X315871Y160250D01*
X315996Y160000D01*
X316246Y159750D01*
X316537Y159583D01*
X316829Y159500D01*
X317121D01*
X317412Y159583D01*
X317662Y159708D01*
X317871Y159875D01*
G01X319929Y159500D02*
X320221Y159542D01*
X320554Y159667D01*
X320762Y159875D01*
X320846Y160167D01*
X320762Y160458D01*
X320512Y160708D01*
X320137Y160833D01*
X319721D01*
X319471Y160917D01*
X319262Y161125D01*
X319179Y161417D01*
X319304Y161708D01*
X319596Y161917D01*
X319929Y162000D01*
X320262Y161917D01*
X320554Y161708D01*
X320679Y161417D01*
X320596Y161125D01*
X320387Y160917D01*
X320137Y160833D01*
X319721D01*
X319346Y160708D01*
X319096Y160458D01*
X319012Y160167D01*
X319096Y159875D01*
X319304Y159667D01*
X319637Y159542D01*
X319929Y159500D01*
G01X323029D02*
X323321Y159542D01*
X323654Y159667D01*
X323862Y159875D01*
X323946Y160167D01*
X323862Y160458D01*
X323612Y160708D01*
X323237Y160833D01*
X322821D01*
X322571Y160917D01*
X322362Y161125D01*
X322279Y161417D01*
X322404Y161708D01*
X322696Y161917D01*
X323029Y162000D01*
X323362Y161917D01*
X323654Y161708D01*
X323779Y161417D01*
X323696Y161125D01*
X323487Y160917D01*
X323237Y160833D01*
X322821D01*
X322446Y160708D01*
X322196Y160458D01*
X322112Y160167D01*
X322196Y159875D01*
X322404Y159667D01*
X322737Y159542D01*
X323029Y159500D01*
G01X325337Y161583D02*
X325587Y161833D01*
X325879Y161958D01*
X326212Y162000D01*
X326629Y161917D01*
X326921Y161708D01*
X327004Y161458D01*
X326962Y161208D01*
X326796Y161000D01*
X325962Y160583D01*
X325587Y160292D01*
X325337Y159875D01*
X325254Y159500D01*
X327004D01*
G01X312965Y163833D02*
X313298Y163625D01*
X313673Y163500D01*
X314007D01*
X314340Y163625D01*
X314590Y163833D01*
X314715Y164125D01*
X314632Y164417D01*
X314423Y164667D01*
X314048Y164833D01*
X313548Y164917D01*
X313257Y165083D01*
X313132Y165375D01*
X313215Y165667D01*
X313423Y165875D01*
X313715Y166000D01*
X314007D01*
X314298Y165917D01*
X314548Y165708D01*
G01X317857Y165792D02*
X317607Y165917D01*
X317315Y166000D01*
X316982D01*
X316607Y165875D01*
X316315Y165667D01*
X316107Y165417D01*
X315940Y165000D01*
X315898Y164625D01*
X315982Y164250D01*
X316107Y164000D01*
X316357Y163750D01*
X316648Y163583D01*
X316940Y163500D01*
X317232D01*
X317523Y163583D01*
X317773Y163708D01*
X317982Y163875D01*
G01X320040Y163500D02*
X320332Y163542D01*
X320665Y163667D01*
X320873Y163875D01*
X320957Y164167D01*
X320873Y164458D01*
X320623Y164708D01*
X320248Y164833D01*
X319832D01*
X319582Y164917D01*
X319373Y165125D01*
X319290Y165417D01*
X319415Y165708D01*
X319707Y165917D01*
X320040Y166000D01*
X320373Y165917D01*
X320665Y165708D01*
X320790Y165417D01*
X320707Y165125D01*
X320498Y164917D01*
X320248Y164833D01*
X319832D01*
X319457Y164708D01*
X319207Y164458D01*
X319123Y164167D01*
X319207Y163875D01*
X319415Y163667D01*
X319748Y163542D01*
X320040Y163500D01*
G01X323140D02*
X323432Y163542D01*
X323765Y163667D01*
X323973Y163875D01*
X324057Y164167D01*
X323973Y164458D01*
X323723Y164708D01*
X323348Y164833D01*
X322932D01*
X322682Y164917D01*
X322473Y165125D01*
X322390Y165417D01*
X322515Y165708D01*
X322807Y165917D01*
X323140Y166000D01*
X323473Y165917D01*
X323765Y165708D01*
X323890Y165417D01*
X323807Y165125D01*
X323598Y164917D01*
X323348Y164833D01*
X322932D01*
X322557Y164708D01*
X322307Y164458D01*
X322223Y164167D01*
X322307Y163875D01*
X322515Y163667D01*
X322848Y163542D01*
X323140Y163500D01*
G01X325323Y164000D02*
X325573Y163708D01*
X325907Y163542D01*
X326282Y163500D01*
X326615Y163542D01*
X326948Y163750D01*
X327157Y164000D01*
X327198Y164250D01*
X327115Y164542D01*
X326823Y164750D01*
X326532Y164833D01*
X326157D01*
G01X326532D02*
X326782Y164958D01*
X326990Y165167D01*
X327073Y165417D01*
X326990Y165667D01*
X326782Y165875D01*
X326407Y166000D01*
X326032Y165958D01*
X325657Y165792D01*
G01X312965Y171833D02*
X313298Y171625D01*
X313673Y171500D01*
X314007D01*
X314340Y171625D01*
X314590Y171833D01*
X314715Y172125D01*
X314632Y172417D01*
X314423Y172667D01*
X314048Y172833D01*
X313548Y172917D01*
X313257Y173083D01*
X313132Y173375D01*
X313215Y173667D01*
X313423Y173875D01*
X313715Y174000D01*
X314007D01*
X314298Y173917D01*
X314548Y173708D01*
G01X317857Y173792D02*
X317607Y173917D01*
X317315Y174000D01*
X316982D01*
X316607Y173875D01*
X316315Y173667D01*
X316107Y173417D01*
X315940Y173000D01*
X315898Y172625D01*
X315982Y172250D01*
X316107Y172000D01*
X316357Y171750D01*
X316648Y171583D01*
X316940Y171500D01*
X317232D01*
X317523Y171583D01*
X317773Y171708D01*
X317982Y171875D01*
G01X320040Y171500D02*
X320332Y171542D01*
X320665Y171667D01*
X320873Y171875D01*
X320957Y172167D01*
X320873Y172458D01*
X320623Y172708D01*
X320248Y172833D01*
X319832D01*
X319582Y172917D01*
X319373Y173125D01*
X319290Y173417D01*
X319415Y173708D01*
X319707Y173917D01*
X320040Y174000D01*
X320373Y173917D01*
X320665Y173708D01*
X320790Y173417D01*
X320707Y173125D01*
X320498Y172917D01*
X320248Y172833D01*
X319832D01*
X319457Y172708D01*
X319207Y172458D01*
X319123Y172167D01*
X319207Y171875D01*
X319415Y171667D01*
X319748Y171542D01*
X320040Y171500D01*
G01X323140D02*
X323432Y171542D01*
X323765Y171667D01*
X323973Y171875D01*
X324057Y172167D01*
X323973Y172458D01*
X323723Y172708D01*
X323348Y172833D01*
X322932D01*
X322682Y172917D01*
X322473Y173125D01*
X322390Y173417D01*
X322515Y173708D01*
X322807Y173917D01*
X323140Y174000D01*
X323473Y173917D01*
X323765Y173708D01*
X323890Y173417D01*
X323807Y173125D01*
X323598Y172917D01*
X323348Y172833D01*
X322932D01*
X322557Y172708D01*
X322307Y172458D01*
X322223Y172167D01*
X322307Y171875D01*
X322515Y171667D01*
X322848Y171542D01*
X323140Y171500D01*
G01X326740D02*
Y174000D01*
X325198Y172208D01*
X327282D01*
G01X312965Y167833D02*
X313298Y167625D01*
X313673Y167500D01*
X314007D01*
X314340Y167625D01*
X314590Y167833D01*
X314715Y168125D01*
X314632Y168417D01*
X314423Y168667D01*
X314048Y168833D01*
X313548Y168917D01*
X313257Y169083D01*
X313132Y169375D01*
X313215Y169667D01*
X313423Y169875D01*
X313715Y170000D01*
X314007D01*
X314298Y169917D01*
X314548Y169708D01*
G01X317857Y169792D02*
X317607Y169917D01*
X317315Y170000D01*
X316982D01*
X316607Y169875D01*
X316315Y169667D01*
X316107Y169417D01*
X315940Y169000D01*
X315898Y168625D01*
X315982Y168250D01*
X316107Y168000D01*
X316357Y167750D01*
X316648Y167583D01*
X316940Y167500D01*
X317232D01*
X317523Y167583D01*
X317773Y167708D01*
X317982Y167875D01*
G01X320040Y167500D02*
X320332Y167542D01*
X320665Y167667D01*
X320873Y167875D01*
X320957Y168167D01*
X320873Y168458D01*
X320623Y168708D01*
X320248Y168833D01*
X319832D01*
X319582Y168917D01*
X319373Y169125D01*
X319290Y169417D01*
X319415Y169708D01*
X319707Y169917D01*
X320040Y170000D01*
X320373Y169917D01*
X320665Y169708D01*
X320790Y169417D01*
X320707Y169125D01*
X320498Y168917D01*
X320248Y168833D01*
X319832D01*
X319457Y168708D01*
X319207Y168458D01*
X319123Y168167D01*
X319207Y167875D01*
X319415Y167667D01*
X319748Y167542D01*
X320040Y167500D01*
G01X323140D02*
X323432Y167542D01*
X323765Y167667D01*
X323973Y167875D01*
X324057Y168167D01*
X323973Y168458D01*
X323723Y168708D01*
X323348Y168833D01*
X322932D01*
X322682Y168917D01*
X322473Y169125D01*
X322390Y169417D01*
X322515Y169708D01*
X322807Y169917D01*
X323140Y170000D01*
X323473Y169917D01*
X323765Y169708D01*
X323890Y169417D01*
X323807Y169125D01*
X323598Y168917D01*
X323348Y168833D01*
X322932D01*
X322557Y168708D01*
X322307Y168458D01*
X322223Y168167D01*
X322307Y167875D01*
X322515Y167667D01*
X322848Y167542D01*
X323140Y167500D01*
G01X325323Y167875D02*
X325573Y167667D01*
X325865Y167542D01*
X326240Y167500D01*
X326615Y167583D01*
X326907Y167750D01*
X327115Y168042D01*
X327157Y168375D01*
X327073Y168708D01*
X326865Y168917D01*
X326573Y169083D01*
X326282Y169125D01*
X325990Y169083D01*
X325615Y168917D01*
X325740Y170000D01*
X326865D01*
G01X312854Y187833D02*
X313187Y187625D01*
X313562Y187500D01*
X313896D01*
X314229Y187625D01*
X314479Y187833D01*
X314604Y188125D01*
X314521Y188417D01*
X314312Y188667D01*
X313937Y188833D01*
X313437Y188917D01*
X313146Y189083D01*
X313021Y189375D01*
X313104Y189667D01*
X313312Y189875D01*
X313604Y190000D01*
X313896D01*
X314187Y189917D01*
X314437Y189708D01*
G01X317746Y189792D02*
X317496Y189917D01*
X317204Y190000D01*
X316871D01*
X316496Y189875D01*
X316204Y189667D01*
X315996Y189417D01*
X315829Y189000D01*
X315787Y188625D01*
X315871Y188250D01*
X315996Y188000D01*
X316246Y187750D01*
X316537Y187583D01*
X316829Y187500D01*
X317121D01*
X317412Y187583D01*
X317662Y187708D01*
X317871Y187875D01*
G01X319929Y187500D02*
X320221Y187542D01*
X320554Y187667D01*
X320762Y187875D01*
X320846Y188167D01*
X320762Y188458D01*
X320512Y188708D01*
X320137Y188833D01*
X319721D01*
X319471Y188917D01*
X319262Y189125D01*
X319179Y189417D01*
X319304Y189708D01*
X319596Y189917D01*
X319929Y190000D01*
X320262Y189917D01*
X320554Y189708D01*
X320679Y189417D01*
X320596Y189125D01*
X320387Y188917D01*
X320137Y188833D01*
X319721D01*
X319346Y188708D01*
X319096Y188458D01*
X319012Y188167D01*
X319096Y187875D01*
X319304Y187667D01*
X319637Y187542D01*
X319929Y187500D01*
G01X322321Y187792D02*
X322612Y187583D01*
X322946Y187500D01*
X323279Y187583D01*
X323571Y187833D01*
X323779Y188208D01*
X323862Y188583D01*
Y189042D01*
X323779Y189417D01*
X323571Y189750D01*
X323321Y189917D01*
X323029Y190000D01*
X322696Y189917D01*
X322446Y189750D01*
X322279Y189500D01*
X322196Y189167D01*
X322279Y188875D01*
X322487Y188583D01*
X322737Y188417D01*
X323029Y188375D01*
X323362Y188458D01*
X323612Y188667D01*
X323862Y189042D01*
G01X325337Y189583D02*
X325587Y189833D01*
X325879Y189958D01*
X326212Y190000D01*
X326629Y189917D01*
X326921Y189708D01*
X327004Y189458D01*
X326962Y189208D01*
X326796Y189000D01*
X325962Y188583D01*
X325587Y188292D01*
X325337Y187875D01*
X325254Y187500D01*
X327004D01*
G01X312965Y175833D02*
X313298Y175625D01*
X313673Y175500D01*
X314007D01*
X314340Y175625D01*
X314590Y175833D01*
X314715Y176125D01*
X314632Y176417D01*
X314423Y176667D01*
X314048Y176833D01*
X313548Y176917D01*
X313257Y177083D01*
X313132Y177375D01*
X313215Y177667D01*
X313423Y177875D01*
X313715Y178000D01*
X314007D01*
X314298Y177917D01*
X314548Y177708D01*
G01X317857Y177792D02*
X317607Y177917D01*
X317315Y178000D01*
X316982D01*
X316607Y177875D01*
X316315Y177667D01*
X316107Y177417D01*
X315940Y177000D01*
X315898Y176625D01*
X315982Y176250D01*
X316107Y176000D01*
X316357Y175750D01*
X316648Y175583D01*
X316940Y175500D01*
X317232D01*
X317523Y175583D01*
X317773Y175708D01*
X317982Y175875D01*
G01X320040Y175500D02*
X320332Y175542D01*
X320665Y175667D01*
X320873Y175875D01*
X320957Y176167D01*
X320873Y176458D01*
X320623Y176708D01*
X320248Y176833D01*
X319832D01*
X319582Y176917D01*
X319373Y177125D01*
X319290Y177417D01*
X319415Y177708D01*
X319707Y177917D01*
X320040Y178000D01*
X320373Y177917D01*
X320665Y177708D01*
X320790Y177417D01*
X320707Y177125D01*
X320498Y176917D01*
X320248Y176833D01*
X319832D01*
X319457Y176708D01*
X319207Y176458D01*
X319123Y176167D01*
X319207Y175875D01*
X319415Y175667D01*
X319748Y175542D01*
X320040Y175500D01*
G01X322432Y175792D02*
X322723Y175583D01*
X323057Y175500D01*
X323390Y175583D01*
X323682Y175833D01*
X323890Y176208D01*
X323973Y176583D01*
Y177042D01*
X323890Y177417D01*
X323682Y177750D01*
X323432Y177917D01*
X323140Y178000D01*
X322807Y177917D01*
X322557Y177750D01*
X322390Y177500D01*
X322307Y177167D01*
X322390Y176875D01*
X322598Y176583D01*
X322848Y176417D01*
X323140Y176375D01*
X323473Y176458D01*
X323723Y176667D01*
X323973Y177042D01*
G01X325323Y176000D02*
X325573Y175708D01*
X325907Y175542D01*
X326282Y175500D01*
X326615Y175542D01*
X326948Y175750D01*
X327157Y176000D01*
X327198Y176250D01*
X327115Y176542D01*
X326823Y176750D01*
X326532Y176833D01*
X326157D01*
G01X326532D02*
X326782Y176958D01*
X326990Y177167D01*
X327073Y177417D01*
X326990Y177667D01*
X326782Y177875D01*
X326407Y178000D01*
X326032Y177958D01*
X325657Y177792D01*
G01X312965Y183833D02*
X313298Y183625D01*
X313673Y183500D01*
X314007D01*
X314340Y183625D01*
X314590Y183833D01*
X314715Y184125D01*
X314632Y184417D01*
X314423Y184667D01*
X314048Y184833D01*
X313548Y184917D01*
X313257Y185083D01*
X313132Y185375D01*
X313215Y185667D01*
X313423Y185875D01*
X313715Y186000D01*
X314007D01*
X314298Y185917D01*
X314548Y185708D01*
G01X317857Y185792D02*
X317607Y185917D01*
X317315Y186000D01*
X316982D01*
X316607Y185875D01*
X316315Y185667D01*
X316107Y185417D01*
X315940Y185000D01*
X315898Y184625D01*
X315982Y184250D01*
X316107Y184000D01*
X316357Y183750D01*
X316648Y183583D01*
X316940Y183500D01*
X317232D01*
X317523Y183583D01*
X317773Y183708D01*
X317982Y183875D01*
G01X320040Y183500D02*
X320332Y183542D01*
X320665Y183667D01*
X320873Y183875D01*
X320957Y184167D01*
X320873Y184458D01*
X320623Y184708D01*
X320248Y184833D01*
X319832D01*
X319582Y184917D01*
X319373Y185125D01*
X319290Y185417D01*
X319415Y185708D01*
X319707Y185917D01*
X320040Y186000D01*
X320373Y185917D01*
X320665Y185708D01*
X320790Y185417D01*
X320707Y185125D01*
X320498Y184917D01*
X320248Y184833D01*
X319832D01*
X319457Y184708D01*
X319207Y184458D01*
X319123Y184167D01*
X319207Y183875D01*
X319415Y183667D01*
X319748Y183542D01*
X320040Y183500D01*
G01X322432Y183792D02*
X322723Y183583D01*
X323057Y183500D01*
X323390Y183583D01*
X323682Y183833D01*
X323890Y184208D01*
X323973Y184583D01*
Y185042D01*
X323890Y185417D01*
X323682Y185750D01*
X323432Y185917D01*
X323140Y186000D01*
X322807Y185917D01*
X322557Y185750D01*
X322390Y185500D01*
X322307Y185167D01*
X322390Y184875D01*
X322598Y184583D01*
X322848Y184417D01*
X323140Y184375D01*
X323473Y184458D01*
X323723Y184667D01*
X323973Y185042D01*
G01X326740Y183500D02*
Y186000D01*
X325198Y184208D01*
X327282D01*
G01X312965Y179833D02*
X313298Y179625D01*
X313673Y179500D01*
X314007D01*
X314340Y179625D01*
X314590Y179833D01*
X314715Y180125D01*
X314632Y180417D01*
X314423Y180667D01*
X314048Y180833D01*
X313548Y180917D01*
X313257Y181083D01*
X313132Y181375D01*
X313215Y181667D01*
X313423Y181875D01*
X313715Y182000D01*
X314007D01*
X314298Y181917D01*
X314548Y181708D01*
G01X317857Y181792D02*
X317607Y181917D01*
X317315Y182000D01*
X316982D01*
X316607Y181875D01*
X316315Y181667D01*
X316107Y181417D01*
X315940Y181000D01*
X315898Y180625D01*
X315982Y180250D01*
X316107Y180000D01*
X316357Y179750D01*
X316648Y179583D01*
X316940Y179500D01*
X317232D01*
X317523Y179583D01*
X317773Y179708D01*
X317982Y179875D01*
G01X320040Y179500D02*
X320332Y179542D01*
X320665Y179667D01*
X320873Y179875D01*
X320957Y180167D01*
X320873Y180458D01*
X320623Y180708D01*
X320248Y180833D01*
X319832D01*
X319582Y180917D01*
X319373Y181125D01*
X319290Y181417D01*
X319415Y181708D01*
X319707Y181917D01*
X320040Y182000D01*
X320373Y181917D01*
X320665Y181708D01*
X320790Y181417D01*
X320707Y181125D01*
X320498Y180917D01*
X320248Y180833D01*
X319832D01*
X319457Y180708D01*
X319207Y180458D01*
X319123Y180167D01*
X319207Y179875D01*
X319415Y179667D01*
X319748Y179542D01*
X320040Y179500D01*
G01X322432Y179792D02*
X322723Y179583D01*
X323057Y179500D01*
X323390Y179583D01*
X323682Y179833D01*
X323890Y180208D01*
X323973Y180583D01*
Y181042D01*
X323890Y181417D01*
X323682Y181750D01*
X323432Y181917D01*
X323140Y182000D01*
X322807Y181917D01*
X322557Y181750D01*
X322390Y181500D01*
X322307Y181167D01*
X322390Y180875D01*
X322598Y180583D01*
X322848Y180417D01*
X323140Y180375D01*
X323473Y180458D01*
X323723Y180667D01*
X323973Y181042D01*
G01X325323Y179875D02*
X325573Y179667D01*
X325865Y179542D01*
X326240Y179500D01*
X326615Y179583D01*
X326907Y179750D01*
X327115Y180042D01*
X327157Y180375D01*
X327073Y180708D01*
X326865Y180917D01*
X326573Y181083D01*
X326282Y181125D01*
X325990Y181083D01*
X325615Y180917D01*
X325740Y182000D01*
X326865D01*
G01X310985Y240172D02*
X303985D01*
Y253572D01*
X310985D01*
Y240172D01*
G01X315485Y250572D02*
X311485D01*
Y243172D01*
G01X301596Y256925D02*
X301804Y257258D01*
X301929Y257633D01*
Y257967D01*
X301804Y258300D01*
X301596Y258550D01*
X301304Y258675D01*
X301012Y258592D01*
X300762Y258383D01*
X300596Y258008D01*
X300512Y257508D01*
X300346Y257217D01*
X300054Y257092D01*
X299762Y257175D01*
X299554Y257383D01*
X299429Y257675D01*
Y257967D01*
X299512Y258258D01*
X299721Y258508D01*
G01X299637Y261817D02*
X299512Y261567D01*
X299429Y261275D01*
Y260942D01*
X299554Y260567D01*
X299762Y260275D01*
X300012Y260067D01*
X300429Y259900D01*
X300804Y259858D01*
X301179Y259942D01*
X301429Y260067D01*
X301679Y260317D01*
X301846Y260608D01*
X301929Y260900D01*
Y261192D01*
X301846Y261483D01*
X301721Y261733D01*
X301554Y261942D01*
G01X301637Y263292D02*
X301846Y263583D01*
X301929Y263917D01*
X301846Y264250D01*
X301596Y264542D01*
X301221Y264750D01*
X300846Y264833D01*
X300387D01*
X300012Y264750D01*
X299679Y264542D01*
X299512Y264292D01*
X299429Y264000D01*
X299512Y263667D01*
X299679Y263417D01*
X299929Y263250D01*
X300262Y263167D01*
X300554Y263250D01*
X300846Y263458D01*
X301012Y263708D01*
X301054Y264000D01*
X300971Y264333D01*
X300762Y264583D01*
X300387Y264833D01*
G01X301929Y267100D02*
X301887Y267392D01*
X301762Y267725D01*
X301554Y267933D01*
X301262Y268017D01*
X300971Y267933D01*
X300721Y267683D01*
X300596Y267308D01*
Y266892D01*
X300512Y266642D01*
X300304Y266433D01*
X300012Y266350D01*
X299721Y266475D01*
X299512Y266767D01*
X299429Y267100D01*
X299512Y267433D01*
X299721Y267725D01*
X300012Y267850D01*
X300304Y267767D01*
X300512Y267558D01*
X300596Y267308D01*
Y266892D01*
X300721Y266517D01*
X300971Y266267D01*
X301262Y266183D01*
X301554Y266267D01*
X301762Y266475D01*
X301887Y266808D01*
X301929Y267100D01*
G01Y270700D02*
X299429D01*
X301221Y269158D01*
Y271242D01*
G01X306596Y256925D02*
X306804Y257258D01*
X306929Y257633D01*
Y257967D01*
X306804Y258300D01*
X306596Y258550D01*
X306304Y258675D01*
X306012Y258592D01*
X305762Y258383D01*
X305596Y258008D01*
X305512Y257508D01*
X305346Y257217D01*
X305054Y257092D01*
X304762Y257175D01*
X304554Y257383D01*
X304429Y257675D01*
Y257967D01*
X304512Y258258D01*
X304721Y258508D01*
G01X304637Y261817D02*
X304512Y261567D01*
X304429Y261275D01*
Y260942D01*
X304554Y260567D01*
X304762Y260275D01*
X305012Y260067D01*
X305429Y259900D01*
X305804Y259858D01*
X306179Y259942D01*
X306429Y260067D01*
X306679Y260317D01*
X306846Y260608D01*
X306929Y260900D01*
Y261192D01*
X306846Y261483D01*
X306721Y261733D01*
X306554Y261942D01*
G01X306637Y263292D02*
X306846Y263583D01*
X306929Y263917D01*
X306846Y264250D01*
X306596Y264542D01*
X306221Y264750D01*
X305846Y264833D01*
X305387D01*
X305012Y264750D01*
X304679Y264542D01*
X304512Y264292D01*
X304429Y264000D01*
X304512Y263667D01*
X304679Y263417D01*
X304929Y263250D01*
X305262Y263167D01*
X305554Y263250D01*
X305846Y263458D01*
X306012Y263708D01*
X306054Y264000D01*
X305971Y264333D01*
X305762Y264583D01*
X305387Y264833D01*
G01X306929Y267100D02*
X306887Y267392D01*
X306762Y267725D01*
X306554Y267933D01*
X306262Y268017D01*
X305971Y267933D01*
X305721Y267683D01*
X305596Y267308D01*
Y266892D01*
X305512Y266642D01*
X305304Y266433D01*
X305012Y266350D01*
X304721Y266475D01*
X304512Y266767D01*
X304429Y267100D01*
X304512Y267433D01*
X304721Y267725D01*
X305012Y267850D01*
X305304Y267767D01*
X305512Y267558D01*
X305596Y267308D01*
Y266892D01*
X305721Y266517D01*
X305971Y266267D01*
X306262Y266183D01*
X306554Y266267D01*
X306762Y266475D01*
X306887Y266808D01*
X306929Y267100D01*
G01X306554Y269283D02*
X306762Y269533D01*
X306887Y269825D01*
X306929Y270200D01*
X306846Y270575D01*
X306679Y270867D01*
X306387Y271075D01*
X306054Y271117D01*
X305721Y271033D01*
X305512Y270825D01*
X305346Y270533D01*
X305304Y270242D01*
X305346Y269950D01*
X305512Y269575D01*
X304429Y269700D01*
Y270825D01*
G01X323705Y323152D02*
Y316152D01*
X310305D01*
Y323152D01*
X323705D01*
G01X323629Y332000D02*
Y325000D01*
X310229D01*
Y332000D01*
X323629D01*
G01X324129Y345500D02*
Y338500D01*
X310729D01*
Y345500D01*
X324129D01*
G01X312729Y356000D02*
Y352000D01*
X320129D01*
G01X312729Y350500D02*
Y346500D01*
X320129D01*
G01X324129Y364000D02*
Y357000D01*
X310729D01*
Y364000D01*
X324129D01*
G01X312222Y392375D02*
X312430Y392708D01*
X312555Y393083D01*
Y393417D01*
X312430Y393750D01*
X312222Y394000D01*
X311930Y394125D01*
X311638Y394042D01*
X311388Y393833D01*
X311222Y393458D01*
X311138Y392958D01*
X310972Y392667D01*
X310680Y392542D01*
X310388Y392625D01*
X310180Y392833D01*
X310055Y393125D01*
Y393417D01*
X310138Y393708D01*
X310347Y393958D01*
G01X310263Y397267D02*
X310138Y397017D01*
X310055Y396725D01*
Y396392D01*
X310180Y396017D01*
X310388Y395725D01*
X310638Y395517D01*
X311055Y395350D01*
X311430Y395308D01*
X311805Y395392D01*
X312055Y395517D01*
X312305Y395767D01*
X312472Y396058D01*
X312555Y396350D01*
Y396642D01*
X312472Y396933D01*
X312347Y397183D01*
X312180Y397392D01*
G01X312555Y399450D02*
X310055D01*
X310555Y398950D01*
G01X312555D02*
Y399950D01*
G01X310472Y401758D02*
X310222Y402008D01*
X310097Y402300D01*
X310055Y402633D01*
X310138Y403050D01*
X310347Y403342D01*
X310597Y403425D01*
X310847Y403383D01*
X311055Y403217D01*
X311472Y402383D01*
X311763Y402008D01*
X312180Y401758D01*
X312555Y401675D01*
Y403425D01*
G01Y406150D02*
X310055D01*
X311847Y404608D01*
Y406692D01*
G01X310055Y408750D02*
X310138Y408417D01*
X310347Y408167D01*
X310597Y408000D01*
X310930Y407875D01*
X311305Y407833D01*
X311680Y407875D01*
X312013Y408000D01*
X312263Y408167D01*
X312472Y408417D01*
X312555Y408750D01*
X312472Y409083D01*
X312263Y409333D01*
X312013Y409500D01*
X311680Y409625D01*
X311305Y409667D01*
X310930Y409625D01*
X310597Y409500D01*
X310347Y409333D01*
X310138Y409083D01*
X310055Y408750D01*
G01X308222Y392375D02*
X308430Y392708D01*
X308555Y393083D01*
Y393417D01*
X308430Y393750D01*
X308222Y394000D01*
X307930Y394125D01*
X307638Y394042D01*
X307388Y393833D01*
X307222Y393458D01*
X307138Y392958D01*
X306972Y392667D01*
X306680Y392542D01*
X306388Y392625D01*
X306180Y392833D01*
X306055Y393125D01*
Y393417D01*
X306138Y393708D01*
X306347Y393958D01*
G01X306263Y397267D02*
X306138Y397017D01*
X306055Y396725D01*
Y396392D01*
X306180Y396017D01*
X306388Y395725D01*
X306638Y395517D01*
X307055Y395350D01*
X307430Y395308D01*
X307805Y395392D01*
X308055Y395517D01*
X308305Y395767D01*
X308472Y396058D01*
X308555Y396350D01*
Y396642D01*
X308472Y396933D01*
X308347Y397183D01*
X308180Y397392D01*
G01X308555Y399450D02*
X306055D01*
X306555Y398950D01*
G01X308555D02*
Y399950D01*
G01X306472Y401758D02*
X306222Y402008D01*
X306097Y402300D01*
X306055Y402633D01*
X306138Y403050D01*
X306347Y403342D01*
X306597Y403425D01*
X306847Y403383D01*
X307055Y403217D01*
X307472Y402383D01*
X307763Y402008D01*
X308180Y401758D01*
X308555Y401675D01*
Y403425D01*
G01X308055Y404733D02*
X308347Y404983D01*
X308513Y405317D01*
X308555Y405692D01*
X308513Y406025D01*
X308305Y406358D01*
X308055Y406567D01*
X307805Y406608D01*
X307513Y406525D01*
X307305Y406233D01*
X307222Y405942D01*
Y405567D01*
G01Y405942D02*
X307097Y406192D01*
X306888Y406400D01*
X306638Y406483D01*
X306388Y406400D01*
X306180Y406192D01*
X306055Y405817D01*
X306097Y405442D01*
X306263Y405067D01*
G01X308263Y408042D02*
X308472Y408333D01*
X308555Y408667D01*
X308472Y409000D01*
X308222Y409292D01*
X307847Y409500D01*
X307472Y409583D01*
X307013D01*
X306638Y409500D01*
X306305Y409292D01*
X306138Y409042D01*
X306055Y408750D01*
X306138Y408417D01*
X306305Y408167D01*
X306555Y408000D01*
X306888Y407917D01*
X307180Y408000D01*
X307472Y408208D01*
X307638Y408458D01*
X307680Y408750D01*
X307597Y409083D01*
X307388Y409333D01*
X307013Y409583D01*
G01X304222Y392375D02*
X304430Y392708D01*
X304555Y393083D01*
Y393417D01*
X304430Y393750D01*
X304222Y394000D01*
X303930Y394125D01*
X303638Y394042D01*
X303388Y393833D01*
X303222Y393458D01*
X303138Y392958D01*
X302972Y392667D01*
X302680Y392542D01*
X302388Y392625D01*
X302180Y392833D01*
X302055Y393125D01*
Y393417D01*
X302138Y393708D01*
X302347Y393958D01*
G01X302263Y397267D02*
X302138Y397017D01*
X302055Y396725D01*
Y396392D01*
X302180Y396017D01*
X302388Y395725D01*
X302638Y395517D01*
X303055Y395350D01*
X303430Y395308D01*
X303805Y395392D01*
X304055Y395517D01*
X304305Y395767D01*
X304472Y396058D01*
X304555Y396350D01*
Y396642D01*
X304472Y396933D01*
X304347Y397183D01*
X304180Y397392D01*
G01X304555Y399450D02*
X302055D01*
X302555Y398950D01*
G01X304555D02*
Y399950D01*
G01X302472Y401758D02*
X302222Y402008D01*
X302097Y402300D01*
X302055Y402633D01*
X302138Y403050D01*
X302347Y403342D01*
X302597Y403425D01*
X302847Y403383D01*
X303055Y403217D01*
X303472Y402383D01*
X303763Y402008D01*
X304180Y401758D01*
X304555Y401675D01*
Y403425D01*
G01X304055Y404733D02*
X304347Y404983D01*
X304513Y405317D01*
X304555Y405692D01*
X304513Y406025D01*
X304305Y406358D01*
X304055Y406567D01*
X303805Y406608D01*
X303513Y406525D01*
X303305Y406233D01*
X303222Y405942D01*
Y405567D01*
G01Y405942D02*
X303097Y406192D01*
X302888Y406400D01*
X302638Y406483D01*
X302388Y406400D01*
X302180Y406192D01*
X302055Y405817D01*
X302097Y405442D01*
X302263Y405067D01*
G01X304555Y408750D02*
X304513Y409042D01*
X304388Y409375D01*
X304180Y409583D01*
X303888Y409667D01*
X303597Y409583D01*
X303347Y409333D01*
X303222Y408958D01*
Y408542D01*
X303138Y408292D01*
X302930Y408083D01*
X302638Y408000D01*
X302347Y408125D01*
X302138Y408417D01*
X302055Y408750D01*
X302138Y409083D01*
X302347Y409375D01*
X302638Y409500D01*
X302930Y409417D01*
X303138Y409208D01*
X303222Y408958D01*
Y408542D01*
X303347Y408167D01*
X303597Y407917D01*
X303888Y407833D01*
X304180Y407917D01*
X304388Y408125D01*
X304513Y408458D01*
X304555Y408750D01*
G01X300222Y392375D02*
X300430Y392708D01*
X300555Y393083D01*
Y393417D01*
X300430Y393750D01*
X300222Y394000D01*
X299930Y394125D01*
X299638Y394042D01*
X299388Y393833D01*
X299222Y393458D01*
X299138Y392958D01*
X298972Y392667D01*
X298680Y392542D01*
X298388Y392625D01*
X298180Y392833D01*
X298055Y393125D01*
Y393417D01*
X298138Y393708D01*
X298347Y393958D01*
G01X298263Y397267D02*
X298138Y397017D01*
X298055Y396725D01*
Y396392D01*
X298180Y396017D01*
X298388Y395725D01*
X298638Y395517D01*
X299055Y395350D01*
X299430Y395308D01*
X299805Y395392D01*
X300055Y395517D01*
X300305Y395767D01*
X300472Y396058D01*
X300555Y396350D01*
Y396642D01*
X300472Y396933D01*
X300347Y397183D01*
X300180Y397392D01*
G01X300555Y399450D02*
X298055D01*
X298555Y398950D01*
G01X300555D02*
Y399950D01*
G01X298472Y401758D02*
X298222Y402008D01*
X298097Y402300D01*
X298055Y402633D01*
X298138Y403050D01*
X298347Y403342D01*
X298597Y403425D01*
X298847Y403383D01*
X299055Y403217D01*
X299472Y402383D01*
X299763Y402008D01*
X300180Y401758D01*
X300555Y401675D01*
Y403425D01*
G01X300055Y404733D02*
X300347Y404983D01*
X300513Y405317D01*
X300555Y405692D01*
X300513Y406025D01*
X300305Y406358D01*
X300055Y406567D01*
X299805Y406608D01*
X299513Y406525D01*
X299305Y406233D01*
X299222Y405942D01*
Y405567D01*
G01Y405942D02*
X299097Y406192D01*
X298888Y406400D01*
X298638Y406483D01*
X298388Y406400D01*
X298180Y406192D01*
X298055Y405817D01*
X298097Y405442D01*
X298263Y405067D01*
G01X300555Y408667D02*
X300013Y408750D01*
X299555Y408875D01*
X299138Y409042D01*
X298680Y409250D01*
X298055Y409583D01*
Y407917D01*
G01X315000Y447500D02*
X345000D01*
Y446500D01*
X369500D01*
Y431500D01*
X313000D01*
Y435000D01*
X309000D01*
Y447500D01*
X315000D01*
G01X298159Y437378D02*
Y423978D01*
G01X308555Y419467D02*
X306055D01*
Y420467D01*
X306180Y420800D01*
X306472Y421050D01*
X306805Y421133D01*
X307138Y421050D01*
X307388Y420842D01*
X307513Y420467D01*
Y419467D01*
G01X306263Y424317D02*
X306138Y424067D01*
X306055Y423775D01*
Y423442D01*
X306180Y423067D01*
X306388Y422775D01*
X306638Y422567D01*
X307055Y422400D01*
X307430Y422358D01*
X307805Y422442D01*
X308055Y422567D01*
X308305Y422817D01*
X308472Y423108D01*
X308555Y423400D01*
Y423692D01*
X308472Y423983D01*
X308347Y424233D01*
X308180Y424442D01*
G01X308555Y426500D02*
X306055D01*
X306555Y426000D01*
G01X308555D02*
Y427000D01*
G01X308263Y428892D02*
X308472Y429183D01*
X308555Y429517D01*
X308472Y429850D01*
X308222Y430142D01*
X307847Y430350D01*
X307472Y430433D01*
X307013D01*
X306638Y430350D01*
X306305Y430142D01*
X306138Y429892D01*
X306055Y429600D01*
X306138Y429267D01*
X306305Y429017D01*
X306555Y428850D01*
X306888Y428767D01*
X307180Y428850D01*
X307472Y429058D01*
X307638Y429308D01*
X307680Y429600D01*
X307597Y429933D01*
X307388Y430183D01*
X307013Y430433D01*
G01X308555Y432700D02*
X306055D01*
X306555Y432200D01*
G01X308555D02*
Y433200D01*
G01X314555Y444700D02*
X310555D01*
Y437300D01*
G01X306930Y491333D02*
X307263Y491125D01*
X307638Y491000D01*
X307972D01*
X308305Y491125D01*
X308555Y491333D01*
X308680Y491625D01*
X308597Y491917D01*
X308388Y492167D01*
X308013Y492333D01*
X307513Y492417D01*
X307222Y492583D01*
X307097Y492875D01*
X307180Y493167D01*
X307388Y493375D01*
X307680Y493500D01*
X307972D01*
X308263Y493417D01*
X308513Y493208D01*
G01X311822Y493292D02*
X311572Y493417D01*
X311280Y493500D01*
X310947D01*
X310572Y493375D01*
X310280Y493167D01*
X310072Y492917D01*
X309905Y492500D01*
X309863Y492125D01*
X309947Y491750D01*
X310072Y491500D01*
X310322Y491250D01*
X310613Y491083D01*
X310905Y491000D01*
X311197D01*
X311488Y491083D01*
X311738Y491208D01*
X311947Y491375D01*
G01X314005Y491000D02*
Y493500D01*
X313505Y493000D01*
G01Y491000D02*
X314505D01*
G01X317105D02*
Y493500D01*
X316605Y493000D01*
G01Y491000D02*
X317605D01*
G01X320205Y493500D02*
X319872Y493417D01*
X319622Y493208D01*
X319455Y492958D01*
X319330Y492625D01*
X319288Y492250D01*
X319330Y491875D01*
X319455Y491542D01*
X319622Y491292D01*
X319872Y491083D01*
X320205Y491000D01*
X320538Y491083D01*
X320788Y491292D01*
X320955Y491542D01*
X321080Y491875D01*
X321122Y492250D01*
X321080Y492625D01*
X320955Y492958D01*
X320788Y493208D01*
X320538Y493417D01*
X320205Y493500D01*
G01X323305D02*
X322972Y493417D01*
X322722Y493208D01*
X322555Y492958D01*
X322430Y492625D01*
X322388Y492250D01*
X322430Y491875D01*
X322555Y491542D01*
X322722Y491292D01*
X322972Y491083D01*
X323305Y491000D01*
X323638Y491083D01*
X323888Y491292D01*
X324055Y491542D01*
X324180Y491875D01*
X324222Y492250D01*
X324180Y492625D01*
X324055Y492958D01*
X323888Y493208D01*
X323638Y493417D01*
X323305Y493500D01*
G01X308222Y503425D02*
X308430Y503758D01*
X308555Y504133D01*
Y504467D01*
X308430Y504800D01*
X308222Y505050D01*
X307930Y505175D01*
X307638Y505092D01*
X307388Y504883D01*
X307222Y504508D01*
X307138Y504008D01*
X306972Y503717D01*
X306680Y503592D01*
X306388Y503675D01*
X306180Y503883D01*
X306055Y504175D01*
Y504467D01*
X306138Y504758D01*
X306347Y505008D01*
G01X308555Y506567D02*
X306055D01*
Y507608D01*
X306180Y507942D01*
X306347Y508150D01*
X306680Y508233D01*
X307013Y508150D01*
X307222Y507900D01*
X307347Y507608D01*
Y506567D01*
G01Y507608D02*
X308555Y508233D01*
G01Y510417D02*
X308013Y510500D01*
X307555Y510625D01*
X307138Y510792D01*
X306680Y511000D01*
X306055Y511333D01*
Y509667D01*
G01X308555Y513600D02*
X308513Y513892D01*
X308388Y514225D01*
X308180Y514433D01*
X307888Y514517D01*
X307597Y514433D01*
X307347Y514183D01*
X307222Y513808D01*
Y513392D01*
X307138Y513142D01*
X306930Y512933D01*
X306638Y512850D01*
X306347Y512975D01*
X306138Y513267D01*
X306055Y513600D01*
X306138Y513933D01*
X306347Y514225D01*
X306638Y514350D01*
X306930Y514267D01*
X307138Y514058D01*
X307222Y513808D01*
Y513392D01*
X307347Y513017D01*
X307597Y512767D01*
X307888Y512683D01*
X308180Y512767D01*
X308388Y512975D01*
X308513Y513308D01*
X308555Y513600D01*
G01X307513Y515908D02*
X307222Y516200D01*
X307055Y516450D01*
X306972Y516783D01*
X307055Y517075D01*
X307222Y517283D01*
X307472Y517450D01*
X307763Y517492D01*
X308013Y517450D01*
X308263Y517283D01*
X308472Y517033D01*
X308555Y516742D01*
X308472Y516408D01*
X308222Y516117D01*
X307847Y515950D01*
X307430Y515908D01*
X306888Y515992D01*
X306597Y516117D01*
X306305Y516325D01*
X306097Y516617D01*
X306055Y516908D01*
X306138Y517200D01*
X306347Y517408D01*
G01X318223Y505683D02*
Y509683D01*
X310823D01*
G01X308722Y522875D02*
X308930Y523208D01*
X309055Y523583D01*
Y523917D01*
X308930Y524250D01*
X308722Y524500D01*
X308430Y524625D01*
X308138Y524542D01*
X307888Y524333D01*
X307722Y523958D01*
X307638Y523458D01*
X307472Y523167D01*
X307180Y523042D01*
X306888Y523125D01*
X306680Y523333D01*
X306555Y523625D01*
Y523917D01*
X306638Y524208D01*
X306847Y524458D01*
G01X306763Y527767D02*
X306638Y527517D01*
X306555Y527225D01*
Y526892D01*
X306680Y526517D01*
X306888Y526225D01*
X307138Y526017D01*
X307555Y525850D01*
X307930Y525808D01*
X308305Y525892D01*
X308555Y526017D01*
X308805Y526267D01*
X308972Y526558D01*
X309055Y526850D01*
Y527142D01*
X308972Y527433D01*
X308847Y527683D01*
X308680Y527892D01*
G01X309055Y529950D02*
X306555D01*
X307055Y529450D01*
G01X309055D02*
Y530450D01*
G01Y533050D02*
X306555D01*
X307055Y532550D01*
G01X309055D02*
Y533550D01*
G01X306555Y536150D02*
X306638Y535817D01*
X306847Y535567D01*
X307097Y535400D01*
X307430Y535275D01*
X307805Y535233D01*
X308180Y535275D01*
X308513Y535400D01*
X308763Y535567D01*
X308972Y535817D01*
X309055Y536150D01*
X308972Y536483D01*
X308763Y536733D01*
X308513Y536900D01*
X308180Y537025D01*
X307805Y537067D01*
X307430Y537025D01*
X307097Y536900D01*
X306847Y536733D01*
X306638Y536483D01*
X306555Y536150D01*
G01X309055Y539250D02*
X306555D01*
X307055Y538750D01*
G01X309055D02*
Y539750D01*
G01X308667Y691000D02*
Y701000D01*
X313000Y692667D01*
X317333Y701000D01*
Y691000D01*
G01X319433D02*
X323600Y701000D01*
X327767Y691000D01*
G01X326267Y694500D02*
X320933D01*
G01X330533Y691000D02*
Y701000D01*
X333867D01*
X335200Y700500D01*
X336200Y699833D01*
X337033Y698833D01*
X337700Y697666D01*
X337867Y696000D01*
X337700Y694333D01*
X337033Y693167D01*
X336200Y692166D01*
X335200Y691500D01*
X333867Y691000D01*
X330533D01*
G01X348133D02*
X341467D01*
Y701000D01*
X348133D01*
G01X345467Y696167D02*
X341467D01*
G01X364000Y701000D02*
X368000D01*
G01X366000D02*
Y691000D01*
G01X364000D02*
X368000D01*
G01X372767D02*
Y701000D01*
X380433Y691000D01*
Y701000D01*
G01X397800D02*
Y691000D01*
G01X393967Y701000D02*
X401633D01*
G01X404233Y691000D02*
X408400Y701000D01*
X412567Y691000D01*
G01X411067Y694500D02*
X405733D01*
G01X417000Y701000D02*
X421000D01*
G01X419000D02*
Y691000D01*
G01X417000D02*
X421000D01*
G01X424600Y701000D02*
X426933Y691000D01*
X429600Y701000D01*
X432267Y691000D01*
X434600Y701000D01*
G01X436033Y691000D02*
X440200Y701000D01*
X444367Y691000D01*
G01X442867Y694500D02*
X437533D01*
G01X446967Y691000D02*
Y701000D01*
X454633Y691000D01*
Y701000D01*
G01X312500Y712000D02*
Y722000D01*
X306333Y714833D01*
X314667D01*
G01X321100Y712000D02*
X322267Y712167D01*
X323600Y712667D01*
X324433Y713500D01*
X324767Y714667D01*
X324433Y715833D01*
X323433Y716833D01*
X321933Y717333D01*
X320267D01*
X319267Y717667D01*
X318433Y718500D01*
X318100Y719667D01*
X318600Y720833D01*
X319766Y721667D01*
X321100Y722000D01*
X322433Y721667D01*
X323600Y720833D01*
X324100Y719667D01*
X323767Y718500D01*
X322933Y717667D01*
X321933Y717333D01*
X320267D01*
X318767Y716833D01*
X317767Y715833D01*
X317433Y714667D01*
X317767Y713500D01*
X318600Y712667D01*
X319933Y712167D01*
X321100Y712000D01*
G01X331700Y711667D02*
X331367Y711833D01*
Y712167D01*
X331700Y712333D01*
X332033Y712167D01*
Y711833D01*
X331700Y711667D01*
G01X343633Y717333D02*
X344300Y717833D01*
X344800Y718666D01*
X345133Y719833D01*
X344800Y720833D01*
X344133Y721500D01*
X342967Y722000D01*
X338467D01*
Y712000D01*
X343967D01*
X345133Y712667D01*
X345800Y713667D01*
X346133Y714833D01*
X345800Y716000D01*
X344800Y717000D01*
X343633Y717333D01*
X338467D01*
G01X352900Y722000D02*
X351566Y721667D01*
X350567Y720833D01*
X349900Y719833D01*
X349400Y718500D01*
X349233Y717000D01*
X349400Y715500D01*
X349900Y714167D01*
X350567Y713166D01*
X351566Y712333D01*
X352900Y712000D01*
X354233Y712333D01*
X355233Y713166D01*
X355900Y714167D01*
X356400Y715500D01*
X356567Y717000D01*
X356400Y718500D01*
X355900Y719833D01*
X355233Y720833D01*
X354233Y721667D01*
X352900Y722000D01*
G01X363167Y712000D02*
X363500Y714167D01*
X364000Y716000D01*
X364667Y717667D01*
X365500Y719500D01*
X366833Y722000D01*
X360167D01*
G01X370933Y720333D02*
X371933Y721333D01*
X373100Y721833D01*
X374433Y722000D01*
X376100Y721667D01*
X377267Y720833D01*
X377600Y719833D01*
X377433Y718833D01*
X376767Y718000D01*
X373433Y716333D01*
X371933Y715167D01*
X370933Y713500D01*
X370600Y712000D01*
X377600D01*
G01X384700D02*
X385867Y712167D01*
X387200Y712667D01*
X388033Y713500D01*
X388367Y714667D01*
X388033Y715833D01*
X387033Y716833D01*
X385533Y717333D01*
X383867D01*
X382867Y717667D01*
X382033Y718500D01*
X381700Y719667D01*
X382200Y720833D01*
X383366Y721667D01*
X384700Y722000D01*
X386033Y721667D01*
X387200Y720833D01*
X387700Y719667D01*
X387367Y718500D01*
X386533Y717667D01*
X385533Y717333D01*
X383867D01*
X382367Y716833D01*
X381367Y715833D01*
X381033Y714667D01*
X381367Y713500D01*
X382200Y712667D01*
X383533Y712167D01*
X384700Y712000D01*
G01X395300Y711667D02*
X394967Y711833D01*
Y712167D01*
X395300Y712333D01*
X395633Y712167D01*
Y711833D01*
X395300Y711667D01*
G01X405900Y722000D02*
X404566Y721667D01*
X403567Y720833D01*
X402900Y719833D01*
X402400Y718500D01*
X402233Y717000D01*
X402400Y715500D01*
X402900Y714167D01*
X403567Y713166D01*
X404566Y712333D01*
X405900Y712000D01*
X407233Y712333D01*
X408233Y713166D01*
X408900Y714167D01*
X409400Y715500D01*
X409567Y717000D01*
X409400Y718500D01*
X408900Y719833D01*
X408233Y720833D01*
X407233Y721667D01*
X405900Y722000D01*
G01X416500Y712000D02*
Y722000D01*
X414500Y720000D01*
G01Y712000D02*
X418500D01*
G01X428433Y717333D02*
X429100Y717833D01*
X429600Y718666D01*
X429933Y719833D01*
X429600Y720833D01*
X428933Y721500D01*
X427767Y722000D01*
X423267D01*
Y712000D01*
X428767D01*
X429933Y712667D01*
X430600Y713667D01*
X430933Y714833D01*
X430600Y716000D01*
X429600Y717000D01*
X428433Y717333D01*
X423267D01*
G01X310500Y734000D02*
Y744000D01*
X308500Y742000D01*
G01Y734000D02*
X312500D01*
G01X317433Y736000D02*
X318433Y734833D01*
X319766Y734167D01*
X321267Y734000D01*
X322600Y734167D01*
X323933Y735000D01*
X324767Y736000D01*
X324933Y737000D01*
X324600Y738166D01*
X323433Y739000D01*
X322267Y739333D01*
X320767D01*
G01X322267D02*
X323267Y739833D01*
X324100Y740666D01*
X324433Y741667D01*
X324100Y742667D01*
X323267Y743500D01*
X321767Y744000D01*
X320267Y743833D01*
X318767Y743167D01*
G01X328867Y735166D02*
X330033Y734333D01*
X331367Y734000D01*
X332700Y734333D01*
X333867Y735333D01*
X334700Y736833D01*
X335033Y738333D01*
Y740167D01*
X334700Y741667D01*
X333867Y743000D01*
X332867Y743667D01*
X331700Y744000D01*
X330366Y743667D01*
X329367Y743000D01*
X328700Y742000D01*
X328367Y740666D01*
X328700Y739500D01*
X329533Y738333D01*
X330533Y737666D01*
X331700Y737500D01*
X333033Y737833D01*
X334033Y738667D01*
X335033Y740167D01*
G01X344300Y734000D02*
Y744000D01*
X338133Y736833D01*
X346467D01*
G01X352900Y734000D02*
X354067Y734167D01*
X355400Y734667D01*
X356233Y735500D01*
X356567Y736667D01*
X356233Y737833D01*
X355233Y738833D01*
X353733Y739333D01*
X352067D01*
X351067Y739667D01*
X350233Y740500D01*
X349900Y741667D01*
X350400Y742833D01*
X351566Y743667D01*
X352900Y744000D01*
X354233Y743667D01*
X355400Y742833D01*
X355900Y741667D01*
X355567Y740500D01*
X354733Y739667D01*
X353733Y739333D01*
X352067D01*
X350567Y738833D01*
X349567Y737833D01*
X349233Y736667D01*
X349567Y735500D01*
X350400Y734667D01*
X351733Y734167D01*
X352900Y734000D01*
G01X361333Y737333D02*
X365667D01*
G01X374100Y734000D02*
Y744000D01*
X372100Y742000D01*
G01Y734000D02*
X376100D01*
G01X386033Y739333D02*
X386700Y739833D01*
X387200Y740666D01*
X387533Y741833D01*
X387200Y742833D01*
X386533Y743500D01*
X385367Y744000D01*
X380867D01*
Y734000D01*
X386367D01*
X387533Y734667D01*
X388200Y735667D01*
X388533Y736833D01*
X388200Y738000D01*
X387200Y739000D01*
X386033Y739333D01*
X380867D01*
G01X309500Y755000D02*
Y765000D01*
G01X316500D02*
Y755000D01*
G01Y760000D02*
X309500D01*
G01X323600Y755000D02*
X322600Y755167D01*
X321600Y755833D01*
X320933Y757000D01*
X320600Y758333D01*
X320933Y759667D01*
X321600Y760833D01*
X322600Y761500D01*
X323600Y761666D01*
X324600Y761500D01*
X325600Y760833D01*
X326267Y759667D01*
X326433Y758333D01*
X326267Y757000D01*
X325600Y755833D01*
X324600Y755167D01*
X323600Y755000D01*
G01X331367D02*
Y761666D01*
G01Y760000D02*
X332033Y760833D01*
X333033Y761500D01*
X334367Y761666D01*
X335533Y761500D01*
X336533Y760833D01*
X337033Y759667D01*
Y755000D01*
G01X342300Y759500D02*
X347633D01*
X347133Y760667D01*
X346300Y761333D01*
X345133Y761666D01*
X343967Y761500D01*
X342967Y761000D01*
X342300Y759833D01*
X341967Y758833D01*
Y757833D01*
X342300Y756833D01*
X343133Y755833D01*
X344133Y755167D01*
X345300Y755000D01*
X346467Y755333D01*
X347633Y756333D01*
G01X351900Y752000D02*
X352900Y751667D01*
X354233Y752000D01*
X355067Y752667D01*
X355733Y753500D01*
X356733Y756166D01*
X358900Y761666D01*
G01X353567D02*
X356733Y756166D01*
G01X377933Y760333D02*
X378600Y760833D01*
X379100Y761666D01*
X379433Y762833D01*
X379100Y763833D01*
X378433Y764500D01*
X377267Y765000D01*
X372767D01*
Y755000D01*
X378267D01*
X379433Y755667D01*
X380100Y756667D01*
X380433Y757833D01*
X380100Y759000D01*
X379100Y760000D01*
X377933Y760333D01*
X372767D01*
G01X390200Y755000D02*
Y761666D01*
G01Y760500D02*
X389533Y761167D01*
X388533Y761500D01*
X387367Y761666D01*
X386200Y761333D01*
X385200Y760667D01*
X384533Y759667D01*
X384200Y758333D01*
X384533Y757000D01*
X385200Y756000D01*
X386200Y755333D01*
X387367Y755000D01*
X388533Y755167D01*
X389533Y755667D01*
X390200Y756333D01*
G01X400800Y765000D02*
Y755000D01*
G01Y756500D02*
X400133Y755667D01*
X399133Y755167D01*
X397967Y755000D01*
X396633Y755333D01*
X395633Y756166D01*
X394967Y757167D01*
X394800Y758333D01*
X394967Y759500D01*
X395633Y760500D01*
X396633Y761333D01*
X397967Y761666D01*
X399133Y761500D01*
X399967Y761167D01*
X400800Y760500D01*
G01X406067Y752500D02*
X407233Y751833D01*
X408567Y751667D01*
X409733Y751833D01*
X410733Y752667D01*
X411400Y753833D01*
Y761666D01*
G01Y760333D02*
X410733Y761000D01*
X409733Y761500D01*
X408567Y761666D01*
X407233Y761333D01*
X406400Y760667D01*
X405733Y759500D01*
X405400Y758333D01*
X405567Y757333D01*
X406233Y756166D01*
X407233Y755333D01*
X408567Y755000D01*
X409567Y755167D01*
X410733Y755833D01*
X411400Y756500D01*
G01X416500Y759500D02*
X421833D01*
X421333Y760667D01*
X420500Y761333D01*
X419333Y761666D01*
X418167Y761500D01*
X417167Y761000D01*
X416500Y759833D01*
X416167Y758833D01*
Y757833D01*
X416500Y756833D01*
X417333Y755833D01*
X418333Y755167D01*
X419500Y755000D01*
X420667Y755333D01*
X421833Y756333D01*
G01X427267Y755000D02*
Y761666D01*
G01Y760333D02*
X428100Y761000D01*
X428933Y761500D01*
X430100Y761666D01*
X430933Y761500D01*
X431933Y761000D01*
G01X452133Y760333D02*
X452800Y760833D01*
X453300Y761666D01*
X453633Y762833D01*
X453300Y763833D01*
X452633Y764500D01*
X451467Y765000D01*
X446967D01*
Y755000D01*
X452467D01*
X453633Y755667D01*
X454300Y756667D01*
X454633Y757833D01*
X454300Y759000D01*
X453300Y760000D01*
X452133Y760333D01*
X446967D01*
G01X464400Y755000D02*
Y761666D01*
G01Y760500D02*
X463733Y761167D01*
X462733Y761500D01*
X461567Y761666D01*
X460400Y761333D01*
X459400Y760667D01*
X458733Y759667D01*
X458400Y758333D01*
X458733Y757000D01*
X459400Y756000D01*
X460400Y755333D01*
X461567Y755000D01*
X462733Y755167D01*
X463733Y755667D01*
X464400Y756333D01*
G01X469500Y756166D02*
X470333Y755500D01*
X471500Y755000D01*
X472500D01*
X473500Y755333D01*
X474167Y755833D01*
X474500Y756500D01*
X474333Y757500D01*
X473667Y758000D01*
X470666Y759000D01*
X470000Y760167D01*
X470333Y761000D01*
X471000Y761500D01*
X472000Y761666D01*
X473000Y761500D01*
X474000Y761000D01*
G01X480100Y759500D02*
X485433D01*
X484933Y760667D01*
X484100Y761333D01*
X482933Y761666D01*
X481767Y761500D01*
X480767Y761000D01*
X480100Y759833D01*
X479767Y758833D01*
Y757833D01*
X480100Y756833D01*
X480933Y755833D01*
X481933Y755167D01*
X483100Y755000D01*
X484267Y755333D01*
X485433Y756333D01*
G01X490200Y755000D02*
Y765000D01*
G01Y760000D02*
X491033Y761000D01*
X492033Y761500D01*
X493033Y761666D01*
X494533Y761333D01*
X495533Y760667D01*
X496200Y759500D01*
Y758167D01*
X495867Y756833D01*
X495200Y755833D01*
X494033Y755167D01*
X493033Y755000D01*
X492033Y755167D01*
X491033Y755667D01*
X490200Y756500D01*
G01X503800Y755000D02*
X502800Y755167D01*
X501800Y755833D01*
X501133Y757000D01*
X500800Y758333D01*
X501133Y759667D01*
X501800Y760833D01*
X502800Y761500D01*
X503800Y761666D01*
X504800Y761500D01*
X505800Y760833D01*
X506467Y759667D01*
X506633Y758333D01*
X506467Y757000D01*
X505800Y755833D01*
X504800Y755167D01*
X503800Y755000D01*
G01X517400D02*
Y761666D01*
G01Y760500D02*
X516733Y761167D01*
X515733Y761500D01*
X514567Y761666D01*
X513400Y761333D01*
X512400Y760667D01*
X511733Y759667D01*
X511400Y758333D01*
X511733Y757000D01*
X512400Y756000D01*
X513400Y755333D01*
X514567Y755000D01*
X515733Y755167D01*
X516733Y755667D01*
X517400Y756333D01*
G01X522667Y755000D02*
Y761666D01*
G01Y760333D02*
X523500Y761000D01*
X524333Y761500D01*
X525500Y761666D01*
X526333Y761500D01*
X527333Y761000D01*
G01X538600Y765000D02*
Y755000D01*
G01Y756500D02*
X537933Y755667D01*
X536933Y755167D01*
X535767Y755000D01*
X534433Y755333D01*
X533433Y756166D01*
X532767Y757167D01*
X532600Y758333D01*
X532767Y759500D01*
X533433Y760500D01*
X534433Y761333D01*
X535767Y761666D01*
X536933Y761500D01*
X537767Y761167D01*
X538600Y760500D01*
G01X300925Y877833D02*
X301258Y877625D01*
X301633Y877500D01*
X301967D01*
X302300Y877625D01*
X302550Y877833D01*
X302675Y878125D01*
X302592Y878417D01*
X302383Y878667D01*
X302008Y878833D01*
X301508Y878917D01*
X301217Y879083D01*
X301092Y879375D01*
X301175Y879667D01*
X301383Y879875D01*
X301675Y880000D01*
X301967D01*
X302258Y879917D01*
X302508Y879708D01*
G01X304067Y877500D02*
Y880000D01*
X305108D01*
X305442Y879875D01*
X305650Y879708D01*
X305733Y879375D01*
X305650Y879042D01*
X305400Y878833D01*
X305108Y878708D01*
X304067D01*
G01X305108D02*
X305733Y877500D01*
G01X308000D02*
X308292Y877542D01*
X308625Y877667D01*
X308833Y877875D01*
X308917Y878167D01*
X308833Y878458D01*
X308583Y878708D01*
X308208Y878833D01*
X307792D01*
X307542Y878917D01*
X307333Y879125D01*
X307250Y879417D01*
X307375Y879708D01*
X307667Y879917D01*
X308000Y880000D01*
X308333Y879917D01*
X308625Y879708D01*
X308750Y879417D01*
X308667Y879125D01*
X308458Y878917D01*
X308208Y878833D01*
X307792D01*
X307417Y878708D01*
X307167Y878458D01*
X307083Y878167D01*
X307167Y877875D01*
X307375Y877667D01*
X307708Y877542D01*
X308000Y877500D01*
G01X310183Y878000D02*
X310433Y877708D01*
X310767Y877542D01*
X311142Y877500D01*
X311475Y877542D01*
X311808Y877750D01*
X312017Y878000D01*
X312058Y878250D01*
X311975Y878542D01*
X311683Y878750D01*
X311392Y878833D01*
X311017D01*
G01X311392D02*
X311642Y878958D01*
X311850Y879167D01*
X311933Y879417D01*
X311850Y879667D01*
X311642Y879875D01*
X311267Y880000D01*
X310892Y879958D01*
X310517Y879792D01*
G01X313492Y877792D02*
X313783Y877583D01*
X314117Y877500D01*
X314450Y877583D01*
X314742Y877833D01*
X314950Y878208D01*
X315033Y878583D01*
Y879042D01*
X314950Y879417D01*
X314742Y879750D01*
X314492Y879917D01*
X314200Y880000D01*
X313867Y879917D01*
X313617Y879750D01*
X313450Y879500D01*
X313367Y879167D01*
X313450Y878875D01*
X313658Y878583D01*
X313908Y878417D01*
X314200Y878375D01*
X314533Y878458D01*
X314783Y878667D01*
X315033Y879042D01*
G01X300925Y883833D02*
X301258Y883625D01*
X301633Y883500D01*
X301967D01*
X302300Y883625D01*
X302550Y883833D01*
X302675Y884125D01*
X302592Y884417D01*
X302383Y884667D01*
X302008Y884833D01*
X301508Y884917D01*
X301217Y885083D01*
X301092Y885375D01*
X301175Y885667D01*
X301383Y885875D01*
X301675Y886000D01*
X301967D01*
X302258Y885917D01*
X302508Y885708D01*
G01X304067Y883500D02*
Y886000D01*
X305108D01*
X305442Y885875D01*
X305650Y885708D01*
X305733Y885375D01*
X305650Y885042D01*
X305400Y884833D01*
X305108Y884708D01*
X304067D01*
G01X305108D02*
X305733Y883500D01*
G01X307917D02*
X308000Y884042D01*
X308125Y884500D01*
X308292Y884917D01*
X308500Y885375D01*
X308833Y886000D01*
X307167D01*
G01X311100Y883500D02*
X311392Y883542D01*
X311725Y883667D01*
X311933Y883875D01*
X312017Y884167D01*
X311933Y884458D01*
X311683Y884708D01*
X311308Y884833D01*
X310892D01*
X310642Y884917D01*
X310433Y885125D01*
X310350Y885417D01*
X310475Y885708D01*
X310767Y885917D01*
X311100Y886000D01*
X311433Y885917D01*
X311725Y885708D01*
X311850Y885417D01*
X311767Y885125D01*
X311558Y884917D01*
X311308Y884833D01*
X310892D01*
X310517Y884708D01*
X310267Y884458D01*
X310183Y884167D01*
X310267Y883875D01*
X310475Y883667D01*
X310808Y883542D01*
X311100Y883500D01*
G01X313283Y884000D02*
X313533Y883708D01*
X313867Y883542D01*
X314242Y883500D01*
X314575Y883542D01*
X314908Y883750D01*
X315117Y884000D01*
X315158Y884250D01*
X315075Y884542D01*
X314783Y884750D01*
X314492Y884833D01*
X314117D01*
G01X314492D02*
X314742Y884958D01*
X314950Y885167D01*
X315033Y885417D01*
X314950Y885667D01*
X314742Y885875D01*
X314367Y886000D01*
X313992Y885958D01*
X313617Y885792D01*
G01X300925Y892333D02*
X301258Y892125D01*
X301633Y892000D01*
X301967D01*
X302300Y892125D01*
X302550Y892333D01*
X302675Y892625D01*
X302592Y892917D01*
X302383Y893167D01*
X302008Y893333D01*
X301508Y893417D01*
X301217Y893583D01*
X301092Y893875D01*
X301175Y894167D01*
X301383Y894375D01*
X301675Y894500D01*
X301967D01*
X302258Y894417D01*
X302508Y894208D01*
G01X304067Y892000D02*
Y894500D01*
X305108D01*
X305442Y894375D01*
X305650Y894208D01*
X305733Y893875D01*
X305650Y893542D01*
X305400Y893333D01*
X305108Y893208D01*
X304067D01*
G01X305108D02*
X305733Y892000D01*
G01X307208Y894083D02*
X307458Y894333D01*
X307750Y894458D01*
X308083Y894500D01*
X308500Y894417D01*
X308792Y894208D01*
X308875Y893958D01*
X308833Y893708D01*
X308667Y893500D01*
X307833Y893083D01*
X307458Y892792D01*
X307208Y892375D01*
X307125Y892000D01*
X308875D01*
G01X310308Y893042D02*
X310600Y893333D01*
X310850Y893500D01*
X311183Y893583D01*
X311475Y893500D01*
X311683Y893333D01*
X311850Y893083D01*
X311892Y892792D01*
X311850Y892542D01*
X311683Y892292D01*
X311433Y892083D01*
X311142Y892000D01*
X310808Y892083D01*
X310517Y892333D01*
X310350Y892708D01*
X310308Y893125D01*
X310392Y893667D01*
X310517Y893958D01*
X310725Y894250D01*
X311017Y894458D01*
X311308Y894500D01*
X311600Y894417D01*
X311808Y894208D01*
G01X313408Y893042D02*
X313700Y893333D01*
X313950Y893500D01*
X314283Y893583D01*
X314575Y893500D01*
X314783Y893333D01*
X314950Y893083D01*
X314992Y892792D01*
X314950Y892542D01*
X314783Y892292D01*
X314533Y892083D01*
X314242Y892000D01*
X313908Y892083D01*
X313617Y892333D01*
X313450Y892708D01*
X313408Y893125D01*
X313492Y893667D01*
X313617Y893958D01*
X313825Y894250D01*
X314117Y894458D01*
X314408Y894500D01*
X314700Y894417D01*
X314908Y894208D01*
G01X313425Y939333D02*
X313758Y939125D01*
X314133Y939000D01*
X314467D01*
X314800Y939125D01*
X315050Y939333D01*
X315175Y939625D01*
X315092Y939917D01*
X314883Y940167D01*
X314508Y940333D01*
X314008Y940417D01*
X313717Y940583D01*
X313592Y940875D01*
X313675Y941167D01*
X313883Y941375D01*
X314175Y941500D01*
X314467D01*
X314758Y941417D01*
X315008Y941208D01*
G01X318317Y941292D02*
X318067Y941417D01*
X317775Y941500D01*
X317442D01*
X317067Y941375D01*
X316775Y941167D01*
X316567Y940917D01*
X316400Y940500D01*
X316358Y940125D01*
X316442Y939750D01*
X316567Y939500D01*
X316817Y939250D01*
X317108Y939083D01*
X317400Y939000D01*
X317692D01*
X317983Y939083D01*
X318233Y939208D01*
X318442Y939375D01*
G01X321000Y939000D02*
Y941500D01*
X319458Y939708D01*
X321542D01*
G01X322683Y939500D02*
X322933Y939208D01*
X323267Y939042D01*
X323642Y939000D01*
X323975Y939042D01*
X324308Y939250D01*
X324517Y939500D01*
X324558Y939750D01*
X324475Y940042D01*
X324183Y940250D01*
X323892Y940333D01*
X323517D01*
G01X323892D02*
X324142Y940458D01*
X324350Y940667D01*
X324433Y940917D01*
X324350Y941167D01*
X324142Y941375D01*
X323767Y941500D01*
X323392Y941458D01*
X323017Y941292D01*
G01X325908Y941083D02*
X326158Y941333D01*
X326450Y941458D01*
X326783Y941500D01*
X327200Y941417D01*
X327492Y941208D01*
X327575Y940958D01*
X327533Y940708D01*
X327367Y940500D01*
X326533Y940083D01*
X326158Y939792D01*
X325908Y939375D01*
X325825Y939000D01*
X327575D01*
G01X313925Y946333D02*
X314258Y946125D01*
X314633Y946000D01*
X314967D01*
X315300Y946125D01*
X315550Y946333D01*
X315675Y946625D01*
X315592Y946917D01*
X315383Y947167D01*
X315008Y947333D01*
X314508Y947417D01*
X314217Y947583D01*
X314092Y947875D01*
X314175Y948167D01*
X314383Y948375D01*
X314675Y948500D01*
X314967D01*
X315258Y948417D01*
X315508Y948208D01*
G01X318817Y948292D02*
X318567Y948417D01*
X318275Y948500D01*
X317942D01*
X317567Y948375D01*
X317275Y948167D01*
X317067Y947917D01*
X316900Y947500D01*
X316858Y947125D01*
X316942Y946750D01*
X317067Y946500D01*
X317317Y946250D01*
X317608Y946083D01*
X317900Y946000D01*
X318192D01*
X318483Y946083D01*
X318733Y946208D01*
X318942Y946375D01*
G01X321500Y946000D02*
Y948500D01*
X319958Y946708D01*
X322042D01*
G01X323183Y946500D02*
X323433Y946208D01*
X323767Y946042D01*
X324142Y946000D01*
X324475Y946042D01*
X324808Y946250D01*
X325017Y946500D01*
X325058Y946750D01*
X324975Y947042D01*
X324683Y947250D01*
X324392Y947333D01*
X324017D01*
G01X324392D02*
X324642Y947458D01*
X324850Y947667D01*
X324933Y947917D01*
X324850Y948167D01*
X324642Y948375D01*
X324267Y948500D01*
X323892Y948458D01*
X323517Y948292D01*
G01X326408Y947042D02*
X326700Y947333D01*
X326950Y947500D01*
X327283Y947583D01*
X327575Y947500D01*
X327783Y947333D01*
X327950Y947083D01*
X327992Y946792D01*
X327950Y946542D01*
X327783Y946292D01*
X327533Y946083D01*
X327242Y946000D01*
X326908Y946083D01*
X326617Y946333D01*
X326450Y946708D01*
X326408Y947125D01*
X326492Y947667D01*
X326617Y947958D01*
X326825Y948250D01*
X327117Y948458D01*
X327408Y948500D01*
X327700Y948417D01*
X327908Y948208D01*
G01X326200Y5700D02*
Y11200D01*
G01X334200Y5700D02*
X326200D01*
G01X321800Y12900D02*
Y23100D01*
G01Y12900D02*
Y23100D01*
G01X326200Y23300D02*
X334200D01*
G01X326200Y17800D02*
Y23300D01*
G01X319400Y23500D02*
X313900D01*
G01X319400Y31500D02*
Y23500D01*
G01X325500Y29100D02*
X353500D01*
G01X325500Y63900D02*
Y29100D01*
G01X326667Y25000D02*
Y27500D01*
X327667D01*
X328000Y27375D01*
X328250Y27083D01*
X328333Y26750D01*
X328250Y26417D01*
X328042Y26167D01*
X327667Y26042D01*
X326667D01*
G01X331517Y27292D02*
X331267Y27417D01*
X330975Y27500D01*
X330642D01*
X330267Y27375D01*
X329975Y27167D01*
X329767Y26917D01*
X329600Y26500D01*
X329558Y26125D01*
X329642Y25750D01*
X329767Y25500D01*
X330017Y25250D01*
X330308Y25083D01*
X330600Y25000D01*
X330892D01*
X331183Y25083D01*
X331433Y25208D01*
X331642Y25375D01*
G01X333700Y25000D02*
Y27500D01*
X333200Y27000D01*
G01Y25000D02*
X334200D01*
G01X336092Y25292D02*
X336383Y25083D01*
X336717Y25000D01*
X337050Y25083D01*
X337342Y25333D01*
X337550Y25708D01*
X337633Y26083D01*
Y26542D01*
X337550Y26917D01*
X337342Y27250D01*
X337092Y27417D01*
X336800Y27500D01*
X336467Y27417D01*
X336217Y27250D01*
X336050Y27000D01*
X335967Y26667D01*
X336050Y26375D01*
X336258Y26083D01*
X336508Y25917D01*
X336800Y25875D01*
X337133Y25958D01*
X337383Y26167D01*
X337633Y26542D01*
G01X339900Y25000D02*
X340192Y25042D01*
X340525Y25167D01*
X340733Y25375D01*
X340817Y25667D01*
X340733Y25958D01*
X340483Y26208D01*
X340108Y26333D01*
X339692D01*
X339442Y26417D01*
X339233Y26625D01*
X339150Y26917D01*
X339275Y27208D01*
X339567Y27417D01*
X339900Y27500D01*
X340233Y27417D01*
X340525Y27208D01*
X340650Y26917D01*
X340567Y26625D01*
X340358Y26417D01*
X340108Y26333D01*
X339692D01*
X339317Y26208D01*
X339067Y25958D01*
X338983Y25667D01*
X339067Y25375D01*
X339275Y25167D01*
X339608Y25042D01*
X339900Y25000D01*
G01X319400Y32200D02*
X313900D01*
G01X319400Y40200D02*
Y32200D01*
G01X313900Y40200D02*
X319400D01*
G01X313900Y31500D02*
X319400D01*
G01X323500Y32467D02*
X321000D01*
Y33467D01*
X321125Y33800D01*
X321417Y34050D01*
X321750Y34133D01*
X322083Y34050D01*
X322333Y33842D01*
X322458Y33467D01*
Y32467D01*
G01X321208Y37317D02*
X321083Y37067D01*
X321000Y36775D01*
Y36442D01*
X321125Y36067D01*
X321333Y35775D01*
X321583Y35567D01*
X322000Y35400D01*
X322375Y35358D01*
X322750Y35442D01*
X323000Y35567D01*
X323250Y35817D01*
X323417Y36108D01*
X323500Y36400D01*
Y36692D01*
X323417Y36983D01*
X323292Y37233D01*
X323125Y37442D01*
G01X321417Y38708D02*
X321167Y38958D01*
X321042Y39250D01*
X321000Y39583D01*
X321083Y40000D01*
X321292Y40292D01*
X321542Y40375D01*
X321792Y40333D01*
X322000Y40167D01*
X322417Y39333D01*
X322708Y38958D01*
X323125Y38708D01*
X323500Y38625D01*
Y40375D01*
G01X321000Y42600D02*
X321083Y42267D01*
X321292Y42017D01*
X321542Y41850D01*
X321875Y41725D01*
X322250Y41683D01*
X322625Y41725D01*
X322958Y41850D01*
X323208Y42017D01*
X323417Y42267D01*
X323500Y42600D01*
X323417Y42933D01*
X323208Y43183D01*
X322958Y43350D01*
X322625Y43475D01*
X322250Y43517D01*
X321875Y43475D01*
X321542Y43350D01*
X321292Y43183D01*
X321083Y42933D01*
X321000Y42600D01*
G01X322458Y44908D02*
X322167Y45200D01*
X322000Y45450D01*
X321917Y45783D01*
X322000Y46075D01*
X322167Y46283D01*
X322417Y46450D01*
X322708Y46492D01*
X322958Y46450D01*
X323208Y46283D01*
X323417Y46033D01*
X323500Y45742D01*
X323417Y45408D01*
X323167Y45117D01*
X322792Y44950D01*
X322375Y44908D01*
X321833Y44992D01*
X321542Y45117D01*
X321250Y45325D01*
X321042Y45617D01*
X321000Y45908D01*
X321083Y46200D01*
X321292Y46408D01*
G01X319400Y40800D02*
X313900D01*
G01X319400Y48800D02*
Y40800D01*
G01X313900Y48800D02*
X319400D01*
G01X323500Y49467D02*
X321000D01*
Y50467D01*
X321125Y50800D01*
X321417Y51050D01*
X321750Y51133D01*
X322083Y51050D01*
X322333Y50842D01*
X322458Y50467D01*
Y49467D01*
G01X321208Y54317D02*
X321083Y54067D01*
X321000Y53775D01*
Y53442D01*
X321125Y53067D01*
X321333Y52775D01*
X321583Y52567D01*
X322000Y52400D01*
X322375Y52358D01*
X322750Y52442D01*
X323000Y52567D01*
X323250Y52817D01*
X323417Y53108D01*
X323500Y53400D01*
Y53692D01*
X323417Y53983D01*
X323292Y54233D01*
X323125Y54442D01*
G01X321417Y55708D02*
X321167Y55958D01*
X321042Y56250D01*
X321000Y56583D01*
X321083Y57000D01*
X321292Y57292D01*
X321542Y57375D01*
X321792Y57333D01*
X322000Y57167D01*
X322417Y56333D01*
X322708Y55958D01*
X323125Y55708D01*
X323500Y55625D01*
Y57375D01*
G01X321000Y59600D02*
X321083Y59267D01*
X321292Y59017D01*
X321542Y58850D01*
X321875Y58725D01*
X322250Y58683D01*
X322625Y58725D01*
X322958Y58850D01*
X323208Y59017D01*
X323417Y59267D01*
X323500Y59600D01*
X323417Y59933D01*
X323208Y60183D01*
X322958Y60350D01*
X322625Y60475D01*
X322250Y60517D01*
X321875Y60475D01*
X321542Y60350D01*
X321292Y60183D01*
X321083Y59933D01*
X321000Y59600D01*
G01X323208Y61992D02*
X323417Y62283D01*
X323500Y62617D01*
X323417Y62950D01*
X323167Y63242D01*
X322792Y63450D01*
X322417Y63533D01*
X321958D01*
X321583Y63450D01*
X321250Y63242D01*
X321083Y62992D01*
X321000Y62700D01*
X321083Y62367D01*
X321250Y62117D01*
X321500Y61950D01*
X321833Y61867D01*
X322125Y61950D01*
X322417Y62158D01*
X322583Y62408D01*
X322625Y62700D01*
X322542Y63033D01*
X322333Y63283D01*
X321958Y63533D01*
G01X353500Y63900D02*
X325500D01*
G01X313822Y69424D02*
Y64424D01*
X318822D01*
G01X326862Y86382D02*
Y88382D01*
G01X326200Y91500D02*
Y95500D01*
X318800D01*
G01Y100000D02*
Y96000D01*
X326200D01*
G01X329667Y128425D02*
X329875Y128758D01*
X330000Y129133D01*
Y129467D01*
X329875Y129800D01*
X329667Y130050D01*
X329375Y130175D01*
X329083Y130092D01*
X328833Y129883D01*
X328667Y129508D01*
X328583Y129008D01*
X328417Y128717D01*
X328125Y128592D01*
X327833Y128675D01*
X327625Y128883D01*
X327500Y129175D01*
Y129467D01*
X327583Y129758D01*
X327792Y130008D01*
G01X327708Y133317D02*
X327583Y133067D01*
X327500Y132775D01*
Y132442D01*
X327625Y132067D01*
X327833Y131775D01*
X328083Y131567D01*
X328500Y131400D01*
X328875Y131358D01*
X329250Y131442D01*
X329500Y131567D01*
X329750Y131817D01*
X329917Y132108D01*
X330000Y132400D01*
Y132692D01*
X329917Y132983D01*
X329792Y133233D01*
X329625Y133442D01*
G01X329708Y134792D02*
X329917Y135083D01*
X330000Y135417D01*
X329917Y135750D01*
X329667Y136042D01*
X329292Y136250D01*
X328917Y136333D01*
X328458D01*
X328083Y136250D01*
X327750Y136042D01*
X327583Y135792D01*
X327500Y135500D01*
X327583Y135167D01*
X327750Y134917D01*
X328000Y134750D01*
X328333Y134667D01*
X328625Y134750D01*
X328917Y134958D01*
X329083Y135208D01*
X329125Y135500D01*
X329042Y135833D01*
X328833Y136083D01*
X328458Y136333D01*
G01X328958Y137808D02*
X328667Y138100D01*
X328500Y138350D01*
X328417Y138683D01*
X328500Y138975D01*
X328667Y139183D01*
X328917Y139350D01*
X329208Y139392D01*
X329458Y139350D01*
X329708Y139183D01*
X329917Y138933D01*
X330000Y138642D01*
X329917Y138308D01*
X329667Y138017D01*
X329292Y137850D01*
X328875Y137808D01*
X328333Y137892D01*
X328042Y138017D01*
X327750Y138225D01*
X327542Y138517D01*
X327500Y138808D01*
X327583Y139100D01*
X327792Y139308D01*
G01X330000Y142200D02*
X327500D01*
X329292Y140658D01*
Y142742D01*
G01X318410Y204705D02*
X318743Y204497D01*
X319118Y204372D01*
X319452D01*
X319785Y204497D01*
X320035Y204705D01*
X320160Y204997D01*
X320077Y205289D01*
X319868Y205539D01*
X319493Y205705D01*
X318993Y205789D01*
X318702Y205955D01*
X318577Y206247D01*
X318660Y206539D01*
X318868Y206747D01*
X319160Y206872D01*
X319452D01*
X319743Y206789D01*
X319993Y206580D01*
G01X323302Y206664D02*
X323052Y206789D01*
X322760Y206872D01*
X322427D01*
X322052Y206747D01*
X321760Y206539D01*
X321552Y206289D01*
X321385Y205872D01*
X321343Y205497D01*
X321427Y205122D01*
X321552Y204872D01*
X321802Y204622D01*
X322093Y204455D01*
X322385Y204372D01*
X322677D01*
X322968Y204455D01*
X323218Y204580D01*
X323427Y204747D01*
G01X324777Y204664D02*
X325068Y204455D01*
X325402Y204372D01*
X325735Y204455D01*
X326027Y204705D01*
X326235Y205080D01*
X326318Y205455D01*
Y205914D01*
X326235Y206289D01*
X326027Y206622D01*
X325777Y206789D01*
X325485Y206872D01*
X325152Y206789D01*
X324902Y206622D01*
X324735Y206372D01*
X324652Y206039D01*
X324735Y205747D01*
X324943Y205455D01*
X325193Y205289D01*
X325485Y205247D01*
X325818Y205330D01*
X326068Y205539D01*
X326318Y205914D01*
G01X327793Y206455D02*
X328043Y206705D01*
X328335Y206830D01*
X328668Y206872D01*
X329085Y206789D01*
X329377Y206580D01*
X329460Y206330D01*
X329418Y206080D01*
X329252Y205872D01*
X328418Y205455D01*
X328043Y205164D01*
X327793Y204747D01*
X327710Y204372D01*
X329460D01*
G01X331685D02*
Y206872D01*
X331185Y206372D01*
G01Y204372D02*
X332185D01*
G01X318354Y200833D02*
X318687Y200625D01*
X319062Y200500D01*
X319396D01*
X319729Y200625D01*
X319979Y200833D01*
X320104Y201125D01*
X320021Y201417D01*
X319812Y201667D01*
X319437Y201833D01*
X318937Y201917D01*
X318646Y202083D01*
X318521Y202375D01*
X318604Y202667D01*
X318812Y202875D01*
X319104Y203000D01*
X319396D01*
X319687Y202917D01*
X319937Y202708D01*
G01X323246Y202792D02*
X322996Y202917D01*
X322704Y203000D01*
X322371D01*
X321996Y202875D01*
X321704Y202667D01*
X321496Y202417D01*
X321329Y202000D01*
X321287Y201625D01*
X321371Y201250D01*
X321496Y201000D01*
X321746Y200750D01*
X322037Y200583D01*
X322329Y200500D01*
X322621D01*
X322912Y200583D01*
X323162Y200708D01*
X323371Y200875D01*
G01X324721Y200792D02*
X325012Y200583D01*
X325346Y200500D01*
X325679Y200583D01*
X325971Y200833D01*
X326179Y201208D01*
X326262Y201583D01*
Y202042D01*
X326179Y202417D01*
X325971Y202750D01*
X325721Y202917D01*
X325429Y203000D01*
X325096Y202917D01*
X324846Y202750D01*
X324679Y202500D01*
X324596Y202167D01*
X324679Y201875D01*
X324887Y201583D01*
X325137Y201417D01*
X325429Y201375D01*
X325762Y201458D01*
X326012Y201667D01*
X326262Y202042D01*
G01X327737Y202583D02*
X327987Y202833D01*
X328279Y202958D01*
X328612Y203000D01*
X329029Y202917D01*
X329321Y202708D01*
X329404Y202458D01*
X329362Y202208D01*
X329196Y202000D01*
X328362Y201583D01*
X327987Y201292D01*
X327737Y200875D01*
X327654Y200500D01*
X329404D01*
G01X330837Y202583D02*
X331087Y202833D01*
X331379Y202958D01*
X331712Y203000D01*
X332129Y202917D01*
X332421Y202708D01*
X332504Y202458D01*
X332462Y202208D01*
X332296Y202000D01*
X331462Y201583D01*
X331087Y201292D01*
X330837Y200875D01*
X330754Y200500D01*
X332504D01*
G01X330354Y190333D02*
X330687Y190125D01*
X331062Y190000D01*
X331396D01*
X331729Y190125D01*
X331979Y190333D01*
X332104Y190625D01*
X332021Y190917D01*
X331812Y191167D01*
X331437Y191333D01*
X330937Y191417D01*
X330646Y191583D01*
X330521Y191875D01*
X330604Y192167D01*
X330812Y192375D01*
X331104Y192500D01*
X331396D01*
X331687Y192417D01*
X331937Y192208D01*
G01X335246Y192292D02*
X334996Y192417D01*
X334704Y192500D01*
X334371D01*
X333996Y192375D01*
X333704Y192167D01*
X333496Y191917D01*
X333329Y191500D01*
X333287Y191125D01*
X333371Y190750D01*
X333496Y190500D01*
X333746Y190250D01*
X334037Y190083D01*
X334329Y190000D01*
X334621D01*
X334912Y190083D01*
X335162Y190208D01*
X335371Y190375D01*
G01X336721Y190292D02*
X337012Y190083D01*
X337346Y190000D01*
X337679Y190083D01*
X337971Y190333D01*
X338179Y190708D01*
X338262Y191083D01*
Y191542D01*
X338179Y191917D01*
X337971Y192250D01*
X337721Y192417D01*
X337429Y192500D01*
X337096Y192417D01*
X336846Y192250D01*
X336679Y192000D01*
X336596Y191667D01*
X336679Y191375D01*
X336887Y191083D01*
X337137Y190917D01*
X337429Y190875D01*
X337762Y190958D01*
X338012Y191167D01*
X338262Y191542D01*
G01X340529Y192500D02*
X340196Y192417D01*
X339946Y192208D01*
X339779Y191958D01*
X339654Y191625D01*
X339612Y191250D01*
X339654Y190875D01*
X339779Y190542D01*
X339946Y190292D01*
X340196Y190083D01*
X340529Y190000D01*
X340862Y190083D01*
X341112Y190292D01*
X341279Y190542D01*
X341404Y190875D01*
X341446Y191250D01*
X341404Y191625D01*
X341279Y191958D01*
X341112Y192208D01*
X340862Y192417D01*
X340529Y192500D01*
G01X343629Y190000D02*
Y192500D01*
X343129Y192000D01*
G01Y190000D02*
X344129D01*
G01X330354Y194333D02*
X330687Y194125D01*
X331062Y194000D01*
X331396D01*
X331729Y194125D01*
X331979Y194333D01*
X332104Y194625D01*
X332021Y194917D01*
X331812Y195167D01*
X331437Y195333D01*
X330937Y195417D01*
X330646Y195583D01*
X330521Y195875D01*
X330604Y196167D01*
X330812Y196375D01*
X331104Y196500D01*
X331396D01*
X331687Y196417D01*
X331937Y196208D01*
G01X335246Y196292D02*
X334996Y196417D01*
X334704Y196500D01*
X334371D01*
X333996Y196375D01*
X333704Y196167D01*
X333496Y195917D01*
X333329Y195500D01*
X333287Y195125D01*
X333371Y194750D01*
X333496Y194500D01*
X333746Y194250D01*
X334037Y194083D01*
X334329Y194000D01*
X334621D01*
X334912Y194083D01*
X335162Y194208D01*
X335371Y194375D01*
G01X336721Y194292D02*
X337012Y194083D01*
X337346Y194000D01*
X337679Y194083D01*
X337971Y194333D01*
X338179Y194708D01*
X338262Y195083D01*
Y195542D01*
X338179Y195917D01*
X337971Y196250D01*
X337721Y196417D01*
X337429Y196500D01*
X337096Y196417D01*
X336846Y196250D01*
X336679Y196000D01*
X336596Y195667D01*
X336679Y195375D01*
X336887Y195083D01*
X337137Y194917D01*
X337429Y194875D01*
X337762Y194958D01*
X338012Y195167D01*
X338262Y195542D01*
G01X340529Y196500D02*
X340196Y196417D01*
X339946Y196208D01*
X339779Y195958D01*
X339654Y195625D01*
X339612Y195250D01*
X339654Y194875D01*
X339779Y194542D01*
X339946Y194292D01*
X340196Y194083D01*
X340529Y194000D01*
X340862Y194083D01*
X341112Y194292D01*
X341279Y194542D01*
X341404Y194875D01*
X341446Y195250D01*
X341404Y195625D01*
X341279Y195958D01*
X341112Y196208D01*
X340862Y196417D01*
X340529Y196500D01*
G01X342837Y196083D02*
X343087Y196333D01*
X343379Y196458D01*
X343712Y196500D01*
X344129Y196417D01*
X344421Y196208D01*
X344504Y195958D01*
X344462Y195708D01*
X344296Y195500D01*
X343462Y195083D01*
X343087Y194792D01*
X342837Y194375D01*
X342754Y194000D01*
X344504D01*
G01X318410Y213205D02*
X318743Y212997D01*
X319118Y212872D01*
X319452D01*
X319785Y212997D01*
X320035Y213205D01*
X320160Y213497D01*
X320077Y213789D01*
X319868Y214039D01*
X319493Y214205D01*
X318993Y214289D01*
X318702Y214455D01*
X318577Y214747D01*
X318660Y215039D01*
X318868Y215247D01*
X319160Y215372D01*
X319452D01*
X319743Y215289D01*
X319993Y215080D01*
G01X323302Y215164D02*
X323052Y215289D01*
X322760Y215372D01*
X322427D01*
X322052Y215247D01*
X321760Y215039D01*
X321552Y214789D01*
X321385Y214372D01*
X321343Y213997D01*
X321427Y213622D01*
X321552Y213372D01*
X321802Y213122D01*
X322093Y212955D01*
X322385Y212872D01*
X322677D01*
X322968Y212955D01*
X323218Y213080D01*
X323427Y213247D01*
G01X324777Y213164D02*
X325068Y212955D01*
X325402Y212872D01*
X325735Y212955D01*
X326027Y213205D01*
X326235Y213580D01*
X326318Y213955D01*
Y214414D01*
X326235Y214789D01*
X326027Y215122D01*
X325777Y215289D01*
X325485Y215372D01*
X325152Y215289D01*
X324902Y215122D01*
X324735Y214872D01*
X324652Y214539D01*
X324735Y214247D01*
X324943Y213955D01*
X325193Y213789D01*
X325485Y213747D01*
X325818Y213830D01*
X326068Y214039D01*
X326318Y214414D01*
G01X328585Y212872D02*
Y215372D01*
X328085Y214872D01*
G01Y212872D02*
X329085D01*
G01X330977Y213164D02*
X331268Y212955D01*
X331602Y212872D01*
X331935Y212955D01*
X332227Y213205D01*
X332435Y213580D01*
X332518Y213955D01*
Y214414D01*
X332435Y214789D01*
X332227Y215122D01*
X331977Y215289D01*
X331685Y215372D01*
X331352Y215289D01*
X331102Y215122D01*
X330935Y214872D01*
X330852Y214539D01*
X330935Y214247D01*
X331143Y213955D01*
X331393Y213789D01*
X331685Y213747D01*
X332018Y213830D01*
X332268Y214039D01*
X332518Y214414D01*
G01X318354Y208833D02*
X318687Y208625D01*
X319062Y208500D01*
X319396D01*
X319729Y208625D01*
X319979Y208833D01*
X320104Y209125D01*
X320021Y209417D01*
X319812Y209667D01*
X319437Y209833D01*
X318937Y209917D01*
X318646Y210083D01*
X318521Y210375D01*
X318604Y210667D01*
X318812Y210875D01*
X319104Y211000D01*
X319396D01*
X319687Y210917D01*
X319937Y210708D01*
G01X323246Y210792D02*
X322996Y210917D01*
X322704Y211000D01*
X322371D01*
X321996Y210875D01*
X321704Y210667D01*
X321496Y210417D01*
X321329Y210000D01*
X321287Y209625D01*
X321371Y209250D01*
X321496Y209000D01*
X321746Y208750D01*
X322037Y208583D01*
X322329Y208500D01*
X322621D01*
X322912Y208583D01*
X323162Y208708D01*
X323371Y208875D01*
G01X324721Y208792D02*
X325012Y208583D01*
X325346Y208500D01*
X325679Y208583D01*
X325971Y208833D01*
X326179Y209208D01*
X326262Y209583D01*
Y210042D01*
X326179Y210417D01*
X325971Y210750D01*
X325721Y210917D01*
X325429Y211000D01*
X325096Y210917D01*
X324846Y210750D01*
X324679Y210500D01*
X324596Y210167D01*
X324679Y209875D01*
X324887Y209583D01*
X325137Y209417D01*
X325429Y209375D01*
X325762Y209458D01*
X326012Y209667D01*
X326262Y210042D01*
G01X327737Y210583D02*
X327987Y210833D01*
X328279Y210958D01*
X328612Y211000D01*
X329029Y210917D01*
X329321Y210708D01*
X329404Y210458D01*
X329362Y210208D01*
X329196Y210000D01*
X328362Y209583D01*
X327987Y209292D01*
X327737Y208875D01*
X327654Y208500D01*
X329404D01*
G01X331629Y211000D02*
X331296Y210917D01*
X331046Y210708D01*
X330879Y210458D01*
X330754Y210125D01*
X330712Y209750D01*
X330754Y209375D01*
X330879Y209042D01*
X331046Y208792D01*
X331296Y208583D01*
X331629Y208500D01*
X331962Y208583D01*
X332212Y208792D01*
X332379Y209042D01*
X332504Y209375D01*
X332546Y209750D01*
X332504Y210125D01*
X332379Y210458D01*
X332212Y210708D01*
X331962Y210917D01*
X331629Y211000D01*
G01X344629Y244250D02*
X329229D01*
G01D02*
Y266750D01*
G01X327985Y240672D02*
X320985D01*
Y254072D01*
X327985D01*
Y240672D01*
G01X319985Y250572D02*
X315985D01*
Y243172D01*
G01X326167Y256525D02*
X326375Y256858D01*
X326500Y257233D01*
Y257567D01*
X326375Y257900D01*
X326167Y258150D01*
X325875Y258275D01*
X325583Y258192D01*
X325333Y257983D01*
X325167Y257608D01*
X325083Y257108D01*
X324917Y256817D01*
X324625Y256692D01*
X324333Y256775D01*
X324125Y256983D01*
X324000Y257275D01*
Y257567D01*
X324083Y257858D01*
X324292Y258108D01*
G01X326500Y259625D02*
X324000Y261375D01*
G01Y259625D02*
X326500Y261375D01*
G01Y263600D02*
X324000D01*
X324500Y263100D01*
G01X326500D02*
Y264100D01*
G01X329229Y266750D02*
X344629D01*
G01X329096Y271875D02*
X329304Y272208D01*
X329429Y272583D01*
Y272917D01*
X329304Y273250D01*
X329096Y273500D01*
X328804Y273625D01*
X328512Y273542D01*
X328262Y273333D01*
X328096Y272958D01*
X328012Y272458D01*
X327846Y272167D01*
X327554Y272042D01*
X327262Y272125D01*
X327054Y272333D01*
X326929Y272625D01*
Y272917D01*
X327012Y273208D01*
X327221Y273458D01*
G01X327137Y276767D02*
X327012Y276517D01*
X326929Y276225D01*
Y275892D01*
X327054Y275517D01*
X327262Y275225D01*
X327512Y275017D01*
X327929Y274850D01*
X328304Y274808D01*
X328679Y274892D01*
X328929Y275017D01*
X329179Y275267D01*
X329346Y275558D01*
X329429Y275850D01*
Y276142D01*
X329346Y276433D01*
X329221Y276683D01*
X329054Y276892D01*
G01X329429Y278950D02*
X326929D01*
X327429Y278450D01*
G01X329429D02*
Y279450D01*
G01Y282050D02*
X326929D01*
X327429Y281550D01*
G01X329429D02*
Y282550D01*
G01X329137Y284442D02*
X329346Y284733D01*
X329429Y285067D01*
X329346Y285400D01*
X329096Y285692D01*
X328721Y285900D01*
X328346Y285983D01*
X327887D01*
X327512Y285900D01*
X327179Y285692D01*
X327012Y285442D01*
X326929Y285150D01*
X327012Y284817D01*
X327179Y284567D01*
X327429Y284400D01*
X327762Y284317D01*
X328054Y284400D01*
X328346Y284608D01*
X328512Y284858D01*
X328554Y285150D01*
X328471Y285483D01*
X328262Y285733D01*
X327887Y285983D01*
G01X329429Y288750D02*
X326929D01*
X328721Y287208D01*
Y289292D01*
G01X329096Y290875D02*
X329304Y291208D01*
X329429Y291583D01*
Y291917D01*
X329304Y292250D01*
X329096Y292500D01*
X328804Y292625D01*
X328512Y292542D01*
X328262Y292333D01*
X328096Y291958D01*
X328012Y291458D01*
X327846Y291167D01*
X327554Y291042D01*
X327262Y291125D01*
X327054Y291333D01*
X326929Y291625D01*
Y291917D01*
X327012Y292208D01*
X327221Y292458D01*
G01X327137Y295767D02*
X327012Y295517D01*
X326929Y295225D01*
Y294892D01*
X327054Y294517D01*
X327262Y294225D01*
X327512Y294017D01*
X327929Y293850D01*
X328304Y293808D01*
X328679Y293892D01*
X328929Y294017D01*
X329179Y294267D01*
X329346Y294558D01*
X329429Y294850D01*
Y295142D01*
X329346Y295433D01*
X329221Y295683D01*
X329054Y295892D01*
G01X329429Y297950D02*
X326929D01*
X327429Y297450D01*
G01X329429D02*
Y298450D01*
G01Y301050D02*
X326929D01*
X327429Y300550D01*
G01X329429D02*
Y301550D01*
G01X329054Y303233D02*
X329262Y303483D01*
X329387Y303775D01*
X329429Y304150D01*
X329346Y304525D01*
X329179Y304817D01*
X328887Y305025D01*
X328554Y305067D01*
X328221Y304983D01*
X328012Y304775D01*
X327846Y304483D01*
X327804Y304192D01*
X327846Y303900D01*
X328012Y303525D01*
X326929Y303650D01*
Y304775D01*
G01X329429Y307750D02*
X326929D01*
X328721Y306208D01*
Y308292D01*
G01X313805Y315152D02*
Y311152D01*
X321205D01*
G01X313729Y336500D02*
Y332500D01*
X321129D01*
G01X325667Y368375D02*
X325875Y368708D01*
X326000Y369083D01*
Y369417D01*
X325875Y369750D01*
X325667Y370000D01*
X325375Y370125D01*
X325083Y370042D01*
X324833Y369833D01*
X324667Y369458D01*
X324583Y368958D01*
X324417Y368667D01*
X324125Y368542D01*
X323833Y368625D01*
X323625Y368833D01*
X323500Y369125D01*
Y369417D01*
X323583Y369708D01*
X323792Y369958D01*
G01X323708Y373267D02*
X323583Y373017D01*
X323500Y372725D01*
Y372392D01*
X323625Y372017D01*
X323833Y371725D01*
X324083Y371517D01*
X324500Y371350D01*
X324875Y371308D01*
X325250Y371392D01*
X325500Y371517D01*
X325750Y371767D01*
X325917Y372058D01*
X326000Y372350D01*
Y372642D01*
X325917Y372933D01*
X325792Y373183D01*
X325625Y373392D01*
G01X326000Y375450D02*
X323500D01*
X324000Y374950D01*
G01X326000D02*
Y375950D01*
G01Y378550D02*
X323500D01*
X324000Y378050D01*
G01X326000D02*
Y379050D01*
G01X325708Y380942D02*
X325917Y381233D01*
X326000Y381567D01*
X325917Y381900D01*
X325667Y382192D01*
X325292Y382400D01*
X324917Y382483D01*
X324458D01*
X324083Y382400D01*
X323750Y382192D01*
X323583Y381942D01*
X323500Y381650D01*
X323583Y381317D01*
X323750Y381067D01*
X324000Y380900D01*
X324333Y380817D01*
X324625Y380900D01*
X324917Y381108D01*
X325083Y381358D01*
X325125Y381650D01*
X325042Y381983D01*
X324833Y382233D01*
X324458Y382483D01*
G01X326000Y384750D02*
X325958Y385042D01*
X325833Y385375D01*
X325625Y385583D01*
X325333Y385667D01*
X325042Y385583D01*
X324792Y385333D01*
X324667Y384958D01*
Y384542D01*
X324583Y384292D01*
X324375Y384083D01*
X324083Y384000D01*
X323792Y384125D01*
X323583Y384417D01*
X323500Y384750D01*
X323583Y385083D01*
X323792Y385375D01*
X324083Y385500D01*
X324375Y385417D01*
X324583Y385208D01*
X324667Y384958D01*
Y384542D01*
X324792Y384167D01*
X325042Y383917D01*
X325333Y383833D01*
X325625Y383917D01*
X325833Y384125D01*
X325958Y384458D01*
X326000Y384750D01*
G01X330096Y368375D02*
X330304Y368708D01*
X330429Y369083D01*
Y369417D01*
X330304Y369750D01*
X330096Y370000D01*
X329804Y370125D01*
X329512Y370042D01*
X329262Y369833D01*
X329096Y369458D01*
X329012Y368958D01*
X328846Y368667D01*
X328554Y368542D01*
X328262Y368625D01*
X328054Y368833D01*
X327929Y369125D01*
Y369417D01*
X328012Y369708D01*
X328221Y369958D01*
G01X328137Y373267D02*
X328012Y373017D01*
X327929Y372725D01*
Y372392D01*
X328054Y372017D01*
X328262Y371725D01*
X328512Y371517D01*
X328929Y371350D01*
X329304Y371308D01*
X329679Y371392D01*
X329929Y371517D01*
X330179Y371767D01*
X330346Y372058D01*
X330429Y372350D01*
Y372642D01*
X330346Y372933D01*
X330221Y373183D01*
X330054Y373392D01*
G01X330429Y375450D02*
X327929D01*
X328429Y374950D01*
G01X330429D02*
Y375950D01*
G01Y378550D02*
X327929D01*
X328429Y378050D01*
G01X330429D02*
Y379050D01*
G01X330137Y380942D02*
X330346Y381233D01*
X330429Y381567D01*
X330346Y381900D01*
X330096Y382192D01*
X329721Y382400D01*
X329346Y382483D01*
X328887D01*
X328512Y382400D01*
X328179Y382192D01*
X328012Y381942D01*
X327929Y381650D01*
X328012Y381317D01*
X328179Y381067D01*
X328429Y380900D01*
X328762Y380817D01*
X329054Y380900D01*
X329346Y381108D01*
X329512Y381358D01*
X329554Y381650D01*
X329471Y381983D01*
X329262Y382233D01*
X328887Y382483D01*
G01X330137Y384042D02*
X330346Y384333D01*
X330429Y384667D01*
X330346Y385000D01*
X330096Y385292D01*
X329721Y385500D01*
X329346Y385583D01*
X328887D01*
X328512Y385500D01*
X328179Y385292D01*
X328012Y385042D01*
X327929Y384750D01*
X328012Y384417D01*
X328179Y384167D01*
X328429Y384000D01*
X328762Y383917D01*
X329054Y384000D01*
X329346Y384208D01*
X329512Y384458D01*
X329554Y384750D01*
X329471Y385083D01*
X329262Y385333D01*
X328887Y385583D01*
G01X320167Y392375D02*
X320375Y392708D01*
X320500Y393083D01*
Y393417D01*
X320375Y393750D01*
X320167Y394000D01*
X319875Y394125D01*
X319583Y394042D01*
X319333Y393833D01*
X319167Y393458D01*
X319083Y392958D01*
X318917Y392667D01*
X318625Y392542D01*
X318333Y392625D01*
X318125Y392833D01*
X318000Y393125D01*
Y393417D01*
X318083Y393708D01*
X318292Y393958D01*
G01X318208Y397267D02*
X318083Y397017D01*
X318000Y396725D01*
Y396392D01*
X318125Y396017D01*
X318333Y395725D01*
X318583Y395517D01*
X319000Y395350D01*
X319375Y395308D01*
X319750Y395392D01*
X320000Y395517D01*
X320250Y395767D01*
X320417Y396058D01*
X320500Y396350D01*
Y396642D01*
X320417Y396933D01*
X320292Y397183D01*
X320125Y397392D01*
G01X320500Y399450D02*
X318000D01*
X318500Y398950D01*
G01X320500D02*
Y399950D01*
G01X318417Y401758D02*
X318167Y402008D01*
X318042Y402300D01*
X318000Y402633D01*
X318083Y403050D01*
X318292Y403342D01*
X318542Y403425D01*
X318792Y403383D01*
X319000Y403217D01*
X319417Y402383D01*
X319708Y402008D01*
X320125Y401758D01*
X320500Y401675D01*
Y403425D01*
G01X320000Y404733D02*
X320292Y404983D01*
X320458Y405317D01*
X320500Y405692D01*
X320458Y406025D01*
X320250Y406358D01*
X320000Y406567D01*
X319750Y406608D01*
X319458Y406525D01*
X319250Y406233D01*
X319167Y405942D01*
Y405567D01*
G01Y405942D02*
X319042Y406192D01*
X318833Y406400D01*
X318583Y406483D01*
X318333Y406400D01*
X318125Y406192D01*
X318000Y405817D01*
X318042Y405442D01*
X318208Y405067D01*
G01X320125Y407833D02*
X320333Y408083D01*
X320458Y408375D01*
X320500Y408750D01*
X320417Y409125D01*
X320250Y409417D01*
X319958Y409625D01*
X319625Y409667D01*
X319292Y409583D01*
X319083Y409375D01*
X318917Y409083D01*
X318875Y408792D01*
X318917Y408500D01*
X319083Y408125D01*
X318000Y408250D01*
Y409375D01*
G01X316222Y392375D02*
X316430Y392708D01*
X316555Y393083D01*
Y393417D01*
X316430Y393750D01*
X316222Y394000D01*
X315930Y394125D01*
X315638Y394042D01*
X315388Y393833D01*
X315222Y393458D01*
X315138Y392958D01*
X314972Y392667D01*
X314680Y392542D01*
X314388Y392625D01*
X314180Y392833D01*
X314055Y393125D01*
Y393417D01*
X314138Y393708D01*
X314347Y393958D01*
G01X314263Y397267D02*
X314138Y397017D01*
X314055Y396725D01*
Y396392D01*
X314180Y396017D01*
X314388Y395725D01*
X314638Y395517D01*
X315055Y395350D01*
X315430Y395308D01*
X315805Y395392D01*
X316055Y395517D01*
X316305Y395767D01*
X316472Y396058D01*
X316555Y396350D01*
Y396642D01*
X316472Y396933D01*
X316347Y397183D01*
X316180Y397392D01*
G01X316555Y399450D02*
X314055D01*
X314555Y398950D01*
G01X316555D02*
Y399950D01*
G01X314472Y401758D02*
X314222Y402008D01*
X314097Y402300D01*
X314055Y402633D01*
X314138Y403050D01*
X314347Y403342D01*
X314597Y403425D01*
X314847Y403383D01*
X315055Y403217D01*
X315472Y402383D01*
X315763Y402008D01*
X316180Y401758D01*
X316555Y401675D01*
Y403425D01*
G01X316055Y404733D02*
X316347Y404983D01*
X316513Y405317D01*
X316555Y405692D01*
X316513Y406025D01*
X316305Y406358D01*
X316055Y406567D01*
X315805Y406608D01*
X315513Y406525D01*
X315305Y406233D01*
X315222Y405942D01*
Y405567D01*
G01Y405942D02*
X315097Y406192D01*
X314888Y406400D01*
X314638Y406483D01*
X314388Y406400D01*
X314180Y406192D01*
X314055Y405817D01*
X314097Y405442D01*
X314263Y405067D01*
G01X316555Y408750D02*
X314055D01*
X314555Y408250D01*
G01X316555D02*
Y409250D01*
G01X322723Y462283D02*
Y466283D01*
X315323D01*
G01X322723Y457783D02*
Y461783D01*
X315323D01*
G01X322693Y452373D02*
Y456373D01*
X315293D01*
G01X323723Y477783D02*
Y481783D01*
X316323D01*
G01X323723Y473283D02*
Y477283D01*
X316323D01*
G01X339823Y487483D02*
X328523D01*
G01X321955Y529000D02*
X320505Y527550D01*
G01Y530450D02*
X321955Y529000D01*
G01X320505Y534500D02*
Y523500D01*
G01D02*
X341105D01*
G01Y534500D02*
X320505D01*
G01X329722Y559925D02*
X329930Y560258D01*
X330055Y560633D01*
Y560967D01*
X329930Y561300D01*
X329722Y561550D01*
X329430Y561675D01*
X329138Y561592D01*
X328888Y561383D01*
X328722Y561008D01*
X328638Y560508D01*
X328472Y560217D01*
X328180Y560092D01*
X327888Y560175D01*
X327680Y560383D01*
X327555Y560675D01*
Y560967D01*
X327638Y561258D01*
X327847Y561508D01*
G01X330055Y563067D02*
X327555D01*
Y564108D01*
X327680Y564442D01*
X327847Y564650D01*
X328180Y564733D01*
X328513Y564650D01*
X328722Y564400D01*
X328847Y564108D01*
Y563067D01*
G01Y564108D02*
X330055Y564733D01*
G01X329763Y566292D02*
X329972Y566583D01*
X330055Y566917D01*
X329972Y567250D01*
X329722Y567542D01*
X329347Y567750D01*
X328972Y567833D01*
X328513D01*
X328138Y567750D01*
X327805Y567542D01*
X327638Y567292D01*
X327555Y567000D01*
X327638Y566667D01*
X327805Y566417D01*
X328055Y566250D01*
X328388Y566167D01*
X328680Y566250D01*
X328972Y566458D01*
X329138Y566708D01*
X329180Y567000D01*
X329097Y567333D01*
X328888Y567583D01*
X328513Y567833D01*
G01X327972Y569308D02*
X327722Y569558D01*
X327597Y569850D01*
X327555Y570183D01*
X327638Y570600D01*
X327847Y570892D01*
X328097Y570975D01*
X328347Y570933D01*
X328555Y570767D01*
X328972Y569933D01*
X329263Y569558D01*
X329680Y569308D01*
X330055Y569225D01*
Y570975D01*
G01X327555Y573200D02*
X327638Y572867D01*
X327847Y572617D01*
X328097Y572450D01*
X328430Y572325D01*
X328805Y572283D01*
X329180Y572325D01*
X329513Y572450D01*
X329763Y572617D01*
X329972Y572867D01*
X330055Y573200D01*
X329972Y573533D01*
X329763Y573783D01*
X329513Y573950D01*
X329180Y574075D01*
X328805Y574117D01*
X328430Y574075D01*
X328097Y573950D01*
X327847Y573783D01*
X327638Y573533D01*
X327555Y573200D01*
G01X327055Y550800D02*
X331055D01*
Y558200D01*
G01X320722Y555875D02*
X320930Y556208D01*
X321055Y556583D01*
Y556917D01*
X320930Y557250D01*
X320722Y557500D01*
X320430Y557625D01*
X320138Y557542D01*
X319888Y557333D01*
X319722Y556958D01*
X319638Y556458D01*
X319472Y556167D01*
X319180Y556042D01*
X318888Y556125D01*
X318680Y556333D01*
X318555Y556625D01*
Y556917D01*
X318638Y557208D01*
X318847Y557458D01*
G01X318763Y560767D02*
X318638Y560517D01*
X318555Y560225D01*
Y559892D01*
X318680Y559517D01*
X318888Y559225D01*
X319138Y559017D01*
X319555Y558850D01*
X319930Y558808D01*
X320305Y558892D01*
X320555Y559017D01*
X320805Y559267D01*
X320972Y559558D01*
X321055Y559850D01*
Y560142D01*
X320972Y560433D01*
X320847Y560683D01*
X320680Y560892D01*
G01X321055Y562950D02*
X318555D01*
X319055Y562450D01*
G01X321055D02*
Y563450D01*
G01Y566050D02*
X318555D01*
X319055Y565550D01*
G01X321055D02*
Y566550D01*
G01X318972Y568358D02*
X318722Y568608D01*
X318597Y568900D01*
X318555Y569233D01*
X318638Y569650D01*
X318847Y569942D01*
X319097Y570025D01*
X319347Y569983D01*
X319555Y569817D01*
X319972Y568983D01*
X320263Y568608D01*
X320680Y568358D01*
X321055Y568275D01*
Y570025D01*
G01X318555Y572250D02*
X318638Y571917D01*
X318847Y571667D01*
X319097Y571500D01*
X319430Y571375D01*
X319805Y571333D01*
X320180Y571375D01*
X320513Y571500D01*
X320763Y571667D01*
X320972Y571917D01*
X321055Y572250D01*
X320972Y572583D01*
X320763Y572833D01*
X320513Y573000D01*
X320180Y573125D01*
X319805Y573167D01*
X319430Y573125D01*
X319097Y573000D01*
X318847Y572833D01*
X318638Y572583D01*
X318555Y572250D01*
G01X325190Y556158D02*
X325398Y556491D01*
X325523Y556866D01*
Y557200D01*
X325398Y557533D01*
X325190Y557783D01*
X324898Y557908D01*
X324606Y557825D01*
X324356Y557616D01*
X324190Y557241D01*
X324106Y556741D01*
X323940Y556450D01*
X323648Y556325D01*
X323356Y556408D01*
X323148Y556616D01*
X323023Y556908D01*
Y557200D01*
X323106Y557491D01*
X323315Y557741D01*
G01X323231Y561050D02*
X323106Y560800D01*
X323023Y560508D01*
Y560175D01*
X323148Y559800D01*
X323356Y559508D01*
X323606Y559300D01*
X324023Y559133D01*
X324398Y559091D01*
X324773Y559175D01*
X325023Y559300D01*
X325273Y559550D01*
X325440Y559841D01*
X325523Y560133D01*
Y560425D01*
X325440Y560716D01*
X325315Y560966D01*
X325148Y561175D01*
G01X325523Y563233D02*
X323023D01*
X323523Y562733D01*
G01X325523D02*
Y563733D01*
G01Y566333D02*
X323023D01*
X323523Y565833D01*
G01X325523D02*
Y566833D01*
G01X323440Y568641D02*
X323190Y568891D01*
X323065Y569183D01*
X323023Y569516D01*
X323106Y569933D01*
X323315Y570225D01*
X323565Y570308D01*
X323815Y570266D01*
X324023Y570100D01*
X324440Y569266D01*
X324731Y568891D01*
X325148Y568641D01*
X325523Y568558D01*
Y570308D01*
G01Y572533D02*
X323023D01*
X323523Y572033D01*
G01X325523D02*
Y573033D01*
G01X317425Y877833D02*
X317758Y877625D01*
X318133Y877500D01*
X318467D01*
X318800Y877625D01*
X319050Y877833D01*
X319175Y878125D01*
X319092Y878417D01*
X318883Y878667D01*
X318508Y878833D01*
X318008Y878917D01*
X317717Y879083D01*
X317592Y879375D01*
X317675Y879667D01*
X317883Y879875D01*
X318175Y880000D01*
X318467D01*
X318758Y879917D01*
X319008Y879708D01*
G01X320567Y877500D02*
Y880000D01*
X321608D01*
X321942Y879875D01*
X322150Y879708D01*
X322233Y879375D01*
X322150Y879042D01*
X321900Y878833D01*
X321608Y878708D01*
X320567D01*
G01X321608D02*
X322233Y877500D01*
G01X323583Y878000D02*
X323833Y877708D01*
X324167Y877542D01*
X324542Y877500D01*
X324875Y877542D01*
X325208Y877750D01*
X325417Y878000D01*
X325458Y878250D01*
X325375Y878542D01*
X325083Y878750D01*
X324792Y878833D01*
X324417D01*
G01X324792D02*
X325042Y878958D01*
X325250Y879167D01*
X325333Y879417D01*
X325250Y879667D01*
X325042Y879875D01*
X324667Y880000D01*
X324292Y879958D01*
X323917Y879792D01*
G01X327600Y877500D02*
Y880000D01*
X327100Y879500D01*
G01Y877500D02*
X328100D01*
G01X330700D02*
Y880000D01*
X330200Y879500D01*
G01Y877500D02*
X331200D01*
G01X317425Y883833D02*
X317758Y883625D01*
X318133Y883500D01*
X318467D01*
X318800Y883625D01*
X319050Y883833D01*
X319175Y884125D01*
X319092Y884417D01*
X318883Y884667D01*
X318508Y884833D01*
X318008Y884917D01*
X317717Y885083D01*
X317592Y885375D01*
X317675Y885667D01*
X317883Y885875D01*
X318175Y886000D01*
X318467D01*
X318758Y885917D01*
X319008Y885708D01*
G01X320567Y883500D02*
Y886000D01*
X321608D01*
X321942Y885875D01*
X322150Y885708D01*
X322233Y885375D01*
X322150Y885042D01*
X321900Y884833D01*
X321608Y884708D01*
X320567D01*
G01X321608D02*
X322233Y883500D01*
G01X323583Y884000D02*
X323833Y883708D01*
X324167Y883542D01*
X324542Y883500D01*
X324875Y883542D01*
X325208Y883750D01*
X325417Y884000D01*
X325458Y884250D01*
X325375Y884542D01*
X325083Y884750D01*
X324792Y884833D01*
X324417D01*
G01X324792D02*
X325042Y884958D01*
X325250Y885167D01*
X325333Y885417D01*
X325250Y885667D01*
X325042Y885875D01*
X324667Y886000D01*
X324292Y885958D01*
X323917Y885792D01*
G01X327600Y883500D02*
Y886000D01*
X327100Y885500D01*
G01Y883500D02*
X328100D01*
G01X330700Y886000D02*
X330367Y885917D01*
X330117Y885708D01*
X329950Y885458D01*
X329825Y885125D01*
X329783Y884750D01*
X329825Y884375D01*
X329950Y884042D01*
X330117Y883792D01*
X330367Y883583D01*
X330700Y883500D01*
X331033Y883583D01*
X331283Y883792D01*
X331450Y884042D01*
X331575Y884375D01*
X331617Y884750D01*
X331575Y885125D01*
X331450Y885458D01*
X331283Y885708D01*
X331033Y885917D01*
X330700Y886000D01*
G01X317425Y892333D02*
X317758Y892125D01*
X318133Y892000D01*
X318467D01*
X318800Y892125D01*
X319050Y892333D01*
X319175Y892625D01*
X319092Y892917D01*
X318883Y893167D01*
X318508Y893333D01*
X318008Y893417D01*
X317717Y893583D01*
X317592Y893875D01*
X317675Y894167D01*
X317883Y894375D01*
X318175Y894500D01*
X318467D01*
X318758Y894417D01*
X319008Y894208D01*
G01X320567Y892000D02*
Y894500D01*
X321608D01*
X321942Y894375D01*
X322150Y894208D01*
X322233Y893875D01*
X322150Y893542D01*
X321900Y893333D01*
X321608Y893208D01*
X320567D01*
G01X321608D02*
X322233Y892000D01*
G01X323583Y892500D02*
X323833Y892208D01*
X324167Y892042D01*
X324542Y892000D01*
X324875Y892042D01*
X325208Y892250D01*
X325417Y892500D01*
X325458Y892750D01*
X325375Y893042D01*
X325083Y893250D01*
X324792Y893333D01*
X324417D01*
G01X324792D02*
X325042Y893458D01*
X325250Y893667D01*
X325333Y893917D01*
X325250Y894167D01*
X325042Y894375D01*
X324667Y894500D01*
X324292Y894458D01*
X323917Y894292D01*
G01X327600Y894500D02*
X327267Y894417D01*
X327017Y894208D01*
X326850Y893958D01*
X326725Y893625D01*
X326683Y893250D01*
X326725Y892875D01*
X326850Y892542D01*
X327017Y892292D01*
X327267Y892083D01*
X327600Y892000D01*
X327933Y892083D01*
X328183Y892292D01*
X328350Y892542D01*
X328475Y892875D01*
X328517Y893250D01*
X328475Y893625D01*
X328350Y893958D01*
X328183Y894208D01*
X327933Y894417D01*
X327600Y894500D01*
G01X330617Y892000D02*
X330700Y892542D01*
X330825Y893000D01*
X330992Y893417D01*
X331200Y893875D01*
X331533Y894500D01*
X329867D01*
G01X317425Y888333D02*
X317758Y888125D01*
X318133Y888000D01*
X318467D01*
X318800Y888125D01*
X319050Y888333D01*
X319175Y888625D01*
X319092Y888917D01*
X318883Y889167D01*
X318508Y889333D01*
X318008Y889417D01*
X317717Y889583D01*
X317592Y889875D01*
X317675Y890167D01*
X317883Y890375D01*
X318175Y890500D01*
X318467D01*
X318758Y890417D01*
X319008Y890208D01*
G01X320567Y888000D02*
Y890500D01*
X321608D01*
X321942Y890375D01*
X322150Y890208D01*
X322233Y889875D01*
X322150Y889542D01*
X321900Y889333D01*
X321608Y889208D01*
X320567D01*
G01X321608D02*
X322233Y888000D01*
G01X323583Y888500D02*
X323833Y888208D01*
X324167Y888042D01*
X324542Y888000D01*
X324875Y888042D01*
X325208Y888250D01*
X325417Y888500D01*
X325458Y888750D01*
X325375Y889042D01*
X325083Y889250D01*
X324792Y889333D01*
X324417D01*
G01X324792D02*
X325042Y889458D01*
X325250Y889667D01*
X325333Y889917D01*
X325250Y890167D01*
X325042Y890375D01*
X324667Y890500D01*
X324292Y890458D01*
X323917Y890292D01*
G01X327600Y890500D02*
X327267Y890417D01*
X327017Y890208D01*
X326850Y889958D01*
X326725Y889625D01*
X326683Y889250D01*
X326725Y888875D01*
X326850Y888542D01*
X327017Y888292D01*
X327267Y888083D01*
X327600Y888000D01*
X327933Y888083D01*
X328183Y888292D01*
X328350Y888542D01*
X328475Y888875D01*
X328517Y889250D01*
X328475Y889625D01*
X328350Y889958D01*
X328183Y890208D01*
X327933Y890417D01*
X327600Y890500D01*
G01X330700Y888000D02*
X330992Y888042D01*
X331325Y888167D01*
X331533Y888375D01*
X331617Y888667D01*
X331533Y888958D01*
X331283Y889208D01*
X330908Y889333D01*
X330492D01*
X330242Y889417D01*
X330033Y889625D01*
X329950Y889917D01*
X330075Y890208D01*
X330367Y890417D01*
X330700Y890500D01*
X331033Y890417D01*
X331325Y890208D01*
X331450Y889917D01*
X331367Y889625D01*
X331158Y889417D01*
X330908Y889333D01*
X330492D01*
X330117Y889208D01*
X329867Y888958D01*
X329783Y888667D01*
X329867Y888375D01*
X330075Y888167D01*
X330408Y888042D01*
X330700Y888000D01*
G01X329500Y905517D02*
X327000D01*
Y906558D01*
X327125Y906892D01*
X327292Y907100D01*
X327625Y907183D01*
X327958Y907100D01*
X328167Y906850D01*
X328292Y906558D01*
Y905517D01*
G01Y906558D02*
X329500Y907183D01*
G01X328458Y908658D02*
X328167Y908950D01*
X328000Y909200D01*
X327917Y909533D01*
X328000Y909825D01*
X328167Y910033D01*
X328417Y910200D01*
X328708Y910242D01*
X328958Y910200D01*
X329208Y910033D01*
X329417Y909783D01*
X329500Y909492D01*
X329417Y909158D01*
X329167Y908867D01*
X328792Y908700D01*
X328375Y908658D01*
X327833Y908742D01*
X327542Y908867D01*
X327250Y909075D01*
X327042Y909367D01*
X327000Y909658D01*
X327083Y909950D01*
X327292Y910158D01*
G01X329500Y912550D02*
X327000D01*
X327500Y912050D01*
G01X329500D02*
Y913050D01*
G01X329208Y914942D02*
X329417Y915233D01*
X329500Y915567D01*
X329417Y915900D01*
X329167Y916192D01*
X328792Y916400D01*
X328417Y916483D01*
X327958D01*
X327583Y916400D01*
X327250Y916192D01*
X327083Y915942D01*
X327000Y915650D01*
X327083Y915317D01*
X327250Y915067D01*
X327500Y914900D01*
X327833Y914817D01*
X328125Y914900D01*
X328417Y915108D01*
X328583Y915358D01*
X328625Y915650D01*
X328542Y915983D01*
X328333Y916233D01*
X327958Y916483D01*
G01X325000Y905517D02*
X322500D01*
Y906558D01*
X322625Y906892D01*
X322792Y907100D01*
X323125Y907183D01*
X323458Y907100D01*
X323667Y906850D01*
X323792Y906558D01*
Y905517D01*
G01Y906558D02*
X325000Y907183D01*
G01X323958Y908658D02*
X323667Y908950D01*
X323500Y909200D01*
X323417Y909533D01*
X323500Y909825D01*
X323667Y910033D01*
X323917Y910200D01*
X324208Y910242D01*
X324458Y910200D01*
X324708Y910033D01*
X324917Y909783D01*
X325000Y909492D01*
X324917Y909158D01*
X324667Y908867D01*
X324292Y908700D01*
X323875Y908658D01*
X323333Y908742D01*
X323042Y908867D01*
X322750Y909075D01*
X322542Y909367D01*
X322500Y909658D01*
X322583Y909950D01*
X322792Y910158D01*
G01X323958Y911758D02*
X323667Y912050D01*
X323500Y912300D01*
X323417Y912633D01*
X323500Y912925D01*
X323667Y913133D01*
X323917Y913300D01*
X324208Y913342D01*
X324458Y913300D01*
X324708Y913133D01*
X324917Y912883D01*
X325000Y912592D01*
X324917Y912258D01*
X324667Y911967D01*
X324292Y911800D01*
X323875Y911758D01*
X323333Y911842D01*
X323042Y911967D01*
X322750Y912175D01*
X322542Y912467D01*
X322500Y912758D01*
X322583Y913050D01*
X322792Y913258D01*
G01X322917Y914858D02*
X322667Y915108D01*
X322542Y915400D01*
X322500Y915733D01*
X322583Y916150D01*
X322792Y916442D01*
X323042Y916525D01*
X323292Y916483D01*
X323500Y916317D01*
X323917Y915483D01*
X324208Y915108D01*
X324625Y914858D01*
X325000Y914775D01*
Y916525D01*
G01X320500Y905517D02*
X318000D01*
Y906558D01*
X318125Y906892D01*
X318292Y907100D01*
X318625Y907183D01*
X318958Y907100D01*
X319167Y906850D01*
X319292Y906558D01*
Y905517D01*
G01Y906558D02*
X320500Y907183D01*
G01X319458Y908658D02*
X319167Y908950D01*
X319000Y909200D01*
X318917Y909533D01*
X319000Y909825D01*
X319167Y910033D01*
X319417Y910200D01*
X319708Y910242D01*
X319958Y910200D01*
X320208Y910033D01*
X320417Y909783D01*
X320500Y909492D01*
X320417Y909158D01*
X320167Y908867D01*
X319792Y908700D01*
X319375Y908658D01*
X318833Y908742D01*
X318542Y908867D01*
X318250Y909075D01*
X318042Y909367D01*
X318000Y909658D01*
X318083Y909950D01*
X318292Y910158D01*
G01X319458Y911758D02*
X319167Y912050D01*
X319000Y912300D01*
X318917Y912633D01*
X319000Y912925D01*
X319167Y913133D01*
X319417Y913300D01*
X319708Y913342D01*
X319958Y913300D01*
X320208Y913133D01*
X320417Y912883D01*
X320500Y912592D01*
X320417Y912258D01*
X320167Y911967D01*
X319792Y911800D01*
X319375Y911758D01*
X318833Y911842D01*
X318542Y911967D01*
X318250Y912175D01*
X318042Y912467D01*
X318000Y912758D01*
X318083Y913050D01*
X318292Y913258D01*
G01X320208Y914942D02*
X320417Y915233D01*
X320500Y915567D01*
X320417Y915900D01*
X320167Y916192D01*
X319792Y916400D01*
X319417Y916483D01*
X318958D01*
X318583Y916400D01*
X318250Y916192D01*
X318083Y915942D01*
X318000Y915650D01*
X318083Y915317D01*
X318250Y915067D01*
X318500Y914900D01*
X318833Y914817D01*
X319125Y914900D01*
X319417Y915108D01*
X319583Y915358D01*
X319625Y915650D01*
X319542Y915983D01*
X319333Y916233D01*
X318958Y916483D01*
G01X319475Y927333D02*
X319808Y927125D01*
X320183Y927000D01*
X320517D01*
X320850Y927125D01*
X321100Y927333D01*
X321225Y927625D01*
X321142Y927917D01*
X320933Y928167D01*
X320558Y928333D01*
X320058Y928417D01*
X319767Y928583D01*
X319642Y928875D01*
X319725Y929167D01*
X319933Y929375D01*
X320225Y929500D01*
X320517D01*
X320808Y929417D01*
X321058Y929208D01*
G01X322533Y929500D02*
Y927708D01*
X322700Y927333D01*
X323033Y927083D01*
X323450Y927000D01*
X323867Y927083D01*
X324200Y927333D01*
X324367Y927708D01*
Y929500D01*
G01X326550Y927000D02*
Y929500D01*
X326050Y929000D01*
G01Y927000D02*
X327050D01*
G01X328858Y928042D02*
X329150Y928333D01*
X329400Y928500D01*
X329733Y928583D01*
X330025Y928500D01*
X330233Y928333D01*
X330400Y928083D01*
X330442Y927792D01*
X330400Y927542D01*
X330233Y927292D01*
X329983Y927083D01*
X329692Y927000D01*
X329358Y927083D01*
X329067Y927333D01*
X328900Y927708D01*
X328858Y928125D01*
X328942Y928667D01*
X329067Y928958D01*
X329275Y929250D01*
X329567Y929458D01*
X329858Y929500D01*
X330150Y929417D01*
X330358Y929208D01*
G01X343600Y5700D02*
Y11200D01*
G01X351600Y5700D02*
X343600D01*
G01X334200Y11200D02*
Y5700D01*
G01X334900D02*
Y11200D01*
G01X342900Y5700D02*
X334900D01*
G01X342900Y11200D02*
Y5700D01*
G01X343600Y23300D02*
X351600D01*
G01X343600Y17800D02*
Y23300D01*
G01X334200D02*
Y17800D01*
G01X342900Y23300D02*
Y17800D01*
G01X334900Y23300D02*
X342900D01*
G01X334900Y17800D02*
Y23300D01*
G01X342367Y25000D02*
Y27500D01*
X343367D01*
X343700Y27375D01*
X343950Y27083D01*
X344033Y26750D01*
X343950Y26417D01*
X343742Y26167D01*
X343367Y26042D01*
X342367D01*
G01X347217Y27292D02*
X346967Y27417D01*
X346675Y27500D01*
X346342D01*
X345967Y27375D01*
X345675Y27167D01*
X345467Y26917D01*
X345300Y26500D01*
X345258Y26125D01*
X345342Y25750D01*
X345467Y25500D01*
X345717Y25250D01*
X346008Y25083D01*
X346300Y25000D01*
X346592D01*
X346883Y25083D01*
X347133Y25208D01*
X347342Y25375D01*
G01X348608Y27083D02*
X348858Y27333D01*
X349150Y27458D01*
X349483Y27500D01*
X349900Y27417D01*
X350192Y27208D01*
X350275Y26958D01*
X350233Y26708D01*
X350067Y26500D01*
X349233Y26083D01*
X348858Y25792D01*
X348608Y25375D01*
X348525Y25000D01*
X350275D01*
G01X352500Y27500D02*
X352167Y27417D01*
X351917Y27208D01*
X351750Y26958D01*
X351625Y26625D01*
X351583Y26250D01*
X351625Y25875D01*
X351750Y25542D01*
X351917Y25292D01*
X352167Y25083D01*
X352500Y25000D01*
X352833Y25083D01*
X353083Y25292D01*
X353250Y25542D01*
X353375Y25875D01*
X353417Y26250D01*
X353375Y26625D01*
X353250Y26958D01*
X353083Y27208D01*
X352833Y27417D01*
X352500Y27500D01*
G01X354808Y27083D02*
X355058Y27333D01*
X355350Y27458D01*
X355683Y27500D01*
X356100Y27417D01*
X356392Y27208D01*
X356475Y26958D01*
X356433Y26708D01*
X356267Y26500D01*
X355433Y26083D01*
X355058Y25792D01*
X354808Y25375D01*
X354725Y25000D01*
X356475D01*
G01X333022Y64424D02*
X338022D01*
Y69424D01*
G01Y82424D02*
Y87424D01*
X333022D01*
G01X336930Y78290D02*
X339930D01*
G01X339000Y103340D02*
X343000D01*
Y110740D01*
G01X345000Y103229D02*
X349000D01*
Y110629D01*
G01X331000Y92300D02*
X335000D01*
Y99700D01*
G01X343000D02*
X339000D01*
Y92300D01*
G01X338025Y122833D02*
X338358Y122625D01*
X338733Y122500D01*
X339067D01*
X339400Y122625D01*
X339650Y122833D01*
X339775Y123125D01*
X339692Y123417D01*
X339483Y123667D01*
X339108Y123833D01*
X338608Y123917D01*
X338317Y124083D01*
X338192Y124375D01*
X338275Y124667D01*
X338483Y124875D01*
X338775Y125000D01*
X339067D01*
X339358Y124917D01*
X339608Y124708D01*
G01X341167Y125000D02*
Y122500D01*
X342833D01*
G01X344392Y122792D02*
X344683Y122583D01*
X345017Y122500D01*
X345350Y122583D01*
X345642Y122833D01*
X345850Y123208D01*
X345933Y123583D01*
Y124042D01*
X345850Y124417D01*
X345642Y124750D01*
X345392Y124917D01*
X345100Y125000D01*
X344767Y124917D01*
X344517Y124750D01*
X344350Y124500D01*
X344267Y124167D01*
X344350Y123875D01*
X344558Y123583D01*
X344808Y123417D01*
X345100Y123375D01*
X345433Y123458D01*
X345683Y123667D01*
X345933Y124042D01*
G01X339000Y110840D02*
X343000D01*
Y118240D01*
G01X349000Y118129D02*
X345000D01*
Y110729D01*
G01X334167Y128425D02*
X334375Y128758D01*
X334500Y129133D01*
Y129467D01*
X334375Y129800D01*
X334167Y130050D01*
X333875Y130175D01*
X333583Y130092D01*
X333333Y129883D01*
X333167Y129508D01*
X333083Y129008D01*
X332917Y128717D01*
X332625Y128592D01*
X332333Y128675D01*
X332125Y128883D01*
X332000Y129175D01*
Y129467D01*
X332083Y129758D01*
X332292Y130008D01*
G01X332208Y133317D02*
X332083Y133067D01*
X332000Y132775D01*
Y132442D01*
X332125Y132067D01*
X332333Y131775D01*
X332583Y131567D01*
X333000Y131400D01*
X333375Y131358D01*
X333750Y131442D01*
X334000Y131567D01*
X334250Y131817D01*
X334417Y132108D01*
X334500Y132400D01*
Y132692D01*
X334417Y132983D01*
X334292Y133233D01*
X334125Y133442D01*
G01X334208Y134792D02*
X334417Y135083D01*
X334500Y135417D01*
X334417Y135750D01*
X334167Y136042D01*
X333792Y136250D01*
X333417Y136333D01*
X332958D01*
X332583Y136250D01*
X332250Y136042D01*
X332083Y135792D01*
X332000Y135500D01*
X332083Y135167D01*
X332250Y134917D01*
X332500Y134750D01*
X332833Y134667D01*
X333125Y134750D01*
X333417Y134958D01*
X333583Y135208D01*
X333625Y135500D01*
X333542Y135833D01*
X333333Y136083D01*
X332958Y136333D01*
G01X333458Y137808D02*
X333167Y138100D01*
X333000Y138350D01*
X332917Y138683D01*
X333000Y138975D01*
X333167Y139183D01*
X333417Y139350D01*
X333708Y139392D01*
X333958Y139350D01*
X334208Y139183D01*
X334417Y138933D01*
X334500Y138642D01*
X334417Y138308D01*
X334167Y138017D01*
X333792Y137850D01*
X333375Y137808D01*
X332833Y137892D01*
X332542Y138017D01*
X332250Y138225D01*
X332042Y138517D01*
X332000Y138808D01*
X332083Y139100D01*
X332292Y139308D01*
G01X334125Y140783D02*
X334333Y141033D01*
X334458Y141325D01*
X334500Y141700D01*
X334417Y142075D01*
X334250Y142367D01*
X333958Y142575D01*
X333625Y142617D01*
X333292Y142533D01*
X333083Y142325D01*
X332917Y142033D01*
X332875Y141742D01*
X332917Y141450D01*
X333083Y141075D01*
X332000Y141200D01*
Y142325D01*
G01X330465Y182333D02*
X330798Y182125D01*
X331173Y182000D01*
X331507D01*
X331840Y182125D01*
X332090Y182333D01*
X332215Y182625D01*
X332132Y182917D01*
X331923Y183167D01*
X331548Y183333D01*
X331048Y183417D01*
X330757Y183583D01*
X330632Y183875D01*
X330715Y184167D01*
X330923Y184375D01*
X331215Y184500D01*
X331507D01*
X331798Y184417D01*
X332048Y184208D01*
G01X335357Y184292D02*
X335107Y184417D01*
X334815Y184500D01*
X334482D01*
X334107Y184375D01*
X333815Y184167D01*
X333607Y183917D01*
X333440Y183500D01*
X333398Y183125D01*
X333482Y182750D01*
X333607Y182500D01*
X333857Y182250D01*
X334148Y182083D01*
X334440Y182000D01*
X334732D01*
X335023Y182083D01*
X335273Y182208D01*
X335482Y182375D01*
G01X337540Y182000D02*
X337832Y182042D01*
X338165Y182167D01*
X338373Y182375D01*
X338457Y182667D01*
X338373Y182958D01*
X338123Y183208D01*
X337748Y183333D01*
X337332D01*
X337082Y183417D01*
X336873Y183625D01*
X336790Y183917D01*
X336915Y184208D01*
X337207Y184417D01*
X337540Y184500D01*
X337873Y184417D01*
X338165Y184208D01*
X338290Y183917D01*
X338207Y183625D01*
X337998Y183417D01*
X337748Y183333D01*
X337332D01*
X336957Y183208D01*
X336707Y182958D01*
X336623Y182667D01*
X336707Y182375D01*
X336915Y182167D01*
X337248Y182042D01*
X337540Y182000D01*
G01X339932Y182292D02*
X340223Y182083D01*
X340557Y182000D01*
X340890Y182083D01*
X341182Y182333D01*
X341390Y182708D01*
X341473Y183083D01*
Y183542D01*
X341390Y183917D01*
X341182Y184250D01*
X340932Y184417D01*
X340640Y184500D01*
X340307Y184417D01*
X340057Y184250D01*
X339890Y184000D01*
X339807Y183667D01*
X339890Y183375D01*
X340098Y183083D01*
X340348Y182917D01*
X340640Y182875D01*
X340973Y182958D01*
X341223Y183167D01*
X341473Y183542D01*
G01X343740Y184500D02*
X343407Y184417D01*
X343157Y184208D01*
X342990Y183958D01*
X342865Y183625D01*
X342823Y183250D01*
X342865Y182875D01*
X342990Y182542D01*
X343157Y182292D01*
X343407Y182083D01*
X343740Y182000D01*
X344073Y182083D01*
X344323Y182292D01*
X344490Y182542D01*
X344615Y182875D01*
X344657Y183250D01*
X344615Y183625D01*
X344490Y183958D01*
X344323Y184208D01*
X344073Y184417D01*
X343740Y184500D01*
G01X330465Y186333D02*
X330798Y186125D01*
X331173Y186000D01*
X331507D01*
X331840Y186125D01*
X332090Y186333D01*
X332215Y186625D01*
X332132Y186917D01*
X331923Y187167D01*
X331548Y187333D01*
X331048Y187417D01*
X330757Y187583D01*
X330632Y187875D01*
X330715Y188167D01*
X330923Y188375D01*
X331215Y188500D01*
X331507D01*
X331798Y188417D01*
X332048Y188208D01*
G01X335357Y188292D02*
X335107Y188417D01*
X334815Y188500D01*
X334482D01*
X334107Y188375D01*
X333815Y188167D01*
X333607Y187917D01*
X333440Y187500D01*
X333398Y187125D01*
X333482Y186750D01*
X333607Y186500D01*
X333857Y186250D01*
X334148Y186083D01*
X334440Y186000D01*
X334732D01*
X335023Y186083D01*
X335273Y186208D01*
X335482Y186375D01*
G01X337540Y186000D02*
X337832Y186042D01*
X338165Y186167D01*
X338373Y186375D01*
X338457Y186667D01*
X338373Y186958D01*
X338123Y187208D01*
X337748Y187333D01*
X337332D01*
X337082Y187417D01*
X336873Y187625D01*
X336790Y187917D01*
X336915Y188208D01*
X337207Y188417D01*
X337540Y188500D01*
X337873Y188417D01*
X338165Y188208D01*
X338290Y187917D01*
X338207Y187625D01*
X337998Y187417D01*
X337748Y187333D01*
X337332D01*
X336957Y187208D01*
X336707Y186958D01*
X336623Y186667D01*
X336707Y186375D01*
X336915Y186167D01*
X337248Y186042D01*
X337540Y186000D01*
G01X339932Y186292D02*
X340223Y186083D01*
X340557Y186000D01*
X340890Y186083D01*
X341182Y186333D01*
X341390Y186708D01*
X341473Y187083D01*
Y187542D01*
X341390Y187917D01*
X341182Y188250D01*
X340932Y188417D01*
X340640Y188500D01*
X340307Y188417D01*
X340057Y188250D01*
X339890Y188000D01*
X339807Y187667D01*
X339890Y187375D01*
X340098Y187083D01*
X340348Y186917D01*
X340640Y186875D01*
X340973Y186958D01*
X341223Y187167D01*
X341473Y187542D01*
G01X343740Y186000D02*
Y188500D01*
X343240Y188000D01*
G01Y186000D02*
X344240D01*
G01X343096Y199925D02*
X343304Y200258D01*
X343429Y200633D01*
Y200967D01*
X343304Y201300D01*
X343096Y201550D01*
X342804Y201675D01*
X342512Y201592D01*
X342262Y201383D01*
X342096Y201008D01*
X342012Y200508D01*
X341846Y200217D01*
X341554Y200092D01*
X341262Y200175D01*
X341054Y200383D01*
X340929Y200675D01*
Y200967D01*
X341012Y201258D01*
X341221Y201508D01*
G01X343429Y203067D02*
X340929D01*
Y204108D01*
X341054Y204442D01*
X341221Y204650D01*
X341554Y204733D01*
X341887Y204650D01*
X342096Y204400D01*
X342221Y204108D01*
Y203067D01*
G01Y204108D02*
X343429Y204733D01*
G01X343137Y206292D02*
X343346Y206583D01*
X343429Y206917D01*
X343346Y207250D01*
X343096Y207542D01*
X342721Y207750D01*
X342346Y207833D01*
X341887D01*
X341512Y207750D01*
X341179Y207542D01*
X341012Y207292D01*
X340929Y207000D01*
X341012Y206667D01*
X341179Y206417D01*
X341429Y206250D01*
X341762Y206167D01*
X342054Y206250D01*
X342346Y206458D01*
X342512Y206708D01*
X342554Y207000D01*
X342471Y207333D01*
X342262Y207583D01*
X341887Y207833D01*
G01X341346Y209308D02*
X341096Y209558D01*
X340971Y209850D01*
X340929Y210183D01*
X341012Y210600D01*
X341221Y210892D01*
X341471Y210975D01*
X341721Y210933D01*
X341929Y210767D01*
X342346Y209933D01*
X342637Y209558D01*
X343054Y209308D01*
X343429Y209225D01*
Y210975D01*
G01X341346Y212408D02*
X341096Y212658D01*
X340971Y212950D01*
X340929Y213283D01*
X341012Y213700D01*
X341221Y213992D01*
X341471Y214075D01*
X341721Y214033D01*
X341929Y213867D01*
X342346Y213033D01*
X342637Y212658D01*
X343054Y212408D01*
X343429Y212325D01*
Y214075D01*
G01X343167Y218925D02*
X343375Y219258D01*
X343500Y219633D01*
Y219967D01*
X343375Y220300D01*
X343167Y220550D01*
X342875Y220675D01*
X342583Y220592D01*
X342333Y220383D01*
X342167Y220008D01*
X342083Y219508D01*
X341917Y219217D01*
X341625Y219092D01*
X341333Y219175D01*
X341125Y219383D01*
X341000Y219675D01*
Y219967D01*
X341083Y220258D01*
X341292Y220508D01*
G01X341208Y223817D02*
X341083Y223567D01*
X341000Y223275D01*
Y222942D01*
X341125Y222567D01*
X341333Y222275D01*
X341583Y222067D01*
X342000Y221900D01*
X342375Y221858D01*
X342750Y221942D01*
X343000Y222067D01*
X343250Y222317D01*
X343417Y222608D01*
X343500Y222900D01*
Y223192D01*
X343417Y223483D01*
X343292Y223733D01*
X343125Y223942D01*
G01X343500Y226000D02*
X343458Y226292D01*
X343333Y226625D01*
X343125Y226833D01*
X342833Y226917D01*
X342542Y226833D01*
X342292Y226583D01*
X342167Y226208D01*
Y225792D01*
X342083Y225542D01*
X341875Y225333D01*
X341583Y225250D01*
X341292Y225375D01*
X341083Y225667D01*
X341000Y226000D01*
X341083Y226333D01*
X341292Y226625D01*
X341583Y226750D01*
X341875Y226667D01*
X342083Y226458D01*
X342167Y226208D01*
Y225792D01*
X342292Y225417D01*
X342542Y225167D01*
X342833Y225083D01*
X343125Y225167D01*
X343333Y225375D01*
X343458Y225708D01*
X343500Y226000D01*
G01Y229100D02*
X343458Y229392D01*
X343333Y229725D01*
X343125Y229933D01*
X342833Y230017D01*
X342542Y229933D01*
X342292Y229683D01*
X342167Y229308D01*
Y228892D01*
X342083Y228642D01*
X341875Y228433D01*
X341583Y228350D01*
X341292Y228475D01*
X341083Y228767D01*
X341000Y229100D01*
X341083Y229433D01*
X341292Y229725D01*
X341583Y229850D01*
X341875Y229767D01*
X342083Y229558D01*
X342167Y229308D01*
Y228892D01*
X342292Y228517D01*
X342542Y228267D01*
X342833Y228183D01*
X343125Y228267D01*
X343333Y228475D01*
X343458Y228808D01*
X343500Y229100D01*
G01X342458Y231408D02*
X342167Y231700D01*
X342000Y231950D01*
X341917Y232283D01*
X342000Y232575D01*
X342167Y232783D01*
X342417Y232950D01*
X342708Y232992D01*
X342958Y232950D01*
X343208Y232783D01*
X343417Y232533D01*
X343500Y232242D01*
X343417Y231908D01*
X343167Y231617D01*
X342792Y231450D01*
X342375Y231408D01*
X341833Y231492D01*
X341542Y231617D01*
X341250Y231825D01*
X341042Y232117D01*
X341000Y232408D01*
X341083Y232700D01*
X341292Y232908D01*
G01X339229Y239500D02*
Y235500D01*
X346629D01*
G01X337167Y222925D02*
X337375Y223258D01*
X337500Y223633D01*
Y223967D01*
X337375Y224300D01*
X337167Y224550D01*
X336875Y224675D01*
X336583Y224592D01*
X336333Y224383D01*
X336167Y224008D01*
X336083Y223508D01*
X335917Y223217D01*
X335625Y223092D01*
X335333Y223175D01*
X335125Y223383D01*
X335000Y223675D01*
Y223967D01*
X335083Y224258D01*
X335292Y224508D01*
G01X335208Y227817D02*
X335083Y227567D01*
X335000Y227275D01*
Y226942D01*
X335125Y226567D01*
X335333Y226275D01*
X335583Y226067D01*
X336000Y225900D01*
X336375Y225858D01*
X336750Y225942D01*
X337000Y226067D01*
X337250Y226317D01*
X337417Y226608D01*
X337500Y226900D01*
Y227192D01*
X337417Y227483D01*
X337292Y227733D01*
X337125Y227942D01*
G01X337500Y230000D02*
X337458Y230292D01*
X337333Y230625D01*
X337125Y230833D01*
X336833Y230917D01*
X336542Y230833D01*
X336292Y230583D01*
X336167Y230208D01*
Y229792D01*
X336083Y229542D01*
X335875Y229333D01*
X335583Y229250D01*
X335292Y229375D01*
X335083Y229667D01*
X335000Y230000D01*
X335083Y230333D01*
X335292Y230625D01*
X335583Y230750D01*
X335875Y230667D01*
X336083Y230458D01*
X336167Y230208D01*
Y229792D01*
X336292Y229417D01*
X336542Y229167D01*
X336833Y229083D01*
X337125Y229167D01*
X337333Y229375D01*
X337458Y229708D01*
X337500Y230000D01*
G01Y233100D02*
X337458Y233392D01*
X337333Y233725D01*
X337125Y233933D01*
X336833Y234017D01*
X336542Y233933D01*
X336292Y233683D01*
X336167Y233308D01*
Y232892D01*
X336083Y232642D01*
X335875Y232433D01*
X335583Y232350D01*
X335292Y232475D01*
X335083Y232767D01*
X335000Y233100D01*
X335083Y233433D01*
X335292Y233725D01*
X335583Y233850D01*
X335875Y233767D01*
X336083Y233558D01*
X336167Y233308D01*
Y232892D01*
X336292Y232517D01*
X336542Y232267D01*
X336833Y232183D01*
X337125Y232267D01*
X337333Y232475D01*
X337458Y232808D01*
X337500Y233100D01*
G01Y236117D02*
X336958Y236200D01*
X336500Y236325D01*
X336083Y236492D01*
X335625Y236700D01*
X335000Y237033D01*
Y235367D01*
G01X344629Y266750D02*
Y244250D01*
G01X337096Y271875D02*
X337304Y272208D01*
X337429Y272583D01*
Y272917D01*
X337304Y273250D01*
X337096Y273500D01*
X336804Y273625D01*
X336512Y273542D01*
X336262Y273333D01*
X336096Y272958D01*
X336012Y272458D01*
X335846Y272167D01*
X335554Y272042D01*
X335262Y272125D01*
X335054Y272333D01*
X334929Y272625D01*
Y272917D01*
X335012Y273208D01*
X335221Y273458D01*
G01X335137Y276767D02*
X335012Y276517D01*
X334929Y276225D01*
Y275892D01*
X335054Y275517D01*
X335262Y275225D01*
X335512Y275017D01*
X335929Y274850D01*
X336304Y274808D01*
X336679Y274892D01*
X336929Y275017D01*
X337179Y275267D01*
X337346Y275558D01*
X337429Y275850D01*
Y276142D01*
X337346Y276433D01*
X337221Y276683D01*
X337054Y276892D01*
G01X337429Y278950D02*
X334929D01*
X335429Y278450D01*
G01X337429D02*
Y279450D01*
G01Y282050D02*
X334929D01*
X335429Y281550D01*
G01X337429D02*
Y282550D01*
G01X337137Y284442D02*
X337346Y284733D01*
X337429Y285067D01*
X337346Y285400D01*
X337096Y285692D01*
X336721Y285900D01*
X336346Y285983D01*
X335887D01*
X335512Y285900D01*
X335179Y285692D01*
X335012Y285442D01*
X334929Y285150D01*
X335012Y284817D01*
X335179Y284567D01*
X335429Y284400D01*
X335762Y284317D01*
X336054Y284400D01*
X336346Y284608D01*
X336512Y284858D01*
X336554Y285150D01*
X336471Y285483D01*
X336262Y285733D01*
X335887Y285983D01*
G01X336387Y287458D02*
X336096Y287750D01*
X335929Y288000D01*
X335846Y288333D01*
X335929Y288625D01*
X336096Y288833D01*
X336346Y289000D01*
X336637Y289042D01*
X336887Y289000D01*
X337137Y288833D01*
X337346Y288583D01*
X337429Y288292D01*
X337346Y287958D01*
X337096Y287667D01*
X336721Y287500D01*
X336304Y287458D01*
X335762Y287542D01*
X335471Y287667D01*
X335179Y287875D01*
X334971Y288167D01*
X334929Y288458D01*
X335012Y288750D01*
X335221Y288958D01*
G01X341096Y271875D02*
X341304Y272208D01*
X341429Y272583D01*
Y272917D01*
X341304Y273250D01*
X341096Y273500D01*
X340804Y273625D01*
X340512Y273542D01*
X340262Y273333D01*
X340096Y272958D01*
X340012Y272458D01*
X339846Y272167D01*
X339554Y272042D01*
X339262Y272125D01*
X339054Y272333D01*
X338929Y272625D01*
Y272917D01*
X339012Y273208D01*
X339221Y273458D01*
G01X339137Y276767D02*
X339012Y276517D01*
X338929Y276225D01*
Y275892D01*
X339054Y275517D01*
X339262Y275225D01*
X339512Y275017D01*
X339929Y274850D01*
X340304Y274808D01*
X340679Y274892D01*
X340929Y275017D01*
X341179Y275267D01*
X341346Y275558D01*
X341429Y275850D01*
Y276142D01*
X341346Y276433D01*
X341221Y276683D01*
X341054Y276892D01*
G01X341429Y278950D02*
X338929D01*
X339429Y278450D01*
G01X341429D02*
Y279450D01*
G01Y282050D02*
X338929D01*
X339429Y281550D01*
G01X341429D02*
Y282550D01*
G01X341137Y284442D02*
X341346Y284733D01*
X341429Y285067D01*
X341346Y285400D01*
X341096Y285692D01*
X340721Y285900D01*
X340346Y285983D01*
X339887D01*
X339512Y285900D01*
X339179Y285692D01*
X339012Y285442D01*
X338929Y285150D01*
X339012Y284817D01*
X339179Y284567D01*
X339429Y284400D01*
X339762Y284317D01*
X340054Y284400D01*
X340346Y284608D01*
X340512Y284858D01*
X340554Y285150D01*
X340471Y285483D01*
X340262Y285733D01*
X339887Y285983D01*
G01X341429Y288167D02*
X340887Y288250D01*
X340429Y288375D01*
X340012Y288542D01*
X339554Y288750D01*
X338929Y289083D01*
Y287417D01*
G01X333096Y271875D02*
X333304Y272208D01*
X333429Y272583D01*
Y272917D01*
X333304Y273250D01*
X333096Y273500D01*
X332804Y273625D01*
X332512Y273542D01*
X332262Y273333D01*
X332096Y272958D01*
X332012Y272458D01*
X331846Y272167D01*
X331554Y272042D01*
X331262Y272125D01*
X331054Y272333D01*
X330929Y272625D01*
Y272917D01*
X331012Y273208D01*
X331221Y273458D01*
G01X331137Y276767D02*
X331012Y276517D01*
X330929Y276225D01*
Y275892D01*
X331054Y275517D01*
X331262Y275225D01*
X331512Y275017D01*
X331929Y274850D01*
X332304Y274808D01*
X332679Y274892D01*
X332929Y275017D01*
X333179Y275267D01*
X333346Y275558D01*
X333429Y275850D01*
Y276142D01*
X333346Y276433D01*
X333221Y276683D01*
X333054Y276892D01*
G01X333429Y278950D02*
X330929D01*
X331429Y278450D01*
G01X333429D02*
Y279450D01*
G01Y282050D02*
X330929D01*
X331429Y281550D01*
G01X333429D02*
Y282550D01*
G01X333137Y284442D02*
X333346Y284733D01*
X333429Y285067D01*
X333346Y285400D01*
X333096Y285692D01*
X332721Y285900D01*
X332346Y285983D01*
X331887D01*
X331512Y285900D01*
X331179Y285692D01*
X331012Y285442D01*
X330929Y285150D01*
X331012Y284817D01*
X331179Y284567D01*
X331429Y284400D01*
X331762Y284317D01*
X332054Y284400D01*
X332346Y284608D01*
X332512Y284858D01*
X332554Y285150D01*
X332471Y285483D01*
X332262Y285733D01*
X331887Y285983D01*
G01X333054Y287333D02*
X333262Y287583D01*
X333387Y287875D01*
X333429Y288250D01*
X333346Y288625D01*
X333179Y288917D01*
X332887Y289125D01*
X332554Y289167D01*
X332221Y289083D01*
X332012Y288875D01*
X331846Y288583D01*
X331804Y288292D01*
X331846Y288000D01*
X332012Y287625D01*
X330929Y287750D01*
Y288875D01*
G01X337096Y290875D02*
X337304Y291208D01*
X337429Y291583D01*
Y291917D01*
X337304Y292250D01*
X337096Y292500D01*
X336804Y292625D01*
X336512Y292542D01*
X336262Y292333D01*
X336096Y291958D01*
X336012Y291458D01*
X335846Y291167D01*
X335554Y291042D01*
X335262Y291125D01*
X335054Y291333D01*
X334929Y291625D01*
Y291917D01*
X335012Y292208D01*
X335221Y292458D01*
G01X335137Y295767D02*
X335012Y295517D01*
X334929Y295225D01*
Y294892D01*
X335054Y294517D01*
X335262Y294225D01*
X335512Y294017D01*
X335929Y293850D01*
X336304Y293808D01*
X336679Y293892D01*
X336929Y294017D01*
X337179Y294267D01*
X337346Y294558D01*
X337429Y294850D01*
Y295142D01*
X337346Y295433D01*
X337221Y295683D01*
X337054Y295892D01*
G01X337429Y297950D02*
X334929D01*
X335429Y297450D01*
G01X337429D02*
Y298450D01*
G01Y301050D02*
X334929D01*
X335429Y300550D01*
G01X337429D02*
Y301550D01*
G01X337054Y303233D02*
X337262Y303483D01*
X337387Y303775D01*
X337429Y304150D01*
X337346Y304525D01*
X337179Y304817D01*
X336887Y305025D01*
X336554Y305067D01*
X336221Y304983D01*
X336012Y304775D01*
X335846Y304483D01*
X335804Y304192D01*
X335846Y303900D01*
X336012Y303525D01*
X334929Y303650D01*
Y304775D01*
G01X336387Y306458D02*
X336096Y306750D01*
X335929Y307000D01*
X335846Y307333D01*
X335929Y307625D01*
X336096Y307833D01*
X336346Y308000D01*
X336637Y308042D01*
X336887Y308000D01*
X337137Y307833D01*
X337346Y307583D01*
X337429Y307292D01*
X337346Y306958D01*
X337096Y306667D01*
X336721Y306500D01*
X336304Y306458D01*
X335762Y306542D01*
X335471Y306667D01*
X335179Y306875D01*
X334971Y307167D01*
X334929Y307458D01*
X335012Y307750D01*
X335221Y307958D01*
G01X341096Y290875D02*
X341304Y291208D01*
X341429Y291583D01*
Y291917D01*
X341304Y292250D01*
X341096Y292500D01*
X340804Y292625D01*
X340512Y292542D01*
X340262Y292333D01*
X340096Y291958D01*
X340012Y291458D01*
X339846Y291167D01*
X339554Y291042D01*
X339262Y291125D01*
X339054Y291333D01*
X338929Y291625D01*
Y291917D01*
X339012Y292208D01*
X339221Y292458D01*
G01X339137Y295767D02*
X339012Y295517D01*
X338929Y295225D01*
Y294892D01*
X339054Y294517D01*
X339262Y294225D01*
X339512Y294017D01*
X339929Y293850D01*
X340304Y293808D01*
X340679Y293892D01*
X340929Y294017D01*
X341179Y294267D01*
X341346Y294558D01*
X341429Y294850D01*
Y295142D01*
X341346Y295433D01*
X341221Y295683D01*
X341054Y295892D01*
G01X341429Y297950D02*
X338929D01*
X339429Y297450D01*
G01X341429D02*
Y298450D01*
G01Y301050D02*
X338929D01*
X339429Y300550D01*
G01X341429D02*
Y301550D01*
G01X341054Y303233D02*
X341262Y303483D01*
X341387Y303775D01*
X341429Y304150D01*
X341346Y304525D01*
X341179Y304817D01*
X340887Y305025D01*
X340554Y305067D01*
X340221Y304983D01*
X340012Y304775D01*
X339846Y304483D01*
X339804Y304192D01*
X339846Y303900D01*
X340012Y303525D01*
X338929Y303650D01*
Y304775D01*
G01X341429Y307167D02*
X340887Y307250D01*
X340429Y307375D01*
X340012Y307542D01*
X339554Y307750D01*
X338929Y308083D01*
Y306417D01*
G01X333096Y290875D02*
X333304Y291208D01*
X333429Y291583D01*
Y291917D01*
X333304Y292250D01*
X333096Y292500D01*
X332804Y292625D01*
X332512Y292542D01*
X332262Y292333D01*
X332096Y291958D01*
X332012Y291458D01*
X331846Y291167D01*
X331554Y291042D01*
X331262Y291125D01*
X331054Y291333D01*
X330929Y291625D01*
Y291917D01*
X331012Y292208D01*
X331221Y292458D01*
G01X331137Y295767D02*
X331012Y295517D01*
X330929Y295225D01*
Y294892D01*
X331054Y294517D01*
X331262Y294225D01*
X331512Y294017D01*
X331929Y293850D01*
X332304Y293808D01*
X332679Y293892D01*
X332929Y294017D01*
X333179Y294267D01*
X333346Y294558D01*
X333429Y294850D01*
Y295142D01*
X333346Y295433D01*
X333221Y295683D01*
X333054Y295892D01*
G01X333429Y297950D02*
X330929D01*
X331429Y297450D01*
G01X333429D02*
Y298450D01*
G01Y301050D02*
X330929D01*
X331429Y300550D01*
G01X333429D02*
Y301550D01*
G01X333054Y303233D02*
X333262Y303483D01*
X333387Y303775D01*
X333429Y304150D01*
X333346Y304525D01*
X333179Y304817D01*
X332887Y305025D01*
X332554Y305067D01*
X332221Y304983D01*
X332012Y304775D01*
X331846Y304483D01*
X331804Y304192D01*
X331846Y303900D01*
X332012Y303525D01*
X330929Y303650D01*
Y304775D01*
G01X333054Y306333D02*
X333262Y306583D01*
X333387Y306875D01*
X333429Y307250D01*
X333346Y307625D01*
X333179Y307917D01*
X332887Y308125D01*
X332554Y308167D01*
X332221Y308083D01*
X332012Y307875D01*
X331846Y307583D01*
X331804Y307292D01*
X331846Y307000D01*
X332012Y306625D01*
X330929Y306750D01*
Y307875D01*
G01X339096Y368375D02*
X339304Y368708D01*
X339429Y369083D01*
Y369417D01*
X339304Y369750D01*
X339096Y370000D01*
X338804Y370125D01*
X338512Y370042D01*
X338262Y369833D01*
X338096Y369458D01*
X338012Y368958D01*
X337846Y368667D01*
X337554Y368542D01*
X337262Y368625D01*
X337054Y368833D01*
X336929Y369125D01*
Y369417D01*
X337012Y369708D01*
X337221Y369958D01*
G01X337137Y373267D02*
X337012Y373017D01*
X336929Y372725D01*
Y372392D01*
X337054Y372017D01*
X337262Y371725D01*
X337512Y371517D01*
X337929Y371350D01*
X338304Y371308D01*
X338679Y371392D01*
X338929Y371517D01*
X339179Y371767D01*
X339346Y372058D01*
X339429Y372350D01*
Y372642D01*
X339346Y372933D01*
X339221Y373183D01*
X339054Y373392D01*
G01X339429Y375450D02*
X336929D01*
X337429Y374950D01*
G01X339429D02*
Y375950D01*
G01X337346Y377758D02*
X337096Y378008D01*
X336971Y378300D01*
X336929Y378633D01*
X337012Y379050D01*
X337221Y379342D01*
X337471Y379425D01*
X337721Y379383D01*
X337929Y379217D01*
X338346Y378383D01*
X338637Y378008D01*
X339054Y377758D01*
X339429Y377675D01*
Y379425D01*
G01X336929Y381650D02*
X337012Y381317D01*
X337221Y381067D01*
X337471Y380900D01*
X337804Y380775D01*
X338179Y380733D01*
X338554Y380775D01*
X338887Y380900D01*
X339137Y381067D01*
X339346Y381317D01*
X339429Y381650D01*
X339346Y381983D01*
X339137Y382233D01*
X338887Y382400D01*
X338554Y382525D01*
X338179Y382567D01*
X337804Y382525D01*
X337471Y382400D01*
X337221Y382233D01*
X337012Y381983D01*
X336929Y381650D01*
G01Y384750D02*
X337012Y384417D01*
X337221Y384167D01*
X337471Y384000D01*
X337804Y383875D01*
X338179Y383833D01*
X338554Y383875D01*
X338887Y384000D01*
X339137Y384167D01*
X339346Y384417D01*
X339429Y384750D01*
X339346Y385083D01*
X339137Y385333D01*
X338887Y385500D01*
X338554Y385625D01*
X338179Y385667D01*
X337804Y385625D01*
X337471Y385500D01*
X337221Y385333D01*
X337012Y385083D01*
X336929Y384750D01*
G01X335096Y368375D02*
X335304Y368708D01*
X335429Y369083D01*
Y369417D01*
X335304Y369750D01*
X335096Y370000D01*
X334804Y370125D01*
X334512Y370042D01*
X334262Y369833D01*
X334096Y369458D01*
X334012Y368958D01*
X333846Y368667D01*
X333554Y368542D01*
X333262Y368625D01*
X333054Y368833D01*
X332929Y369125D01*
Y369417D01*
X333012Y369708D01*
X333221Y369958D01*
G01X333137Y373267D02*
X333012Y373017D01*
X332929Y372725D01*
Y372392D01*
X333054Y372017D01*
X333262Y371725D01*
X333512Y371517D01*
X333929Y371350D01*
X334304Y371308D01*
X334679Y371392D01*
X334929Y371517D01*
X335179Y371767D01*
X335346Y372058D01*
X335429Y372350D01*
Y372642D01*
X335346Y372933D01*
X335221Y373183D01*
X335054Y373392D01*
G01X335429Y375450D02*
X332929D01*
X333429Y374950D01*
G01X335429D02*
Y375950D01*
G01X333346Y377758D02*
X333096Y378008D01*
X332971Y378300D01*
X332929Y378633D01*
X333012Y379050D01*
X333221Y379342D01*
X333471Y379425D01*
X333721Y379383D01*
X333929Y379217D01*
X334346Y378383D01*
X334637Y378008D01*
X335054Y377758D01*
X335429Y377675D01*
Y379425D01*
G01X332929Y381650D02*
X333012Y381317D01*
X333221Y381067D01*
X333471Y380900D01*
X333804Y380775D01*
X334179Y380733D01*
X334554Y380775D01*
X334887Y380900D01*
X335137Y381067D01*
X335346Y381317D01*
X335429Y381650D01*
X335346Y381983D01*
X335137Y382233D01*
X334887Y382400D01*
X334554Y382525D01*
X334179Y382567D01*
X333804Y382525D01*
X333471Y382400D01*
X333221Y382233D01*
X333012Y381983D01*
X332929Y381650D01*
G01X335429Y384750D02*
X332929D01*
X333429Y384250D01*
G01X335429D02*
Y385250D01*
G01X343480Y383833D02*
X343813Y383625D01*
X344188Y383500D01*
X344522D01*
X344855Y383625D01*
X345105Y383833D01*
X345230Y384125D01*
X345147Y384417D01*
X344938Y384667D01*
X344563Y384833D01*
X344063Y384917D01*
X343772Y385083D01*
X343647Y385375D01*
X343730Y385667D01*
X343938Y385875D01*
X344230Y386000D01*
X344522D01*
X344813Y385917D01*
X345063Y385708D01*
G01X346622Y383500D02*
Y386000D01*
X347663D01*
X347997Y385875D01*
X348205Y385708D01*
X348288Y385375D01*
X348205Y385042D01*
X347955Y384833D01*
X347663Y384708D01*
X346622D01*
G01X347663D02*
X348288Y383500D01*
G01X350472D02*
X350555Y384042D01*
X350680Y384500D01*
X350847Y384917D01*
X351055Y385375D01*
X351388Y386000D01*
X349722D01*
G01X353572Y383500D02*
X353655Y384042D01*
X353780Y384500D01*
X353947Y384917D01*
X354155Y385375D01*
X354488Y386000D01*
X352822D01*
G01X356672Y383500D02*
X356755Y384042D01*
X356880Y384500D01*
X357047Y384917D01*
X357255Y385375D01*
X357588Y386000D01*
X355922D01*
G01X343480Y374833D02*
X343813Y374625D01*
X344188Y374500D01*
X344522D01*
X344855Y374625D01*
X345105Y374833D01*
X345230Y375125D01*
X345147Y375417D01*
X344938Y375667D01*
X344563Y375833D01*
X344063Y375917D01*
X343772Y376083D01*
X343647Y376375D01*
X343730Y376667D01*
X343938Y376875D01*
X344230Y377000D01*
X344522D01*
X344813Y376917D01*
X345063Y376708D01*
G01X346622Y374500D02*
Y377000D01*
X347663D01*
X347997Y376875D01*
X348205Y376708D01*
X348288Y376375D01*
X348205Y376042D01*
X347955Y375833D01*
X347663Y375708D01*
X346622D01*
G01X347663D02*
X348288Y374500D01*
G01X350472D02*
X350555Y375042D01*
X350680Y375500D01*
X350847Y375917D01*
X351055Y376375D01*
X351388Y377000D01*
X349722D01*
G01X353572Y374500D02*
X353655Y375042D01*
X353780Y375500D01*
X353947Y375917D01*
X354155Y376375D01*
X354488Y377000D01*
X352822D01*
G01X356047Y374792D02*
X356338Y374583D01*
X356672Y374500D01*
X357005Y374583D01*
X357297Y374833D01*
X357505Y375208D01*
X357588Y375583D01*
Y376042D01*
X357505Y376417D01*
X357297Y376750D01*
X357047Y376917D01*
X356755Y377000D01*
X356422Y376917D01*
X356172Y376750D01*
X356005Y376500D01*
X355922Y376167D01*
X356005Y375875D01*
X356213Y375583D01*
X356463Y375417D01*
X356755Y375375D01*
X357088Y375458D01*
X357338Y375667D01*
X357588Y376042D01*
G01X343480Y379333D02*
X343813Y379125D01*
X344188Y379000D01*
X344522D01*
X344855Y379125D01*
X345105Y379333D01*
X345230Y379625D01*
X345147Y379917D01*
X344938Y380167D01*
X344563Y380333D01*
X344063Y380417D01*
X343772Y380583D01*
X343647Y380875D01*
X343730Y381167D01*
X343938Y381375D01*
X344230Y381500D01*
X344522D01*
X344813Y381417D01*
X345063Y381208D01*
G01X346622Y379000D02*
Y381500D01*
X347663D01*
X347997Y381375D01*
X348205Y381208D01*
X348288Y380875D01*
X348205Y380542D01*
X347955Y380333D01*
X347663Y380208D01*
X346622D01*
G01X347663D02*
X348288Y379000D01*
G01X350472D02*
X350555Y379542D01*
X350680Y380000D01*
X350847Y380417D01*
X351055Y380875D01*
X351388Y381500D01*
X349722D01*
G01X353655Y379000D02*
X353947Y379042D01*
X354280Y379167D01*
X354488Y379375D01*
X354572Y379667D01*
X354488Y379958D01*
X354238Y380208D01*
X353863Y380333D01*
X353447D01*
X353197Y380417D01*
X352988Y380625D01*
X352905Y380917D01*
X353030Y381208D01*
X353322Y381417D01*
X353655Y381500D01*
X353988Y381417D01*
X354280Y381208D01*
X354405Y380917D01*
X354322Y380625D01*
X354113Y380417D01*
X353863Y380333D01*
X353447D01*
X353072Y380208D01*
X352822Y379958D01*
X352738Y379667D01*
X352822Y379375D01*
X353030Y379167D01*
X353363Y379042D01*
X353655Y379000D01*
G01X356755Y381500D02*
X356422Y381417D01*
X356172Y381208D01*
X356005Y380958D01*
X355880Y380625D01*
X355838Y380250D01*
X355880Y379875D01*
X356005Y379542D01*
X356172Y379292D01*
X356422Y379083D01*
X356755Y379000D01*
X357088Y379083D01*
X357338Y379292D01*
X357505Y379542D01*
X357630Y379875D01*
X357672Y380250D01*
X357630Y380625D01*
X357505Y380958D01*
X357338Y381208D01*
X357088Y381417D01*
X356755Y381500D01*
G01X343480Y369833D02*
X343813Y369625D01*
X344188Y369500D01*
X344522D01*
X344855Y369625D01*
X345105Y369833D01*
X345230Y370125D01*
X345147Y370417D01*
X344938Y370667D01*
X344563Y370833D01*
X344063Y370917D01*
X343772Y371083D01*
X343647Y371375D01*
X343730Y371667D01*
X343938Y371875D01*
X344230Y372000D01*
X344522D01*
X344813Y371917D01*
X345063Y371708D01*
G01X346622Y369500D02*
Y372000D01*
X347663D01*
X347997Y371875D01*
X348205Y371708D01*
X348288Y371375D01*
X348205Y371042D01*
X347955Y370833D01*
X347663Y370708D01*
X346622D01*
G01X347663D02*
X348288Y369500D01*
G01X350472D02*
X350555Y370042D01*
X350680Y370500D01*
X350847Y370917D01*
X351055Y371375D01*
X351388Y372000D01*
X349722D01*
G01X353655Y369500D02*
X353947Y369542D01*
X354280Y369667D01*
X354488Y369875D01*
X354572Y370167D01*
X354488Y370458D01*
X354238Y370708D01*
X353863Y370833D01*
X353447D01*
X353197Y370917D01*
X352988Y371125D01*
X352905Y371417D01*
X353030Y371708D01*
X353322Y371917D01*
X353655Y372000D01*
X353988Y371917D01*
X354280Y371708D01*
X354405Y371417D01*
X354322Y371125D01*
X354113Y370917D01*
X353863Y370833D01*
X353447D01*
X353072Y370708D01*
X352822Y370458D01*
X352738Y370167D01*
X352822Y369875D01*
X353030Y369667D01*
X353363Y369542D01*
X353655Y369500D01*
G01X356755D02*
Y372000D01*
X356255Y371500D01*
G01Y369500D02*
X357255D01*
G01X338740Y398833D02*
X339073Y398625D01*
X339448Y398500D01*
X339782D01*
X340115Y398625D01*
X340365Y398833D01*
X340490Y399125D01*
X340407Y399417D01*
X340198Y399667D01*
X339823Y399833D01*
X339323Y399917D01*
X339032Y400083D01*
X338907Y400375D01*
X338990Y400667D01*
X339198Y400875D01*
X339490Y401000D01*
X339782D01*
X340073Y400917D01*
X340323Y400708D01*
G01X341882Y398500D02*
Y401000D01*
X342923D01*
X343257Y400875D01*
X343465Y400708D01*
X343548Y400375D01*
X343465Y400042D01*
X343215Y399833D01*
X342923Y399708D01*
X341882D01*
G01X342923D02*
X343548Y398500D01*
G01X345815D02*
X346107Y398542D01*
X346440Y398667D01*
X346648Y398875D01*
X346732Y399167D01*
X346648Y399458D01*
X346398Y399708D01*
X346023Y399833D01*
X345607D01*
X345357Y399917D01*
X345148Y400125D01*
X345065Y400417D01*
X345190Y400708D01*
X345482Y400917D01*
X345815Y401000D01*
X346148Y400917D01*
X346440Y400708D01*
X346565Y400417D01*
X346482Y400125D01*
X346273Y399917D01*
X346023Y399833D01*
X345607D01*
X345232Y399708D01*
X344982Y399458D01*
X344898Y399167D01*
X344982Y398875D01*
X345190Y398667D01*
X345523Y398542D01*
X345815Y398500D01*
G01X348123Y400583D02*
X348373Y400833D01*
X348665Y400958D01*
X348998Y401000D01*
X349415Y400917D01*
X349707Y400708D01*
X349790Y400458D01*
X349748Y400208D01*
X349582Y400000D01*
X348748Y399583D01*
X348373Y399292D01*
X348123Y398875D01*
X348040Y398500D01*
X349790D01*
G01X352015Y401000D02*
X351682Y400917D01*
X351432Y400708D01*
X351265Y400458D01*
X351140Y400125D01*
X351098Y399750D01*
X351140Y399375D01*
X351265Y399042D01*
X351432Y398792D01*
X351682Y398583D01*
X352015Y398500D01*
X352348Y398583D01*
X352598Y398792D01*
X352765Y399042D01*
X352890Y399375D01*
X352932Y399750D01*
X352890Y400125D01*
X352765Y400458D01*
X352598Y400708D01*
X352348Y400917D01*
X352015Y401000D01*
G01X338980Y393333D02*
X339313Y393125D01*
X339688Y393000D01*
X340022D01*
X340355Y393125D01*
X340605Y393333D01*
X340730Y393625D01*
X340647Y393917D01*
X340438Y394167D01*
X340063Y394333D01*
X339563Y394417D01*
X339272Y394583D01*
X339147Y394875D01*
X339230Y395167D01*
X339438Y395375D01*
X339730Y395500D01*
X340022D01*
X340313Y395417D01*
X340563Y395208D01*
G01X342122Y393000D02*
Y395500D01*
X343163D01*
X343497Y395375D01*
X343705Y395208D01*
X343788Y394875D01*
X343705Y394542D01*
X343455Y394333D01*
X343163Y394208D01*
X342122D01*
G01X343163D02*
X343788Y393000D01*
G01X345972D02*
X346055Y393542D01*
X346180Y394000D01*
X346347Y394417D01*
X346555Y394875D01*
X346888Y395500D01*
X345222D01*
G01X349072Y393000D02*
X349155Y393542D01*
X349280Y394000D01*
X349447Y394417D01*
X349655Y394875D01*
X349988Y395500D01*
X348322D01*
G01X351463Y394042D02*
X351755Y394333D01*
X352005Y394500D01*
X352338Y394583D01*
X352630Y394500D01*
X352838Y394333D01*
X353005Y394083D01*
X353047Y393792D01*
X353005Y393542D01*
X352838Y393292D01*
X352588Y393083D01*
X352297Y393000D01*
X351963Y393083D01*
X351672Y393333D01*
X351505Y393708D01*
X351463Y394125D01*
X351547Y394667D01*
X351672Y394958D01*
X351880Y395250D01*
X352172Y395458D01*
X352463Y395500D01*
X352755Y395417D01*
X352963Y395208D01*
G01X338980Y388833D02*
X339313Y388625D01*
X339688Y388500D01*
X340022D01*
X340355Y388625D01*
X340605Y388833D01*
X340730Y389125D01*
X340647Y389417D01*
X340438Y389667D01*
X340063Y389833D01*
X339563Y389917D01*
X339272Y390083D01*
X339147Y390375D01*
X339230Y390667D01*
X339438Y390875D01*
X339730Y391000D01*
X340022D01*
X340313Y390917D01*
X340563Y390708D01*
G01X342122Y388500D02*
Y391000D01*
X343163D01*
X343497Y390875D01*
X343705Y390708D01*
X343788Y390375D01*
X343705Y390042D01*
X343455Y389833D01*
X343163Y389708D01*
X342122D01*
G01X343163D02*
X343788Y388500D01*
G01X345972D02*
X346055Y389042D01*
X346180Y389500D01*
X346347Y389917D01*
X346555Y390375D01*
X346888Y391000D01*
X345222D01*
G01X349072Y388500D02*
X349155Y389042D01*
X349280Y389500D01*
X349447Y389917D01*
X349655Y390375D01*
X349988Y391000D01*
X348322D01*
G01X352255Y388500D02*
X352547Y388542D01*
X352880Y388667D01*
X353088Y388875D01*
X353172Y389167D01*
X353088Y389458D01*
X352838Y389708D01*
X352463Y389833D01*
X352047D01*
X351797Y389917D01*
X351588Y390125D01*
X351505Y390417D01*
X351630Y390708D01*
X351922Y390917D01*
X352255Y391000D01*
X352588Y390917D01*
X352880Y390708D01*
X353005Y390417D01*
X352922Y390125D01*
X352713Y389917D01*
X352463Y389833D01*
X352047D01*
X351672Y389708D01*
X351422Y389458D01*
X351338Y389167D01*
X351422Y388875D01*
X351630Y388667D01*
X351963Y388542D01*
X352255Y388500D01*
G01X340925Y403833D02*
X341258Y403625D01*
X341633Y403500D01*
X341967D01*
X342300Y403625D01*
X342550Y403833D01*
X342675Y404125D01*
X342592Y404417D01*
X342383Y404667D01*
X342008Y404833D01*
X341508Y404917D01*
X341217Y405083D01*
X341092Y405375D01*
X341175Y405667D01*
X341383Y405875D01*
X341675Y406000D01*
X341967D01*
X342258Y405917D01*
X342508Y405708D01*
G01X344067Y403500D02*
Y406000D01*
X345108D01*
X345442Y405875D01*
X345650Y405708D01*
X345733Y405375D01*
X345650Y405042D01*
X345400Y404833D01*
X345108Y404708D01*
X344067D01*
G01X345108D02*
X345733Y403500D01*
G01X348000D02*
X348292Y403542D01*
X348625Y403667D01*
X348833Y403875D01*
X348917Y404167D01*
X348833Y404458D01*
X348583Y404708D01*
X348208Y404833D01*
X347792D01*
X347542Y404917D01*
X347333Y405125D01*
X347250Y405417D01*
X347375Y405708D01*
X347667Y405917D01*
X348000Y406000D01*
X348333Y405917D01*
X348625Y405708D01*
X348750Y405417D01*
X348667Y405125D01*
X348458Y404917D01*
X348208Y404833D01*
X347792D01*
X347417Y404708D01*
X347167Y404458D01*
X347083Y404167D01*
X347167Y403875D01*
X347375Y403667D01*
X347708Y403542D01*
X348000Y403500D01*
G01X351100D02*
Y406000D01*
X350600Y405500D01*
G01Y403500D02*
X351600D01*
G01X353408Y404542D02*
X353700Y404833D01*
X353950Y405000D01*
X354283Y405083D01*
X354575Y405000D01*
X354783Y404833D01*
X354950Y404583D01*
X354992Y404292D01*
X354950Y404042D01*
X354783Y403792D01*
X354533Y403583D01*
X354242Y403500D01*
X353908Y403583D01*
X353617Y403833D01*
X353450Y404208D01*
X353408Y404625D01*
X353492Y405167D01*
X353617Y405458D01*
X353825Y405750D01*
X354117Y405958D01*
X354408Y406000D01*
X354700Y405917D01*
X354908Y405708D01*
G01X343730Y408833D02*
X344063Y408625D01*
X344438Y408500D01*
X344772D01*
X345105Y408625D01*
X345355Y408833D01*
X345480Y409125D01*
X345397Y409417D01*
X345188Y409667D01*
X344813Y409833D01*
X344313Y409917D01*
X344022Y410083D01*
X343897Y410375D01*
X343980Y410667D01*
X344188Y410875D01*
X344480Y411000D01*
X344772D01*
X345063Y410917D01*
X345313Y410708D01*
G01X346872Y408500D02*
Y411000D01*
X347913D01*
X348247Y410875D01*
X348455Y410708D01*
X348538Y410375D01*
X348455Y410042D01*
X348205Y409833D01*
X347913Y409708D01*
X346872D01*
G01X347913D02*
X348538Y408500D01*
G01X350805D02*
X351097Y408542D01*
X351430Y408667D01*
X351638Y408875D01*
X351722Y409167D01*
X351638Y409458D01*
X351388Y409708D01*
X351013Y409833D01*
X350597D01*
X350347Y409917D01*
X350138Y410125D01*
X350055Y410417D01*
X350180Y410708D01*
X350472Y410917D01*
X350805Y411000D01*
X351138Y410917D01*
X351430Y410708D01*
X351555Y410417D01*
X351472Y410125D01*
X351263Y409917D01*
X351013Y409833D01*
X350597D01*
X350222Y409708D01*
X349972Y409458D01*
X349888Y409167D01*
X349972Y408875D01*
X350180Y408667D01*
X350513Y408542D01*
X350805Y408500D01*
G01X353905D02*
Y411000D01*
X353405Y410500D01*
G01Y408500D02*
X354405D01*
G01X356922D02*
X357005Y409042D01*
X357130Y409500D01*
X357297Y409917D01*
X357505Y410375D01*
X357838Y411000D01*
X356172D01*
G01X343730Y417833D02*
X344063Y417625D01*
X344438Y417500D01*
X344772D01*
X345105Y417625D01*
X345355Y417833D01*
X345480Y418125D01*
X345397Y418417D01*
X345188Y418667D01*
X344813Y418833D01*
X344313Y418917D01*
X344022Y419083D01*
X343897Y419375D01*
X343980Y419667D01*
X344188Y419875D01*
X344480Y420000D01*
X344772D01*
X345063Y419917D01*
X345313Y419708D01*
G01X346872Y417500D02*
Y420000D01*
X347913D01*
X348247Y419875D01*
X348455Y419708D01*
X348538Y419375D01*
X348455Y419042D01*
X348205Y418833D01*
X347913Y418708D01*
X346872D01*
G01X347913D02*
X348538Y417500D01*
G01X350805D02*
X351097Y417542D01*
X351430Y417667D01*
X351638Y417875D01*
X351722Y418167D01*
X351638Y418458D01*
X351388Y418708D01*
X351013Y418833D01*
X350597D01*
X350347Y418917D01*
X350138Y419125D01*
X350055Y419417D01*
X350180Y419708D01*
X350472Y419917D01*
X350805Y420000D01*
X351138Y419917D01*
X351430Y419708D01*
X351555Y419417D01*
X351472Y419125D01*
X351263Y418917D01*
X351013Y418833D01*
X350597D01*
X350222Y418708D01*
X349972Y418458D01*
X349888Y418167D01*
X349972Y417875D01*
X350180Y417667D01*
X350513Y417542D01*
X350805Y417500D01*
G01X353905D02*
Y420000D01*
X353405Y419500D01*
G01Y417500D02*
X354405D01*
G01X357005D02*
X357297Y417542D01*
X357630Y417667D01*
X357838Y417875D01*
X357922Y418167D01*
X357838Y418458D01*
X357588Y418708D01*
X357213Y418833D01*
X356797D01*
X356547Y418917D01*
X356338Y419125D01*
X356255Y419417D01*
X356380Y419708D01*
X356672Y419917D01*
X357005Y420000D01*
X357338Y419917D01*
X357630Y419708D01*
X357755Y419417D01*
X357672Y419125D01*
X357463Y418917D01*
X357213Y418833D01*
X356797D01*
X356422Y418708D01*
X356172Y418458D01*
X356088Y418167D01*
X356172Y417875D01*
X356380Y417667D01*
X356713Y417542D01*
X357005Y417500D01*
G01X343730Y413333D02*
X344063Y413125D01*
X344438Y413000D01*
X344772D01*
X345105Y413125D01*
X345355Y413333D01*
X345480Y413625D01*
X345397Y413917D01*
X345188Y414167D01*
X344813Y414333D01*
X344313Y414417D01*
X344022Y414583D01*
X343897Y414875D01*
X343980Y415167D01*
X344188Y415375D01*
X344480Y415500D01*
X344772D01*
X345063Y415417D01*
X345313Y415208D01*
G01X346872Y413000D02*
Y415500D01*
X347913D01*
X348247Y415375D01*
X348455Y415208D01*
X348538Y414875D01*
X348455Y414542D01*
X348205Y414333D01*
X347913Y414208D01*
X346872D01*
G01X347913D02*
X348538Y413000D01*
G01X350805D02*
X351097Y413042D01*
X351430Y413167D01*
X351638Y413375D01*
X351722Y413667D01*
X351638Y413958D01*
X351388Y414208D01*
X351013Y414333D01*
X350597D01*
X350347Y414417D01*
X350138Y414625D01*
X350055Y414917D01*
X350180Y415208D01*
X350472Y415417D01*
X350805Y415500D01*
X351138Y415417D01*
X351430Y415208D01*
X351555Y414917D01*
X351472Y414625D01*
X351263Y414417D01*
X351013Y414333D01*
X350597D01*
X350222Y414208D01*
X349972Y413958D01*
X349888Y413667D01*
X349972Y413375D01*
X350180Y413167D01*
X350513Y413042D01*
X350805Y413000D01*
G01X353905D02*
Y415500D01*
X353405Y415000D01*
G01Y413000D02*
X354405D01*
G01X356297Y413292D02*
X356588Y413083D01*
X356922Y413000D01*
X357255Y413083D01*
X357547Y413333D01*
X357755Y413708D01*
X357838Y414083D01*
Y414542D01*
X357755Y414917D01*
X357547Y415250D01*
X357297Y415417D01*
X357005Y415500D01*
X356672Y415417D01*
X356422Y415250D01*
X356255Y415000D01*
X356172Y414667D01*
X356255Y414375D01*
X356463Y414083D01*
X356713Y413917D01*
X357005Y413875D01*
X357338Y413958D01*
X357588Y414167D01*
X357838Y414542D01*
G01X332030Y467333D02*
X332363Y467125D01*
X332738Y467000D01*
X333072D01*
X333405Y467125D01*
X333655Y467333D01*
X333780Y467625D01*
X333697Y467917D01*
X333488Y468167D01*
X333113Y468333D01*
X332613Y468417D01*
X332322Y468583D01*
X332197Y468875D01*
X332280Y469167D01*
X332488Y469375D01*
X332780Y469500D01*
X333072D01*
X333363Y469417D01*
X333613Y469208D01*
G01X335088Y469500D02*
Y467708D01*
X335255Y467333D01*
X335588Y467083D01*
X336005Y467000D01*
X336422Y467083D01*
X336755Y467333D01*
X336922Y467708D01*
Y469500D01*
G01X338313Y468042D02*
X338605Y468333D01*
X338855Y468500D01*
X339188Y468583D01*
X339480Y468500D01*
X339688Y468333D01*
X339855Y468083D01*
X339897Y467792D01*
X339855Y467542D01*
X339688Y467292D01*
X339438Y467083D01*
X339147Y467000D01*
X338813Y467083D01*
X338522Y467333D01*
X338355Y467708D01*
X338313Y468125D01*
X338397Y468667D01*
X338522Y468958D01*
X338730Y469250D01*
X339022Y469458D01*
X339313Y469500D01*
X339605Y469417D01*
X339813Y469208D01*
G01X341413Y468042D02*
X341705Y468333D01*
X341955Y468500D01*
X342288Y468583D01*
X342580Y468500D01*
X342788Y468333D01*
X342955Y468083D01*
X342997Y467792D01*
X342955Y467542D01*
X342788Y467292D01*
X342538Y467083D01*
X342247Y467000D01*
X341913Y467083D01*
X341622Y467333D01*
X341455Y467708D01*
X341413Y468125D01*
X341497Y468667D01*
X341622Y468958D01*
X341830Y469250D01*
X342122Y469458D01*
X342413Y469500D01*
X342705Y469417D01*
X342913Y469208D01*
G01X340323Y462983D02*
Y452783D01*
G01X335723Y462983D02*
X340323D01*
G01X335723Y452083D02*
Y462983D01*
G01Y452083D02*
X347023D01*
G01X338023Y453283D02*
X336823Y452083D01*
G01X338023Y453283D02*
X339223Y452083D01*
G01X335223Y476583D02*
Y486783D01*
G01X339823Y476583D02*
X335223D01*
G01X339823Y487483D02*
Y476583D01*
G01X332030Y489833D02*
X332363Y489625D01*
X332738Y489500D01*
X333072D01*
X333405Y489625D01*
X333655Y489833D01*
X333780Y490125D01*
X333697Y490417D01*
X333488Y490667D01*
X333113Y490833D01*
X332613Y490917D01*
X332322Y491083D01*
X332197Y491375D01*
X332280Y491667D01*
X332488Y491875D01*
X332780Y492000D01*
X333072D01*
X333363Y491917D01*
X333613Y491708D01*
G01X335088Y492000D02*
Y490208D01*
X335255Y489833D01*
X335588Y489583D01*
X336005Y489500D01*
X336422Y489583D01*
X336755Y489833D01*
X336922Y490208D01*
Y492000D01*
G01X338313Y490542D02*
X338605Y490833D01*
X338855Y491000D01*
X339188Y491083D01*
X339480Y491000D01*
X339688Y490833D01*
X339855Y490583D01*
X339897Y490292D01*
X339855Y490042D01*
X339688Y489792D01*
X339438Y489583D01*
X339147Y489500D01*
X338813Y489583D01*
X338522Y489833D01*
X338355Y490208D01*
X338313Y490625D01*
X338397Y491167D01*
X338522Y491458D01*
X338730Y491750D01*
X339022Y491958D01*
X339313Y492000D01*
X339605Y491917D01*
X339813Y491708D01*
G01X341288Y489875D02*
X341538Y489667D01*
X341830Y489542D01*
X342205Y489500D01*
X342580Y489583D01*
X342872Y489750D01*
X343080Y490042D01*
X343122Y490375D01*
X343038Y490708D01*
X342830Y490917D01*
X342538Y491083D01*
X342247Y491125D01*
X341955Y491083D01*
X341580Y490917D01*
X341705Y492000D01*
X342830D01*
G01X337523Y486283D02*
X338723Y487483D01*
G01X337523Y486283D02*
X336323Y487483D01*
G01X337722Y496425D02*
X337930Y496758D01*
X338055Y497133D01*
Y497467D01*
X337930Y497800D01*
X337722Y498050D01*
X337430Y498175D01*
X337138Y498092D01*
X336888Y497883D01*
X336722Y497508D01*
X336638Y497008D01*
X336472Y496717D01*
X336180Y496592D01*
X335888Y496675D01*
X335680Y496883D01*
X335555Y497175D01*
Y497467D01*
X335638Y497758D01*
X335847Y498008D01*
G01X335763Y501317D02*
X335638Y501067D01*
X335555Y500775D01*
Y500442D01*
X335680Y500067D01*
X335888Y499775D01*
X336138Y499567D01*
X336555Y499400D01*
X336930Y499358D01*
X337305Y499442D01*
X337555Y499567D01*
X337805Y499817D01*
X337972Y500108D01*
X338055Y500400D01*
Y500692D01*
X337972Y500983D01*
X337847Y501233D01*
X337680Y501442D01*
G01X337555Y502583D02*
X337847Y502833D01*
X338013Y503167D01*
X338055Y503542D01*
X338013Y503875D01*
X337805Y504208D01*
X337555Y504417D01*
X337305Y504458D01*
X337013Y504375D01*
X336805Y504083D01*
X336722Y503792D01*
Y503417D01*
G01Y503792D02*
X336597Y504042D01*
X336388Y504250D01*
X336138Y504333D01*
X335888Y504250D01*
X335680Y504042D01*
X335555Y503667D01*
X335597Y503292D01*
X335763Y502917D01*
G01X335555Y506600D02*
X335638Y506267D01*
X335847Y506017D01*
X336097Y505850D01*
X336430Y505725D01*
X336805Y505683D01*
X337180Y505725D01*
X337513Y505850D01*
X337763Y506017D01*
X337972Y506267D01*
X338055Y506600D01*
X337972Y506933D01*
X337763Y507183D01*
X337513Y507350D01*
X337180Y507475D01*
X336805Y507517D01*
X336430Y507475D01*
X336097Y507350D01*
X335847Y507183D01*
X335638Y506933D01*
X335555Y506600D01*
G01X338055Y509700D02*
X338013Y509992D01*
X337888Y510325D01*
X337680Y510533D01*
X337388Y510617D01*
X337097Y510533D01*
X336847Y510283D01*
X336722Y509908D01*
Y509492D01*
X336638Y509242D01*
X336430Y509033D01*
X336138Y508950D01*
X335847Y509075D01*
X335638Y509367D01*
X335555Y509700D01*
X335638Y510033D01*
X335847Y510325D01*
X336138Y510450D01*
X336430Y510367D01*
X336638Y510158D01*
X336722Y509908D01*
Y509492D01*
X336847Y509117D01*
X337097Y508867D01*
X337388Y508783D01*
X337680Y508867D01*
X337888Y509075D01*
X338013Y509408D01*
X338055Y509700D01*
G01X333722Y496425D02*
X333930Y496758D01*
X334055Y497133D01*
Y497467D01*
X333930Y497800D01*
X333722Y498050D01*
X333430Y498175D01*
X333138Y498092D01*
X332888Y497883D01*
X332722Y497508D01*
X332638Y497008D01*
X332472Y496717D01*
X332180Y496592D01*
X331888Y496675D01*
X331680Y496883D01*
X331555Y497175D01*
Y497467D01*
X331638Y497758D01*
X331847Y498008D01*
G01X331763Y501317D02*
X331638Y501067D01*
X331555Y500775D01*
Y500442D01*
X331680Y500067D01*
X331888Y499775D01*
X332138Y499567D01*
X332555Y499400D01*
X332930Y499358D01*
X333305Y499442D01*
X333555Y499567D01*
X333805Y499817D01*
X333972Y500108D01*
X334055Y500400D01*
Y500692D01*
X333972Y500983D01*
X333847Y501233D01*
X333680Y501442D01*
G01X333555Y502583D02*
X333847Y502833D01*
X334013Y503167D01*
X334055Y503542D01*
X334013Y503875D01*
X333805Y504208D01*
X333555Y504417D01*
X333305Y504458D01*
X333013Y504375D01*
X332805Y504083D01*
X332722Y503792D01*
Y503417D01*
G01Y503792D02*
X332597Y504042D01*
X332388Y504250D01*
X332138Y504333D01*
X331888Y504250D01*
X331680Y504042D01*
X331555Y503667D01*
X331597Y503292D01*
X331763Y502917D01*
G01X331555Y506600D02*
X331638Y506267D01*
X331847Y506017D01*
X332097Y505850D01*
X332430Y505725D01*
X332805Y505683D01*
X333180Y505725D01*
X333513Y505850D01*
X333763Y506017D01*
X333972Y506267D01*
X334055Y506600D01*
X333972Y506933D01*
X333763Y507183D01*
X333513Y507350D01*
X333180Y507475D01*
X332805Y507517D01*
X332430Y507475D01*
X332097Y507350D01*
X331847Y507183D01*
X331638Y506933D01*
X331555Y506600D01*
G01X334055Y509617D02*
X333513Y509700D01*
X333055Y509825D01*
X332638Y509992D01*
X332180Y510200D01*
X331555Y510533D01*
Y508867D01*
G01X346298Y529094D02*
X344848Y527644D01*
G01Y530544D02*
X346298Y529094D01*
G01X344848Y534594D02*
Y523594D01*
G01D02*
X365448D01*
G01X341105Y523500D02*
Y534500D01*
G01X365448Y534594D02*
X344848D01*
G01X333530Y546333D02*
X333863Y546125D01*
X334238Y546000D01*
X334572D01*
X334905Y546125D01*
X335155Y546333D01*
X335280Y546625D01*
X335197Y546917D01*
X334988Y547167D01*
X334613Y547333D01*
X334113Y547417D01*
X333822Y547583D01*
X333697Y547875D01*
X333780Y548167D01*
X333988Y548375D01*
X334280Y548500D01*
X334572D01*
X334863Y548417D01*
X335113Y548208D01*
G01X336588Y548500D02*
Y546708D01*
X336755Y546333D01*
X337088Y546083D01*
X337505Y546000D01*
X337922Y546083D01*
X338255Y546333D01*
X338422Y546708D01*
Y548500D01*
G01X340522Y546000D02*
X340605Y546542D01*
X340730Y547000D01*
X340897Y547417D01*
X341105Y547875D01*
X341438Y548500D01*
X339772D01*
G01X342913Y548083D02*
X343163Y548333D01*
X343455Y548458D01*
X343788Y548500D01*
X344205Y548417D01*
X344497Y548208D01*
X344580Y547958D01*
X344538Y547708D01*
X344372Y547500D01*
X343538Y547083D01*
X343163Y546792D01*
X342913Y546375D01*
X342830Y546000D01*
X344580D01*
G01X349200Y882500D02*
Y886500D01*
X341800D01*
G01X349200Y876500D02*
Y880500D01*
X341800D01*
G01X344500Y908800D02*
X348500D01*
Y916200D01*
G01X333500Y905517D02*
X331000D01*
Y906558D01*
X331125Y906892D01*
X331292Y907100D01*
X331625Y907183D01*
X331958Y907100D01*
X332167Y906850D01*
X332292Y906558D01*
Y905517D01*
G01Y906558D02*
X333500Y907183D01*
G01X333125Y908533D02*
X333333Y908783D01*
X333458Y909075D01*
X333500Y909450D01*
X333417Y909825D01*
X333250Y910117D01*
X332958Y910325D01*
X332625Y910367D01*
X332292Y910283D01*
X332083Y910075D01*
X331917Y909783D01*
X331875Y909492D01*
X331917Y909200D01*
X332083Y908825D01*
X331000Y908950D01*
Y910075D01*
G01X332458Y911758D02*
X332167Y912050D01*
X332000Y912300D01*
X331917Y912633D01*
X332000Y912925D01*
X332167Y913133D01*
X332417Y913300D01*
X332708Y913342D01*
X332958Y913300D01*
X333208Y913133D01*
X333417Y912883D01*
X333500Y912592D01*
X333417Y912258D01*
X333167Y911967D01*
X332792Y911800D01*
X332375Y911758D01*
X331833Y911842D01*
X331542Y911967D01*
X331250Y912175D01*
X331042Y912467D01*
X331000Y912758D01*
X331083Y913050D01*
X331292Y913258D01*
G01X331000Y915650D02*
X331083Y915317D01*
X331292Y915067D01*
X331542Y914900D01*
X331875Y914775D01*
X332250Y914733D01*
X332625Y914775D01*
X332958Y914900D01*
X333208Y915067D01*
X333417Y915317D01*
X333500Y915650D01*
X333417Y915983D01*
X333208Y916233D01*
X332958Y916400D01*
X332625Y916525D01*
X332250Y916567D01*
X331875Y916525D01*
X331542Y916400D01*
X331292Y916233D01*
X331083Y915983D01*
X331000Y915650D01*
G01X349200Y891000D02*
Y895000D01*
X341800D01*
G01X337300Y930300D02*
Y925800D01*
G01X369100D02*
X337300D01*
G01Y930300D02*
Y933700D01*
G01X339000Y932000D02*
X337300Y930300D01*
G01Y933700D02*
X339000Y932000D01*
G01X337300Y938200D02*
X369100D01*
G01X337300Y933700D02*
Y938200D01*
G01X339167Y959425D02*
X339375Y959758D01*
X339500Y960133D01*
Y960467D01*
X339375Y960800D01*
X339167Y961050D01*
X338875Y961175D01*
X338583Y961092D01*
X338333Y960883D01*
X338167Y960508D01*
X338083Y960008D01*
X337917Y959717D01*
X337625Y959592D01*
X337333Y959675D01*
X337125Y959883D01*
X337000Y960175D01*
Y960467D01*
X337083Y960758D01*
X337292Y961008D01*
G01X339500Y962567D02*
X337000D01*
Y963608D01*
X337125Y963942D01*
X337292Y964150D01*
X337625Y964233D01*
X337958Y964150D01*
X338167Y963900D01*
X338292Y963608D01*
Y962567D01*
G01Y963608D02*
X339500Y964233D01*
G01X339208Y965792D02*
X339417Y966083D01*
X339500Y966417D01*
X339417Y966750D01*
X339167Y967042D01*
X338792Y967250D01*
X338417Y967333D01*
X337958D01*
X337583Y967250D01*
X337250Y967042D01*
X337083Y966792D01*
X337000Y966500D01*
X337083Y966167D01*
X337250Y965917D01*
X337500Y965750D01*
X337833Y965667D01*
X338125Y965750D01*
X338417Y965958D01*
X338583Y966208D01*
X338625Y966500D01*
X338542Y966833D01*
X338333Y967083D01*
X337958Y967333D01*
G01X339125Y968683D02*
X339333Y968933D01*
X339458Y969225D01*
X339500Y969600D01*
X339417Y969975D01*
X339250Y970267D01*
X338958Y970475D01*
X338625Y970517D01*
X338292Y970433D01*
X338083Y970225D01*
X337917Y969933D01*
X337875Y969642D01*
X337917Y969350D01*
X338083Y968975D01*
X337000Y969100D01*
Y970225D01*
G01X339500Y972700D02*
X337000D01*
X337500Y972200D01*
G01X339500D02*
Y973200D01*
G01X336000Y950800D02*
X340000D01*
Y958200D01*
G01X343667Y959425D02*
X343875Y959758D01*
X344000Y960133D01*
Y960467D01*
X343875Y960800D01*
X343667Y961050D01*
X343375Y961175D01*
X343083Y961092D01*
X342833Y960883D01*
X342667Y960508D01*
X342583Y960008D01*
X342417Y959717D01*
X342125Y959592D01*
X341833Y959675D01*
X341625Y959883D01*
X341500Y960175D01*
Y960467D01*
X341583Y960758D01*
X341792Y961008D01*
G01X344000Y962567D02*
X341500D01*
Y963608D01*
X341625Y963942D01*
X341792Y964150D01*
X342125Y964233D01*
X342458Y964150D01*
X342667Y963900D01*
X342792Y963608D01*
Y962567D01*
G01Y963608D02*
X344000Y964233D01*
G01X343708Y965792D02*
X343917Y966083D01*
X344000Y966417D01*
X343917Y966750D01*
X343667Y967042D01*
X343292Y967250D01*
X342917Y967333D01*
X342458D01*
X342083Y967250D01*
X341750Y967042D01*
X341583Y966792D01*
X341500Y966500D01*
X341583Y966167D01*
X341750Y965917D01*
X342000Y965750D01*
X342333Y965667D01*
X342625Y965750D01*
X342917Y965958D01*
X343083Y966208D01*
X343125Y966500D01*
X343042Y966833D01*
X342833Y967083D01*
X342458Y967333D01*
G01X343625Y968683D02*
X343833Y968933D01*
X343958Y969225D01*
X344000Y969600D01*
X343917Y969975D01*
X343750Y970267D01*
X343458Y970475D01*
X343125Y970517D01*
X342792Y970433D01*
X342583Y970225D01*
X342417Y969933D01*
X342375Y969642D01*
X342417Y969350D01*
X342583Y968975D01*
X341500Y969100D01*
Y970225D01*
G01X341917Y971908D02*
X341667Y972158D01*
X341542Y972450D01*
X341500Y972783D01*
X341583Y973200D01*
X341792Y973492D01*
X342042Y973575D01*
X342292Y973533D01*
X342500Y973367D01*
X342917Y972533D01*
X343208Y972158D01*
X343625Y971908D01*
X344000Y971825D01*
Y973575D01*
G01X340500Y950800D02*
X344500D01*
Y958200D01*
G01X348167Y959425D02*
X348375Y959758D01*
X348500Y960133D01*
Y960467D01*
X348375Y960800D01*
X348167Y961050D01*
X347875Y961175D01*
X347583Y961092D01*
X347333Y960883D01*
X347167Y960508D01*
X347083Y960008D01*
X346917Y959717D01*
X346625Y959592D01*
X346333Y959675D01*
X346125Y959883D01*
X346000Y960175D01*
Y960467D01*
X346083Y960758D01*
X346292Y961008D01*
G01X348500Y962567D02*
X346000D01*
Y963608D01*
X346125Y963942D01*
X346292Y964150D01*
X346625Y964233D01*
X346958Y964150D01*
X347167Y963900D01*
X347292Y963608D01*
Y962567D01*
G01Y963608D02*
X348500Y964233D01*
G01X348208Y965792D02*
X348417Y966083D01*
X348500Y966417D01*
X348417Y966750D01*
X348167Y967042D01*
X347792Y967250D01*
X347417Y967333D01*
X346958D01*
X346583Y967250D01*
X346250Y967042D01*
X346083Y966792D01*
X346000Y966500D01*
X346083Y966167D01*
X346250Y965917D01*
X346500Y965750D01*
X346833Y965667D01*
X347125Y965750D01*
X347417Y965958D01*
X347583Y966208D01*
X347625Y966500D01*
X347542Y966833D01*
X347333Y967083D01*
X346958Y967333D01*
G01X348125Y968683D02*
X348333Y968933D01*
X348458Y969225D01*
X348500Y969600D01*
X348417Y969975D01*
X348250Y970267D01*
X347958Y970475D01*
X347625Y970517D01*
X347292Y970433D01*
X347083Y970225D01*
X346917Y969933D01*
X346875Y969642D01*
X346917Y969350D01*
X347083Y968975D01*
X346000Y969100D01*
Y970225D01*
G01X348000Y971783D02*
X348292Y972033D01*
X348458Y972367D01*
X348500Y972742D01*
X348458Y973075D01*
X348250Y973408D01*
X348000Y973617D01*
X347750Y973658D01*
X347458Y973575D01*
X347250Y973283D01*
X347167Y972992D01*
Y972617D01*
G01Y972992D02*
X347042Y973242D01*
X346833Y973450D01*
X346583Y973533D01*
X346333Y973450D01*
X346125Y973242D01*
X346000Y972867D01*
X346042Y972492D01*
X346208Y972117D01*
G01X345000Y950800D02*
X349000D01*
Y958200D01*
G01X352000Y5000D02*
Y4000D01*
X369000D01*
Y5000D01*
G01X351600Y11200D02*
Y5700D01*
G01X352300D02*
Y11200D01*
G01X360300Y5700D02*
X352300D01*
G01X360300Y11200D02*
Y5700D01*
G01X361000D02*
Y11200D01*
G01X369000Y5700D02*
X361000D01*
G01X351600Y23300D02*
Y17800D01*
G01X360300Y23300D02*
Y17800D01*
G01X352300Y23300D02*
X360300D01*
G01X352300Y17800D02*
Y23300D01*
G01X361000D02*
X369000D01*
G01X361000Y17800D02*
Y23300D01*
G01X353500Y29100D02*
Y63900D01*
G01X358067Y25000D02*
Y27500D01*
X359067D01*
X359400Y27375D01*
X359650Y27083D01*
X359733Y26750D01*
X359650Y26417D01*
X359442Y26167D01*
X359067Y26042D01*
X358067D01*
G01X362917Y27292D02*
X362667Y27417D01*
X362375Y27500D01*
X362042D01*
X361667Y27375D01*
X361375Y27167D01*
X361167Y26917D01*
X361000Y26500D01*
X360958Y26125D01*
X361042Y25750D01*
X361167Y25500D01*
X361417Y25250D01*
X361708Y25083D01*
X362000Y25000D01*
X362292D01*
X362583Y25083D01*
X362833Y25208D01*
X363042Y25375D01*
G01X365100Y25000D02*
Y27500D01*
X364600Y27000D01*
G01Y25000D02*
X365600D01*
G01X367492Y25292D02*
X367783Y25083D01*
X368117Y25000D01*
X368450Y25083D01*
X368742Y25333D01*
X368950Y25708D01*
X369033Y26083D01*
Y26542D01*
X368950Y26917D01*
X368742Y27250D01*
X368492Y27417D01*
X368200Y27500D01*
X367867Y27417D01*
X367617Y27250D01*
X367450Y27000D01*
X367367Y26667D01*
X367450Y26375D01*
X367658Y26083D01*
X367908Y25917D01*
X368200Y25875D01*
X368533Y25958D01*
X368783Y26167D01*
X369033Y26542D01*
G01X370508Y26042D02*
X370800Y26333D01*
X371050Y26500D01*
X371383Y26583D01*
X371675Y26500D01*
X371883Y26333D01*
X372050Y26083D01*
X372092Y25792D01*
X372050Y25542D01*
X371883Y25292D01*
X371633Y25083D01*
X371342Y25000D01*
X371008Y25083D01*
X370717Y25333D01*
X370550Y25708D01*
X370508Y26125D01*
X370592Y26667D01*
X370717Y26958D01*
X370925Y27250D01*
X371217Y27458D01*
X371508Y27500D01*
X371800Y27417D01*
X372008Y27208D01*
G01X355000Y30700D02*
Y36200D01*
G01X363000Y30700D02*
X355000D01*
G01X359000Y52017D02*
X356500D01*
Y53017D01*
X356625Y53350D01*
X356917Y53600D01*
X357250Y53683D01*
X357583Y53600D01*
X357833Y53392D01*
X357958Y53017D01*
Y52017D01*
G01X356500Y55117D02*
X359000D01*
Y56783D01*
G01Y59050D02*
X356500D01*
X357000Y58550D01*
G01X359000D02*
Y59550D01*
G01Y62150D02*
X356500D01*
X357000Y61650D01*
G01X359000D02*
Y62650D01*
G01X355000Y48300D02*
X363000D01*
G01X355000Y42800D02*
Y48300D01*
G01X367500Y61700D02*
X361300D01*
Y49300D01*
X367500D01*
G01X351000Y79300D02*
X355000D01*
Y86700D01*
G01X362667Y105925D02*
X362875Y106258D01*
X363000Y106633D01*
Y106967D01*
X362875Y107300D01*
X362667Y107550D01*
X362375Y107675D01*
X362083Y107592D01*
X361833Y107383D01*
X361667Y107008D01*
X361583Y106508D01*
X361417Y106217D01*
X361125Y106092D01*
X360833Y106175D01*
X360625Y106383D01*
X360500Y106675D01*
Y106967D01*
X360583Y107258D01*
X360792Y107508D01*
G01X363000Y109067D02*
X360500D01*
Y110108D01*
X360625Y110442D01*
X360792Y110650D01*
X361125Y110733D01*
X361458Y110650D01*
X361667Y110400D01*
X361792Y110108D01*
Y109067D01*
G01Y110108D02*
X363000Y110733D01*
G01X362625Y112083D02*
X362833Y112333D01*
X362958Y112625D01*
X363000Y113000D01*
X362917Y113375D01*
X362750Y113667D01*
X362458Y113875D01*
X362125Y113917D01*
X361792Y113833D01*
X361583Y113625D01*
X361417Y113333D01*
X361375Y113042D01*
X361417Y112750D01*
X361583Y112375D01*
X360500Y112500D01*
Y113625D01*
G01X363000Y116100D02*
X362958Y116392D01*
X362833Y116725D01*
X362625Y116933D01*
X362333Y117017D01*
X362042Y116933D01*
X361792Y116683D01*
X361667Y116308D01*
Y115892D01*
X361583Y115642D01*
X361375Y115433D01*
X361083Y115350D01*
X360792Y115475D01*
X360583Y115767D01*
X360500Y116100D01*
X360583Y116433D01*
X360792Y116725D01*
X361083Y116850D01*
X361375Y116767D01*
X361583Y116558D01*
X361667Y116308D01*
Y115892D01*
X361792Y115517D01*
X362042Y115267D01*
X362333Y115183D01*
X362625Y115267D01*
X362833Y115475D01*
X362958Y115808D01*
X363000Y116100D01*
G01Y119200D02*
X360500D01*
X361000Y118700D01*
G01X363000D02*
Y119700D01*
G01X354167Y108965D02*
X354375Y109298D01*
X354500Y109673D01*
Y110007D01*
X354375Y110340D01*
X354167Y110590D01*
X353875Y110715D01*
X353583Y110632D01*
X353333Y110423D01*
X353167Y110048D01*
X353083Y109548D01*
X352917Y109257D01*
X352625Y109132D01*
X352333Y109215D01*
X352125Y109423D01*
X352000Y109715D01*
Y110007D01*
X352083Y110298D01*
X352292Y110548D01*
G01X354500Y112107D02*
X352000D01*
Y113148D01*
X352125Y113482D01*
X352292Y113690D01*
X352625Y113773D01*
X352958Y113690D01*
X353167Y113440D01*
X353292Y113148D01*
Y112107D01*
G01Y113148D02*
X354500Y113773D01*
G01X354125Y115123D02*
X354333Y115373D01*
X354458Y115665D01*
X354500Y116040D01*
X354417Y116415D01*
X354250Y116707D01*
X353958Y116915D01*
X353625Y116957D01*
X353292Y116873D01*
X353083Y116665D01*
X352917Y116373D01*
X352875Y116082D01*
X352917Y115790D01*
X353083Y115415D01*
X352000Y115540D01*
Y116665D01*
G01X354500Y119140D02*
X354458Y119432D01*
X354333Y119765D01*
X354125Y119973D01*
X353833Y120057D01*
X353542Y119973D01*
X353292Y119723D01*
X353167Y119348D01*
Y118932D01*
X353083Y118682D01*
X352875Y118473D01*
X352583Y118390D01*
X352292Y118515D01*
X352083Y118807D01*
X352000Y119140D01*
X352083Y119473D01*
X352292Y119765D01*
X352583Y119890D01*
X352875Y119807D01*
X353083Y119598D01*
X353167Y119348D01*
Y118932D01*
X353292Y118557D01*
X353542Y118307D01*
X353833Y118223D01*
X354125Y118307D01*
X354333Y118515D01*
X354458Y118848D01*
X354500Y119140D01*
G01X352417Y121448D02*
X352167Y121698D01*
X352042Y121990D01*
X352000Y122323D01*
X352083Y122740D01*
X352292Y123032D01*
X352542Y123115D01*
X352792Y123073D01*
X353000Y122907D01*
X353417Y122073D01*
X353708Y121698D01*
X354125Y121448D01*
X354500Y121365D01*
Y123115D01*
G01X358167Y108925D02*
X358375Y109258D01*
X358500Y109633D01*
Y109967D01*
X358375Y110300D01*
X358167Y110550D01*
X357875Y110675D01*
X357583Y110592D01*
X357333Y110383D01*
X357167Y110008D01*
X357083Y109508D01*
X356917Y109217D01*
X356625Y109092D01*
X356333Y109175D01*
X356125Y109383D01*
X356000Y109675D01*
Y109967D01*
X356083Y110258D01*
X356292Y110508D01*
G01X358500Y112067D02*
X356000D01*
Y113108D01*
X356125Y113442D01*
X356292Y113650D01*
X356625Y113733D01*
X356958Y113650D01*
X357167Y113400D01*
X357292Y113108D01*
Y112067D01*
G01Y113108D02*
X358500Y113733D01*
G01X358125Y115083D02*
X358333Y115333D01*
X358458Y115625D01*
X358500Y116000D01*
X358417Y116375D01*
X358250Y116667D01*
X357958Y116875D01*
X357625Y116917D01*
X357292Y116833D01*
X357083Y116625D01*
X356917Y116333D01*
X356875Y116042D01*
X356917Y115750D01*
X357083Y115375D01*
X356000Y115500D01*
Y116625D01*
G01X358500Y119100D02*
X358458Y119392D01*
X358333Y119725D01*
X358125Y119933D01*
X357833Y120017D01*
X357542Y119933D01*
X357292Y119683D01*
X357167Y119308D01*
Y118892D01*
X357083Y118642D01*
X356875Y118433D01*
X356583Y118350D01*
X356292Y118475D01*
X356083Y118767D01*
X356000Y119100D01*
X356083Y119433D01*
X356292Y119725D01*
X356583Y119850D01*
X356875Y119767D01*
X357083Y119558D01*
X357167Y119308D01*
Y118892D01*
X357292Y118517D01*
X357542Y118267D01*
X357833Y118183D01*
X358125Y118267D01*
X358333Y118475D01*
X358458Y118808D01*
X358500Y119100D01*
G01X357458Y121408D02*
X357167Y121700D01*
X357000Y121950D01*
X356917Y122283D01*
X357000Y122575D01*
X357167Y122783D01*
X357417Y122950D01*
X357708Y122992D01*
X357958Y122950D01*
X358208Y122783D01*
X358417Y122533D01*
X358500Y122242D01*
X358417Y121908D01*
X358167Y121617D01*
X357792Y121450D01*
X357375Y121408D01*
X356833Y121492D01*
X356542Y121617D01*
X356250Y121825D01*
X356042Y122117D01*
X356000Y122408D01*
X356083Y122700D01*
X356292Y122908D01*
G01X353740Y129802D02*
Y134370D01*
G01Y216260D02*
Y138070D01*
G01X355590Y127952D02*
X360158D01*
G01X355590D02*
G02I-1850J0D01*
G01Y136220D02*
G02I-1850J0D01*
G01X363858Y127952D02*
G02I-1850J0D01*
G01X353740Y224528D02*
Y219960D01*
G01X355590Y218110D02*
G02I-1850J0D01*
G01Y226378D02*
X360158D01*
G01X355590D02*
G02I-1850J0D01*
G01X363858D02*
G02I-1850J0D01*
G01X356596Y253425D02*
X356804Y253758D01*
X356929Y254133D01*
Y254467D01*
X356804Y254800D01*
X356596Y255050D01*
X356304Y255175D01*
X356012Y255092D01*
X355762Y254883D01*
X355596Y254508D01*
X355512Y254008D01*
X355346Y253717D01*
X355054Y253592D01*
X354762Y253675D01*
X354554Y253883D01*
X354429Y254175D01*
Y254467D01*
X354512Y254758D01*
X354721Y255008D01*
G01X356929Y256567D02*
X354429D01*
Y257608D01*
X354554Y257942D01*
X354721Y258150D01*
X355054Y258233D01*
X355387Y258150D01*
X355596Y257900D01*
X355721Y257608D01*
Y256567D01*
G01Y257608D02*
X356929Y258233D01*
G01X355887Y259708D02*
X355596Y260000D01*
X355429Y260250D01*
X355346Y260583D01*
X355429Y260875D01*
X355596Y261083D01*
X355846Y261250D01*
X356137Y261292D01*
X356387Y261250D01*
X356637Y261083D01*
X356846Y260833D01*
X356929Y260542D01*
X356846Y260208D01*
X356596Y259917D01*
X356221Y259750D01*
X355804Y259708D01*
X355262Y259792D01*
X354971Y259917D01*
X354679Y260125D01*
X354471Y260417D01*
X354429Y260708D01*
X354512Y261000D01*
X354721Y261208D01*
G01X356929Y263517D02*
X356387Y263600D01*
X355929Y263725D01*
X355512Y263892D01*
X355054Y264100D01*
X354429Y264433D01*
Y262767D01*
G01X354846Y265908D02*
X354596Y266158D01*
X354471Y266450D01*
X354429Y266783D01*
X354512Y267200D01*
X354721Y267492D01*
X354971Y267575D01*
X355221Y267533D01*
X355429Y267367D01*
X355846Y266533D01*
X356137Y266158D01*
X356554Y265908D01*
X356929Y265825D01*
Y267575D01*
G01X359429Y252200D02*
X355429D01*
Y244800D01*
G01X361096Y253425D02*
X361304Y253758D01*
X361429Y254133D01*
Y254467D01*
X361304Y254800D01*
X361096Y255050D01*
X360804Y255175D01*
X360512Y255092D01*
X360262Y254883D01*
X360096Y254508D01*
X360012Y254008D01*
X359846Y253717D01*
X359554Y253592D01*
X359262Y253675D01*
X359054Y253883D01*
X358929Y254175D01*
Y254467D01*
X359012Y254758D01*
X359221Y255008D01*
G01X361429Y256567D02*
X358929D01*
Y257608D01*
X359054Y257942D01*
X359221Y258150D01*
X359554Y258233D01*
X359887Y258150D01*
X360096Y257900D01*
X360221Y257608D01*
Y256567D01*
G01Y257608D02*
X361429Y258233D01*
G01X360387Y259708D02*
X360096Y260000D01*
X359929Y260250D01*
X359846Y260583D01*
X359929Y260875D01*
X360096Y261083D01*
X360346Y261250D01*
X360637Y261292D01*
X360887Y261250D01*
X361137Y261083D01*
X361346Y260833D01*
X361429Y260542D01*
X361346Y260208D01*
X361096Y259917D01*
X360721Y259750D01*
X360304Y259708D01*
X359762Y259792D01*
X359471Y259917D01*
X359179Y260125D01*
X358971Y260417D01*
X358929Y260708D01*
X359012Y261000D01*
X359221Y261208D01*
G01X361429Y263517D02*
X360887Y263600D01*
X360429Y263725D01*
X360012Y263892D01*
X359554Y264100D01*
X358929Y264433D01*
Y262767D01*
G01X361429Y267200D02*
X358929D01*
X360721Y265658D01*
Y267742D01*
G01X363929Y252200D02*
X359929D01*
Y244800D01*
G01X352096Y253425D02*
X352304Y253758D01*
X352429Y254133D01*
Y254467D01*
X352304Y254800D01*
X352096Y255050D01*
X351804Y255175D01*
X351512Y255092D01*
X351262Y254883D01*
X351096Y254508D01*
X351012Y254008D01*
X350846Y253717D01*
X350554Y253592D01*
X350262Y253675D01*
X350054Y253883D01*
X349929Y254175D01*
Y254467D01*
X350012Y254758D01*
X350221Y255008D01*
G01X352429Y256567D02*
X349929D01*
Y257608D01*
X350054Y257942D01*
X350221Y258150D01*
X350554Y258233D01*
X350887Y258150D01*
X351096Y257900D01*
X351221Y257608D01*
Y256567D01*
G01Y257608D02*
X352429Y258233D01*
G01X351387Y259708D02*
X351096Y260000D01*
X350929Y260250D01*
X350846Y260583D01*
X350929Y260875D01*
X351096Y261083D01*
X351346Y261250D01*
X351637Y261292D01*
X351887Y261250D01*
X352137Y261083D01*
X352346Y260833D01*
X352429Y260542D01*
X352346Y260208D01*
X352096Y259917D01*
X351721Y259750D01*
X351304Y259708D01*
X350762Y259792D01*
X350471Y259917D01*
X350179Y260125D01*
X349971Y260417D01*
X349929Y260708D01*
X350012Y261000D01*
X350221Y261208D01*
G01X352429Y263517D02*
X351887Y263600D01*
X351429Y263725D01*
X351012Y263892D01*
X350554Y264100D01*
X349929Y264433D01*
Y262767D01*
G01X352429Y266700D02*
X352387Y266992D01*
X352262Y267325D01*
X352054Y267533D01*
X351762Y267617D01*
X351471Y267533D01*
X351221Y267283D01*
X351096Y266908D01*
Y266492D01*
X351012Y266242D01*
X350804Y266033D01*
X350512Y265950D01*
X350221Y266075D01*
X350012Y266367D01*
X349929Y266700D01*
X350012Y267033D01*
X350221Y267325D01*
X350512Y267450D01*
X350804Y267367D01*
X351012Y267158D01*
X351096Y266908D01*
Y266492D01*
X351221Y266117D01*
X351471Y265867D01*
X351762Y265783D01*
X352054Y265867D01*
X352262Y266075D01*
X352387Y266408D01*
X352429Y266700D01*
G01X354929Y252200D02*
X350929D01*
Y244800D01*
G01X359167Y278375D02*
X359375Y278708D01*
X359500Y279083D01*
Y279417D01*
X359375Y279750D01*
X359167Y280000D01*
X358875Y280125D01*
X358583Y280042D01*
X358333Y279833D01*
X358167Y279458D01*
X358083Y278958D01*
X357917Y278667D01*
X357625Y278542D01*
X357333Y278625D01*
X357125Y278833D01*
X357000Y279125D01*
Y279417D01*
X357083Y279708D01*
X357292Y279958D01*
G01X357208Y283267D02*
X357083Y283017D01*
X357000Y282725D01*
Y282392D01*
X357125Y282017D01*
X357333Y281725D01*
X357583Y281517D01*
X358000Y281350D01*
X358375Y281308D01*
X358750Y281392D01*
X359000Y281517D01*
X359250Y281767D01*
X359417Y282058D01*
X359500Y282350D01*
Y282642D01*
X359417Y282933D01*
X359292Y283183D01*
X359125Y283392D01*
G01X359500Y285450D02*
X357000D01*
X357500Y284950D01*
G01X359500D02*
Y285950D01*
G01X357000Y288550D02*
X357083Y288217D01*
X357292Y287967D01*
X357542Y287800D01*
X357875Y287675D01*
X358250Y287633D01*
X358625Y287675D01*
X358958Y287800D01*
X359208Y287967D01*
X359417Y288217D01*
X359500Y288550D01*
X359417Y288883D01*
X359208Y289133D01*
X358958Y289300D01*
X358625Y289425D01*
X358250Y289467D01*
X357875Y289425D01*
X357542Y289300D01*
X357292Y289133D01*
X357083Y288883D01*
X357000Y288550D01*
G01Y291650D02*
X357083Y291317D01*
X357292Y291067D01*
X357542Y290900D01*
X357875Y290775D01*
X358250Y290733D01*
X358625Y290775D01*
X358958Y290900D01*
X359208Y291067D01*
X359417Y291317D01*
X359500Y291650D01*
X359417Y291983D01*
X359208Y292233D01*
X358958Y292400D01*
X358625Y292525D01*
X358250Y292567D01*
X357875Y292525D01*
X357542Y292400D01*
X357292Y292233D01*
X357083Y291983D01*
X357000Y291650D01*
G01X357417Y293958D02*
X357167Y294208D01*
X357042Y294500D01*
X357000Y294833D01*
X357083Y295250D01*
X357292Y295542D01*
X357542Y295625D01*
X357792Y295583D01*
X358000Y295417D01*
X358417Y294583D01*
X358708Y294208D01*
X359125Y293958D01*
X359500Y293875D01*
Y295625D01*
G01X354667Y278375D02*
X354875Y278708D01*
X355000Y279083D01*
Y279417D01*
X354875Y279750D01*
X354667Y280000D01*
X354375Y280125D01*
X354083Y280042D01*
X353833Y279833D01*
X353667Y279458D01*
X353583Y278958D01*
X353417Y278667D01*
X353125Y278542D01*
X352833Y278625D01*
X352625Y278833D01*
X352500Y279125D01*
Y279417D01*
X352583Y279708D01*
X352792Y279958D01*
G01X352708Y283267D02*
X352583Y283017D01*
X352500Y282725D01*
Y282392D01*
X352625Y282017D01*
X352833Y281725D01*
X353083Y281517D01*
X353500Y281350D01*
X353875Y281308D01*
X354250Y281392D01*
X354500Y281517D01*
X354750Y281767D01*
X354917Y282058D01*
X355000Y282350D01*
Y282642D01*
X354917Y282933D01*
X354792Y283183D01*
X354625Y283392D01*
G01X355000Y285450D02*
X352500D01*
X353000Y284950D01*
G01X355000D02*
Y285950D01*
G01X352500Y288550D02*
X352583Y288217D01*
X352792Y287967D01*
X353042Y287800D01*
X353375Y287675D01*
X353750Y287633D01*
X354125Y287675D01*
X354458Y287800D01*
X354708Y287967D01*
X354917Y288217D01*
X355000Y288550D01*
X354917Y288883D01*
X354708Y289133D01*
X354458Y289300D01*
X354125Y289425D01*
X353750Y289467D01*
X353375Y289425D01*
X353042Y289300D01*
X352792Y289133D01*
X352583Y288883D01*
X352500Y288550D01*
G01Y291650D02*
X352583Y291317D01*
X352792Y291067D01*
X353042Y290900D01*
X353375Y290775D01*
X353750Y290733D01*
X354125Y290775D01*
X354458Y290900D01*
X354708Y291067D01*
X354917Y291317D01*
X355000Y291650D01*
X354917Y291983D01*
X354708Y292233D01*
X354458Y292400D01*
X354125Y292525D01*
X353750Y292567D01*
X353375Y292525D01*
X353042Y292400D01*
X352792Y292233D01*
X352583Y291983D01*
X352500Y291650D01*
G01Y294750D02*
X352583Y294417D01*
X352792Y294167D01*
X353042Y294000D01*
X353375Y293875D01*
X353750Y293833D01*
X354125Y293875D01*
X354458Y294000D01*
X354708Y294167D01*
X354917Y294417D01*
X355000Y294750D01*
X354917Y295083D01*
X354708Y295333D01*
X354458Y295500D01*
X354125Y295625D01*
X353750Y295667D01*
X353375Y295625D01*
X353042Y295500D01*
X352792Y295333D01*
X352583Y295083D01*
X352500Y294750D01*
G01X362430Y295333D02*
X362763Y295125D01*
X363138Y295000D01*
X363472D01*
X363805Y295125D01*
X364055Y295333D01*
X364180Y295625D01*
X364097Y295917D01*
X363888Y296167D01*
X363513Y296333D01*
X363013Y296417D01*
X362722Y296583D01*
X362597Y296875D01*
X362680Y297167D01*
X362888Y297375D01*
X363180Y297500D01*
X363472D01*
X363763Y297417D01*
X364013Y297208D01*
G01X366405Y297500D02*
Y295000D01*
G01X365447Y297500D02*
X367363D01*
G01X368672Y295000D02*
Y297500D01*
X369672D01*
X370005Y297375D01*
X370255Y297083D01*
X370338Y296750D01*
X370255Y296417D01*
X370047Y296167D01*
X369672Y296042D01*
X368672D01*
G01X372605Y295000D02*
Y297500D01*
X372105Y297000D01*
G01Y295000D02*
X373105D01*
G01X374788Y295375D02*
X375038Y295167D01*
X375330Y295042D01*
X375705Y295000D01*
X376080Y295083D01*
X376372Y295250D01*
X376580Y295542D01*
X376622Y295875D01*
X376538Y296208D01*
X376330Y296417D01*
X376038Y296583D01*
X375747Y296625D01*
X375455Y296583D01*
X375080Y296417D01*
X375205Y297500D01*
X376330D01*
G01X378805D02*
X378472Y297417D01*
X378222Y297208D01*
X378055Y296958D01*
X377930Y296625D01*
X377888Y296250D01*
X377930Y295875D01*
X378055Y295542D01*
X378222Y295292D01*
X378472Y295083D01*
X378805Y295000D01*
X379138Y295083D01*
X379388Y295292D01*
X379555Y295542D01*
X379680Y295875D01*
X379722Y296250D01*
X379680Y296625D01*
X379555Y296958D01*
X379388Y297208D01*
X379138Y297417D01*
X378805Y297500D01*
G01X362430Y299833D02*
X362763Y299625D01*
X363138Y299500D01*
X363472D01*
X363805Y299625D01*
X364055Y299833D01*
X364180Y300125D01*
X364097Y300417D01*
X363888Y300667D01*
X363513Y300833D01*
X363013Y300917D01*
X362722Y301083D01*
X362597Y301375D01*
X362680Y301667D01*
X362888Y301875D01*
X363180Y302000D01*
X363472D01*
X363763Y301917D01*
X364013Y301708D01*
G01X366405Y302000D02*
Y299500D01*
G01X365447Y302000D02*
X367363D01*
G01X368672Y299500D02*
Y302000D01*
X369672D01*
X370005Y301875D01*
X370255Y301583D01*
X370338Y301250D01*
X370255Y300917D01*
X370047Y300667D01*
X369672Y300542D01*
X368672D01*
G01X372605Y299500D02*
Y302000D01*
X372105Y301500D01*
G01Y299500D02*
X373105D01*
G01X375705Y302000D02*
X375372Y301917D01*
X375122Y301708D01*
X374955Y301458D01*
X374830Y301125D01*
X374788Y300750D01*
X374830Y300375D01*
X374955Y300042D01*
X375122Y299792D01*
X375372Y299583D01*
X375705Y299500D01*
X376038Y299583D01*
X376288Y299792D01*
X376455Y300042D01*
X376580Y300375D01*
X376622Y300750D01*
X376580Y301125D01*
X376455Y301458D01*
X376288Y301708D01*
X376038Y301917D01*
X375705Y302000D01*
G01X378013Y301583D02*
X378263Y301833D01*
X378555Y301958D01*
X378888Y302000D01*
X379305Y301917D01*
X379597Y301708D01*
X379680Y301458D01*
X379638Y301208D01*
X379472Y301000D01*
X378638Y300583D01*
X378263Y300292D01*
X378013Y299875D01*
X377930Y299500D01*
X379680D01*
G01X356980Y304333D02*
X357313Y304125D01*
X357688Y304000D01*
X358022D01*
X358355Y304125D01*
X358605Y304333D01*
X358730Y304625D01*
X358647Y304917D01*
X358438Y305167D01*
X358063Y305333D01*
X357563Y305417D01*
X357272Y305583D01*
X357147Y305875D01*
X357230Y306167D01*
X357438Y306375D01*
X357730Y306500D01*
X358022D01*
X358313Y306417D01*
X358563Y306208D01*
G01X360122Y304000D02*
Y306500D01*
X361163D01*
X361497Y306375D01*
X361705Y306208D01*
X361788Y305875D01*
X361705Y305542D01*
X361455Y305333D01*
X361163Y305208D01*
X360122D01*
G01X361163D02*
X361788Y304000D01*
G01X364055D02*
X364347Y304042D01*
X364680Y304167D01*
X364888Y304375D01*
X364972Y304667D01*
X364888Y304958D01*
X364638Y305208D01*
X364263Y305333D01*
X363847D01*
X363597Y305417D01*
X363388Y305625D01*
X363305Y305917D01*
X363430Y306208D01*
X363722Y306417D01*
X364055Y306500D01*
X364388Y306417D01*
X364680Y306208D01*
X364805Y305917D01*
X364722Y305625D01*
X364513Y305417D01*
X364263Y305333D01*
X363847D01*
X363472Y305208D01*
X363222Y304958D01*
X363138Y304667D01*
X363222Y304375D01*
X363430Y304167D01*
X363763Y304042D01*
X364055Y304000D01*
G01X367155D02*
Y306500D01*
X366655Y306000D01*
G01Y304000D02*
X367655D01*
G01X369338Y304375D02*
X369588Y304167D01*
X369880Y304042D01*
X370255Y304000D01*
X370630Y304083D01*
X370922Y304250D01*
X371130Y304542D01*
X371172Y304875D01*
X371088Y305208D01*
X370880Y305417D01*
X370588Y305583D01*
X370297Y305625D01*
X370005Y305583D01*
X369630Y305417D01*
X369755Y306500D01*
X370880D01*
G01X356980Y313333D02*
X357313Y313125D01*
X357688Y313000D01*
X358022D01*
X358355Y313125D01*
X358605Y313333D01*
X358730Y313625D01*
X358647Y313917D01*
X358438Y314167D01*
X358063Y314333D01*
X357563Y314417D01*
X357272Y314583D01*
X357147Y314875D01*
X357230Y315167D01*
X357438Y315375D01*
X357730Y315500D01*
X358022D01*
X358313Y315417D01*
X358563Y315208D01*
G01X360122Y313000D02*
Y315500D01*
X361163D01*
X361497Y315375D01*
X361705Y315208D01*
X361788Y314875D01*
X361705Y314542D01*
X361455Y314333D01*
X361163Y314208D01*
X360122D01*
G01X361163D02*
X361788Y313000D01*
G01X363972D02*
X364055Y313542D01*
X364180Y314000D01*
X364347Y314417D01*
X364555Y314875D01*
X364888Y315500D01*
X363222D01*
G01X367155Y313000D02*
X367447Y313042D01*
X367780Y313167D01*
X367988Y313375D01*
X368072Y313667D01*
X367988Y313958D01*
X367738Y314208D01*
X367363Y314333D01*
X366947D01*
X366697Y314417D01*
X366488Y314625D01*
X366405Y314917D01*
X366530Y315208D01*
X366822Y315417D01*
X367155Y315500D01*
X367488Y315417D01*
X367780Y315208D01*
X367905Y314917D01*
X367822Y314625D01*
X367613Y314417D01*
X367363Y314333D01*
X366947D01*
X366572Y314208D01*
X366322Y313958D01*
X366238Y313667D01*
X366322Y313375D01*
X366530Y313167D01*
X366863Y313042D01*
X367155Y313000D01*
G01X369547Y313292D02*
X369838Y313083D01*
X370172Y313000D01*
X370505Y313083D01*
X370797Y313333D01*
X371005Y313708D01*
X371088Y314083D01*
Y314542D01*
X371005Y314917D01*
X370797Y315250D01*
X370547Y315417D01*
X370255Y315500D01*
X369922Y315417D01*
X369672Y315250D01*
X369505Y315000D01*
X369422Y314667D01*
X369505Y314375D01*
X369713Y314083D01*
X369963Y313917D01*
X370255Y313875D01*
X370588Y313958D01*
X370838Y314167D01*
X371088Y314542D01*
G01X356980Y317833D02*
X357313Y317625D01*
X357688Y317500D01*
X358022D01*
X358355Y317625D01*
X358605Y317833D01*
X358730Y318125D01*
X358647Y318417D01*
X358438Y318667D01*
X358063Y318833D01*
X357563Y318917D01*
X357272Y319083D01*
X357147Y319375D01*
X357230Y319667D01*
X357438Y319875D01*
X357730Y320000D01*
X358022D01*
X358313Y319917D01*
X358563Y319708D01*
G01X360122Y317500D02*
Y320000D01*
X361163D01*
X361497Y319875D01*
X361705Y319708D01*
X361788Y319375D01*
X361705Y319042D01*
X361455Y318833D01*
X361163Y318708D01*
X360122D01*
G01X361163D02*
X361788Y317500D01*
G01X363972D02*
X364055Y318042D01*
X364180Y318500D01*
X364347Y318917D01*
X364555Y319375D01*
X364888Y320000D01*
X363222D01*
G01X366447Y317792D02*
X366738Y317583D01*
X367072Y317500D01*
X367405Y317583D01*
X367697Y317833D01*
X367905Y318208D01*
X367988Y318583D01*
Y319042D01*
X367905Y319417D01*
X367697Y319750D01*
X367447Y319917D01*
X367155Y320000D01*
X366822Y319917D01*
X366572Y319750D01*
X366405Y319500D01*
X366322Y319167D01*
X366405Y318875D01*
X366613Y318583D01*
X366863Y318417D01*
X367155Y318375D01*
X367488Y318458D01*
X367738Y318667D01*
X367988Y319042D01*
G01X369547Y317792D02*
X369838Y317583D01*
X370172Y317500D01*
X370505Y317583D01*
X370797Y317833D01*
X371005Y318208D01*
X371088Y318583D01*
Y319042D01*
X371005Y319417D01*
X370797Y319750D01*
X370547Y319917D01*
X370255Y320000D01*
X369922Y319917D01*
X369672Y319750D01*
X369505Y319500D01*
X369422Y319167D01*
X369505Y318875D01*
X369713Y318583D01*
X369963Y318417D01*
X370255Y318375D01*
X370588Y318458D01*
X370838Y318667D01*
X371088Y319042D01*
G01X356980Y308833D02*
X357313Y308625D01*
X357688Y308500D01*
X358022D01*
X358355Y308625D01*
X358605Y308833D01*
X358730Y309125D01*
X358647Y309417D01*
X358438Y309667D01*
X358063Y309833D01*
X357563Y309917D01*
X357272Y310083D01*
X357147Y310375D01*
X357230Y310667D01*
X357438Y310875D01*
X357730Y311000D01*
X358022D01*
X358313Y310917D01*
X358563Y310708D01*
G01X360122Y308500D02*
Y311000D01*
X361163D01*
X361497Y310875D01*
X361705Y310708D01*
X361788Y310375D01*
X361705Y310042D01*
X361455Y309833D01*
X361163Y309708D01*
X360122D01*
G01X361163D02*
X361788Y308500D01*
G01X364055D02*
X364347Y308542D01*
X364680Y308667D01*
X364888Y308875D01*
X364972Y309167D01*
X364888Y309458D01*
X364638Y309708D01*
X364263Y309833D01*
X363847D01*
X363597Y309917D01*
X363388Y310125D01*
X363305Y310417D01*
X363430Y310708D01*
X363722Y310917D01*
X364055Y311000D01*
X364388Y310917D01*
X364680Y310708D01*
X364805Y310417D01*
X364722Y310125D01*
X364513Y309917D01*
X364263Y309833D01*
X363847D01*
X363472Y309708D01*
X363222Y309458D01*
X363138Y309167D01*
X363222Y308875D01*
X363430Y308667D01*
X363763Y308542D01*
X364055Y308500D01*
G01X367155Y311000D02*
X366822Y310917D01*
X366572Y310708D01*
X366405Y310458D01*
X366280Y310125D01*
X366238Y309750D01*
X366280Y309375D01*
X366405Y309042D01*
X366572Y308792D01*
X366822Y308583D01*
X367155Y308500D01*
X367488Y308583D01*
X367738Y308792D01*
X367905Y309042D01*
X368030Y309375D01*
X368072Y309750D01*
X368030Y310125D01*
X367905Y310458D01*
X367738Y310708D01*
X367488Y310917D01*
X367155Y311000D01*
G01X370255D02*
X369922Y310917D01*
X369672Y310708D01*
X369505Y310458D01*
X369380Y310125D01*
X369338Y309750D01*
X369380Y309375D01*
X369505Y309042D01*
X369672Y308792D01*
X369922Y308583D01*
X370255Y308500D01*
X370588Y308583D01*
X370838Y308792D01*
X371005Y309042D01*
X371130Y309375D01*
X371172Y309750D01*
X371130Y310125D01*
X371005Y310458D01*
X370838Y310708D01*
X370588Y310917D01*
X370255Y311000D01*
G01X356980Y331333D02*
X357313Y331125D01*
X357688Y331000D01*
X358022D01*
X358355Y331125D01*
X358605Y331333D01*
X358730Y331625D01*
X358647Y331917D01*
X358438Y332167D01*
X358063Y332333D01*
X357563Y332417D01*
X357272Y332583D01*
X357147Y332875D01*
X357230Y333167D01*
X357438Y333375D01*
X357730Y333500D01*
X358022D01*
X358313Y333417D01*
X358563Y333208D01*
G01X360122Y331000D02*
Y333500D01*
X361163D01*
X361497Y333375D01*
X361705Y333208D01*
X361788Y332875D01*
X361705Y332542D01*
X361455Y332333D01*
X361163Y332208D01*
X360122D01*
G01X361163D02*
X361788Y331000D01*
G01X363972D02*
X364055Y331542D01*
X364180Y332000D01*
X364347Y332417D01*
X364555Y332875D01*
X364888Y333500D01*
X363222D01*
G01X367072Y331000D02*
X367155Y331542D01*
X367280Y332000D01*
X367447Y332417D01*
X367655Y332875D01*
X367988Y333500D01*
X366322D01*
G01X369463Y333083D02*
X369713Y333333D01*
X370005Y333458D01*
X370338Y333500D01*
X370755Y333417D01*
X371047Y333208D01*
X371130Y332958D01*
X371088Y332708D01*
X370922Y332500D01*
X370088Y332083D01*
X369713Y331792D01*
X369463Y331375D01*
X369380Y331000D01*
X371130D01*
G01X356980Y335833D02*
X357313Y335625D01*
X357688Y335500D01*
X358022D01*
X358355Y335625D01*
X358605Y335833D01*
X358730Y336125D01*
X358647Y336417D01*
X358438Y336667D01*
X358063Y336833D01*
X357563Y336917D01*
X357272Y337083D01*
X357147Y337375D01*
X357230Y337667D01*
X357438Y337875D01*
X357730Y338000D01*
X358022D01*
X358313Y337917D01*
X358563Y337708D01*
G01X360122Y335500D02*
Y338000D01*
X361163D01*
X361497Y337875D01*
X361705Y337708D01*
X361788Y337375D01*
X361705Y337042D01*
X361455Y336833D01*
X361163Y336708D01*
X360122D01*
G01X361163D02*
X361788Y335500D01*
G01X363972D02*
X364055Y336042D01*
X364180Y336500D01*
X364347Y336917D01*
X364555Y337375D01*
X364888Y338000D01*
X363222D01*
G01X367072Y335500D02*
X367155Y336042D01*
X367280Y336500D01*
X367447Y336917D01*
X367655Y337375D01*
X367988Y338000D01*
X366322D01*
G01X369338Y335875D02*
X369588Y335667D01*
X369880Y335542D01*
X370255Y335500D01*
X370630Y335583D01*
X370922Y335750D01*
X371130Y336042D01*
X371172Y336375D01*
X371088Y336708D01*
X370880Y336917D01*
X370588Y337083D01*
X370297Y337125D01*
X370005Y337083D01*
X369630Y336917D01*
X369755Y338000D01*
X370880D01*
G01X356980Y322333D02*
X357313Y322125D01*
X357688Y322000D01*
X358022D01*
X358355Y322125D01*
X358605Y322333D01*
X358730Y322625D01*
X358647Y322917D01*
X358438Y323167D01*
X358063Y323333D01*
X357563Y323417D01*
X357272Y323583D01*
X357147Y323875D01*
X357230Y324167D01*
X357438Y324375D01*
X357730Y324500D01*
X358022D01*
X358313Y324417D01*
X358563Y324208D01*
G01X360122Y322000D02*
Y324500D01*
X361163D01*
X361497Y324375D01*
X361705Y324208D01*
X361788Y323875D01*
X361705Y323542D01*
X361455Y323333D01*
X361163Y323208D01*
X360122D01*
G01X361163D02*
X361788Y322000D01*
G01X363972D02*
X364055Y322542D01*
X364180Y323000D01*
X364347Y323417D01*
X364555Y323875D01*
X364888Y324500D01*
X363222D01*
G01X366447Y322292D02*
X366738Y322083D01*
X367072Y322000D01*
X367405Y322083D01*
X367697Y322333D01*
X367905Y322708D01*
X367988Y323083D01*
Y323542D01*
X367905Y323917D01*
X367697Y324250D01*
X367447Y324417D01*
X367155Y324500D01*
X366822Y324417D01*
X366572Y324250D01*
X366405Y324000D01*
X366322Y323667D01*
X366405Y323375D01*
X366613Y323083D01*
X366863Y322917D01*
X367155Y322875D01*
X367488Y322958D01*
X367738Y323167D01*
X367988Y323542D01*
G01X370172Y322000D02*
X370255Y322542D01*
X370380Y323000D01*
X370547Y323417D01*
X370755Y323875D01*
X371088Y324500D01*
X369422D01*
G01X356980Y326833D02*
X357313Y326625D01*
X357688Y326500D01*
X358022D01*
X358355Y326625D01*
X358605Y326833D01*
X358730Y327125D01*
X358647Y327417D01*
X358438Y327667D01*
X358063Y327833D01*
X357563Y327917D01*
X357272Y328083D01*
X357147Y328375D01*
X357230Y328667D01*
X357438Y328875D01*
X357730Y329000D01*
X358022D01*
X358313Y328917D01*
X358563Y328708D01*
G01X360122Y326500D02*
Y329000D01*
X361163D01*
X361497Y328875D01*
X361705Y328708D01*
X361788Y328375D01*
X361705Y328042D01*
X361455Y327833D01*
X361163Y327708D01*
X360122D01*
G01X361163D02*
X361788Y326500D01*
G01X364055D02*
X364347Y326542D01*
X364680Y326667D01*
X364888Y326875D01*
X364972Y327167D01*
X364888Y327458D01*
X364638Y327708D01*
X364263Y327833D01*
X363847D01*
X363597Y327917D01*
X363388Y328125D01*
X363305Y328417D01*
X363430Y328708D01*
X363722Y328917D01*
X364055Y329000D01*
X364388Y328917D01*
X364680Y328708D01*
X364805Y328417D01*
X364722Y328125D01*
X364513Y327917D01*
X364263Y327833D01*
X363847D01*
X363472Y327708D01*
X363222Y327458D01*
X363138Y327167D01*
X363222Y326875D01*
X363430Y326667D01*
X363763Y326542D01*
X364055Y326500D01*
G01X367155Y329000D02*
X366822Y328917D01*
X366572Y328708D01*
X366405Y328458D01*
X366280Y328125D01*
X366238Y327750D01*
X366280Y327375D01*
X366405Y327042D01*
X366572Y326792D01*
X366822Y326583D01*
X367155Y326500D01*
X367488Y326583D01*
X367738Y326792D01*
X367905Y327042D01*
X368030Y327375D01*
X368072Y327750D01*
X368030Y328125D01*
X367905Y328458D01*
X367738Y328708D01*
X367488Y328917D01*
X367155Y329000D01*
G01X370255Y326500D02*
X370547Y326542D01*
X370880Y326667D01*
X371088Y326875D01*
X371172Y327167D01*
X371088Y327458D01*
X370838Y327708D01*
X370463Y327833D01*
X370047D01*
X369797Y327917D01*
X369588Y328125D01*
X369505Y328417D01*
X369630Y328708D01*
X369922Y328917D01*
X370255Y329000D01*
X370588Y328917D01*
X370880Y328708D01*
X371005Y328417D01*
X370922Y328125D01*
X370713Y327917D01*
X370463Y327833D01*
X370047D01*
X369672Y327708D01*
X369422Y327458D01*
X369338Y327167D01*
X369422Y326875D01*
X369630Y326667D01*
X369963Y326542D01*
X370255Y326500D01*
G01X361596Y349875D02*
X361804Y350208D01*
X361929Y350583D01*
Y350917D01*
X361804Y351250D01*
X361596Y351500D01*
X361304Y351625D01*
X361012Y351542D01*
X360762Y351333D01*
X360596Y350958D01*
X360512Y350458D01*
X360346Y350167D01*
X360054Y350042D01*
X359762Y350125D01*
X359554Y350333D01*
X359429Y350625D01*
Y350917D01*
X359512Y351208D01*
X359721Y351458D01*
G01X359637Y354767D02*
X359512Y354517D01*
X359429Y354225D01*
Y353892D01*
X359554Y353517D01*
X359762Y353225D01*
X360012Y353017D01*
X360429Y352850D01*
X360804Y352808D01*
X361179Y352892D01*
X361429Y353017D01*
X361679Y353267D01*
X361846Y353558D01*
X361929Y353850D01*
Y354142D01*
X361846Y354433D01*
X361721Y354683D01*
X361554Y354892D01*
G01X361929Y356950D02*
X359429D01*
X359929Y356450D01*
G01X361929D02*
Y357450D01*
G01Y360050D02*
X359429D01*
X359929Y359550D01*
G01X361929D02*
Y360550D01*
G01Y363650D02*
X359429D01*
X361221Y362108D01*
Y364192D01*
G01X361929Y366250D02*
X361887Y366542D01*
X361762Y366875D01*
X361554Y367083D01*
X361262Y367167D01*
X360971Y367083D01*
X360721Y366833D01*
X360596Y366458D01*
Y366042D01*
X360512Y365792D01*
X360304Y365583D01*
X360012Y365500D01*
X359721Y365625D01*
X359512Y365917D01*
X359429Y366250D01*
X359512Y366583D01*
X359721Y366875D01*
X360012Y367000D01*
X360304Y366917D01*
X360512Y366708D01*
X360596Y366458D01*
Y366042D01*
X360721Y365667D01*
X360971Y365417D01*
X361262Y365333D01*
X361554Y365417D01*
X361762Y365625D01*
X361887Y365958D01*
X361929Y366250D01*
G01X357596Y349875D02*
X357804Y350208D01*
X357929Y350583D01*
Y350917D01*
X357804Y351250D01*
X357596Y351500D01*
X357304Y351625D01*
X357012Y351542D01*
X356762Y351333D01*
X356596Y350958D01*
X356512Y350458D01*
X356346Y350167D01*
X356054Y350042D01*
X355762Y350125D01*
X355554Y350333D01*
X355429Y350625D01*
Y350917D01*
X355512Y351208D01*
X355721Y351458D01*
G01X355637Y354767D02*
X355512Y354517D01*
X355429Y354225D01*
Y353892D01*
X355554Y353517D01*
X355762Y353225D01*
X356012Y353017D01*
X356429Y352850D01*
X356804Y352808D01*
X357179Y352892D01*
X357429Y353017D01*
X357679Y353267D01*
X357846Y353558D01*
X357929Y353850D01*
Y354142D01*
X357846Y354433D01*
X357721Y354683D01*
X357554Y354892D01*
G01X357929Y356950D02*
X355429D01*
X355929Y356450D01*
G01X357929D02*
Y357450D01*
G01Y360050D02*
X355429D01*
X355929Y359550D01*
G01X357929D02*
Y360550D01*
G01Y363650D02*
X355429D01*
X357221Y362108D01*
Y364192D01*
G01X356887Y365458D02*
X356596Y365750D01*
X356429Y366000D01*
X356346Y366333D01*
X356429Y366625D01*
X356596Y366833D01*
X356846Y367000D01*
X357137Y367042D01*
X357387Y367000D01*
X357637Y366833D01*
X357846Y366583D01*
X357929Y366292D01*
X357846Y365958D01*
X357596Y365667D01*
X357221Y365500D01*
X356804Y365458D01*
X356262Y365542D01*
X355971Y365667D01*
X355679Y365875D01*
X355471Y366167D01*
X355429Y366458D01*
X355512Y366750D01*
X355721Y366958D01*
G01X353596Y349875D02*
X353804Y350208D01*
X353929Y350583D01*
Y350917D01*
X353804Y351250D01*
X353596Y351500D01*
X353304Y351625D01*
X353012Y351542D01*
X352762Y351333D01*
X352596Y350958D01*
X352512Y350458D01*
X352346Y350167D01*
X352054Y350042D01*
X351762Y350125D01*
X351554Y350333D01*
X351429Y350625D01*
Y350917D01*
X351512Y351208D01*
X351721Y351458D01*
G01X351637Y354767D02*
X351512Y354517D01*
X351429Y354225D01*
Y353892D01*
X351554Y353517D01*
X351762Y353225D01*
X352012Y353017D01*
X352429Y352850D01*
X352804Y352808D01*
X353179Y352892D01*
X353429Y353017D01*
X353679Y353267D01*
X353846Y353558D01*
X353929Y353850D01*
Y354142D01*
X353846Y354433D01*
X353721Y354683D01*
X353554Y354892D01*
G01X353929Y356950D02*
X351429D01*
X351929Y356450D01*
G01X353929D02*
Y357450D01*
G01Y360050D02*
X351429D01*
X351929Y359550D01*
G01X353929D02*
Y360550D01*
G01Y363650D02*
X351429D01*
X353221Y362108D01*
Y364192D01*
G01X353929Y366167D02*
X353387Y366250D01*
X352929Y366375D01*
X352512Y366542D01*
X352054Y366750D01*
X351429Y367083D01*
Y365417D01*
G01X356980Y340333D02*
X357313Y340125D01*
X357688Y340000D01*
X358022D01*
X358355Y340125D01*
X358605Y340333D01*
X358730Y340625D01*
X358647Y340917D01*
X358438Y341167D01*
X358063Y341333D01*
X357563Y341417D01*
X357272Y341583D01*
X357147Y341875D01*
X357230Y342167D01*
X357438Y342375D01*
X357730Y342500D01*
X358022D01*
X358313Y342417D01*
X358563Y342208D01*
G01X360122Y340000D02*
Y342500D01*
X361163D01*
X361497Y342375D01*
X361705Y342208D01*
X361788Y341875D01*
X361705Y341542D01*
X361455Y341333D01*
X361163Y341208D01*
X360122D01*
G01X361163D02*
X361788Y340000D01*
G01X363972D02*
X364055Y340542D01*
X364180Y341000D01*
X364347Y341417D01*
X364555Y341875D01*
X364888Y342500D01*
X363222D01*
G01X367155Y340000D02*
X367447Y340042D01*
X367780Y340167D01*
X367988Y340375D01*
X368072Y340667D01*
X367988Y340958D01*
X367738Y341208D01*
X367363Y341333D01*
X366947D01*
X366697Y341417D01*
X366488Y341625D01*
X366405Y341917D01*
X366530Y342208D01*
X366822Y342417D01*
X367155Y342500D01*
X367488Y342417D01*
X367780Y342208D01*
X367905Y341917D01*
X367822Y341625D01*
X367613Y341417D01*
X367363Y341333D01*
X366947D01*
X366572Y341208D01*
X366322Y340958D01*
X366238Y340667D01*
X366322Y340375D01*
X366530Y340167D01*
X366863Y340042D01*
X367155Y340000D01*
G01X370172D02*
X370255Y340542D01*
X370380Y341000D01*
X370547Y341417D01*
X370755Y341875D01*
X371088Y342500D01*
X369422D01*
G01X356980Y344833D02*
X357313Y344625D01*
X357688Y344500D01*
X358022D01*
X358355Y344625D01*
X358605Y344833D01*
X358730Y345125D01*
X358647Y345417D01*
X358438Y345667D01*
X358063Y345833D01*
X357563Y345917D01*
X357272Y346083D01*
X357147Y346375D01*
X357230Y346667D01*
X357438Y346875D01*
X357730Y347000D01*
X358022D01*
X358313Y346917D01*
X358563Y346708D01*
G01X360122Y344500D02*
Y347000D01*
X361163D01*
X361497Y346875D01*
X361705Y346708D01*
X361788Y346375D01*
X361705Y346042D01*
X361455Y345833D01*
X361163Y345708D01*
X360122D01*
G01X361163D02*
X361788Y344500D01*
G01X363972D02*
X364055Y345042D01*
X364180Y345500D01*
X364347Y345917D01*
X364555Y346375D01*
X364888Y347000D01*
X363222D01*
G01X366447Y344792D02*
X366738Y344583D01*
X367072Y344500D01*
X367405Y344583D01*
X367697Y344833D01*
X367905Y345208D01*
X367988Y345583D01*
Y346042D01*
X367905Y346417D01*
X367697Y346750D01*
X367447Y346917D01*
X367155Y347000D01*
X366822Y346917D01*
X366572Y346750D01*
X366405Y346500D01*
X366322Y346167D01*
X366405Y345875D01*
X366613Y345583D01*
X366863Y345417D01*
X367155Y345375D01*
X367488Y345458D01*
X367738Y345667D01*
X367988Y346042D01*
G01X370255Y344500D02*
X370547Y344542D01*
X370880Y344667D01*
X371088Y344875D01*
X371172Y345167D01*
X371088Y345458D01*
X370838Y345708D01*
X370463Y345833D01*
X370047D01*
X369797Y345917D01*
X369588Y346125D01*
X369505Y346417D01*
X369630Y346708D01*
X369922Y346917D01*
X370255Y347000D01*
X370588Y346917D01*
X370880Y346708D01*
X371005Y346417D01*
X370922Y346125D01*
X370713Y345917D01*
X370463Y345833D01*
X370047D01*
X369672Y345708D01*
X369422Y345458D01*
X369338Y345167D01*
X369422Y344875D01*
X369630Y344667D01*
X369963Y344542D01*
X370255Y344500D01*
G01X366755Y374000D02*
Y378000D01*
X359355D01*
G01X366755Y378500D02*
Y382500D01*
X359355D01*
G01X366755Y369000D02*
Y373000D01*
X359355D01*
G01X357112Y387425D02*
X357320Y387758D01*
X357445Y388133D01*
Y388467D01*
X357320Y388800D01*
X357112Y389050D01*
X356820Y389175D01*
X356528Y389092D01*
X356278Y388883D01*
X356112Y388508D01*
X356028Y388008D01*
X355862Y387717D01*
X355570Y387592D01*
X355278Y387675D01*
X355070Y387883D01*
X354945Y388175D01*
Y388467D01*
X355028Y388758D01*
X355237Y389008D01*
G01X354945Y391400D02*
X357445D01*
G01X354945Y390442D02*
Y392358D01*
G01X357445Y393667D02*
X354945D01*
Y394667D01*
X355070Y395000D01*
X355362Y395250D01*
X355695Y395333D01*
X356028Y395250D01*
X356278Y395042D01*
X356403Y394667D01*
Y393667D01*
G01X357445Y397600D02*
X357403Y397892D01*
X357278Y398225D01*
X357070Y398433D01*
X356778Y398517D01*
X356487Y398433D01*
X356237Y398183D01*
X356112Y397808D01*
Y397392D01*
X356028Y397142D01*
X355820Y396933D01*
X355528Y396850D01*
X355237Y396975D01*
X355028Y397267D01*
X354945Y397600D01*
X355028Y397933D01*
X355237Y398225D01*
X355528Y398350D01*
X355820Y398267D01*
X356028Y398058D01*
X356112Y397808D01*
Y397392D01*
X356237Y397017D01*
X356487Y396767D01*
X356778Y396683D01*
X357070Y396767D01*
X357278Y396975D01*
X357403Y397308D01*
X357445Y397600D01*
G01Y400617D02*
X356903Y400700D01*
X356445Y400825D01*
X356028Y400992D01*
X355570Y401200D01*
X354945Y401533D01*
Y399867D01*
G01X366755Y392000D02*
Y396000D01*
X359355D01*
G01X366755Y383000D02*
Y387000D01*
X359355D01*
G01X366755Y387500D02*
Y391500D01*
X359355D01*
G01X367015Y398500D02*
Y402500D01*
X359615D01*
G01X359605Y407270D02*
Y403270D01*
X367005D01*
G01X359605Y412000D02*
Y408000D01*
X367005D01*
G01X359605Y421000D02*
Y417000D01*
X367005D01*
G01X359605Y416500D02*
Y412500D01*
X367005D01*
G01X346875Y448333D02*
X347208Y448125D01*
X347583Y448000D01*
X347917D01*
X348250Y448125D01*
X348500Y448333D01*
X348625Y448625D01*
X348542Y448917D01*
X348333Y449167D01*
X347958Y449333D01*
X347458Y449417D01*
X347167Y449583D01*
X347042Y449875D01*
X347125Y450167D01*
X347333Y450375D01*
X347625Y450500D01*
X347917D01*
X348208Y450417D01*
X348458Y450208D01*
G01X351767Y450292D02*
X351517Y450417D01*
X351225Y450500D01*
X350892D01*
X350517Y450375D01*
X350225Y450167D01*
X350017Y449917D01*
X349850Y449500D01*
X349808Y449125D01*
X349892Y448750D01*
X350017Y448500D01*
X350267Y448250D01*
X350558Y448083D01*
X350850Y448000D01*
X351142D01*
X351433Y448083D01*
X351683Y448208D01*
X351892Y448375D01*
G01X353950Y448000D02*
Y450500D01*
X353450Y450000D01*
G01Y448000D02*
X354450D01*
G01X357050D02*
Y450500D01*
X356550Y450000D01*
G01Y448000D02*
X357550D01*
G01X360150Y450500D02*
X359817Y450417D01*
X359567Y450208D01*
X359400Y449958D01*
X359275Y449625D01*
X359233Y449250D01*
X359275Y448875D01*
X359400Y448542D01*
X359567Y448292D01*
X359817Y448083D01*
X360150Y448000D01*
X360483Y448083D01*
X360733Y448292D01*
X360900Y448542D01*
X361025Y448875D01*
X361067Y449250D01*
X361025Y449625D01*
X360900Y449958D01*
X360733Y450208D01*
X360483Y450417D01*
X360150Y450500D01*
G01X363167Y448000D02*
X363250Y448542D01*
X363375Y449000D01*
X363542Y449417D01*
X363750Y449875D01*
X364083Y450500D01*
X362417D01*
G01X354235Y470450D02*
Y466450D01*
X361635D01*
G01X354323Y465783D02*
Y461783D01*
X361723D01*
G01X353323Y475783D02*
Y471783D01*
X360723D01*
G01X353323Y480283D02*
Y476283D01*
X360723D01*
G01X362860Y482783D02*
X363193Y482575D01*
X363568Y482450D01*
X363902D01*
X364235Y482575D01*
X364485Y482783D01*
X364610Y483075D01*
X364527Y483367D01*
X364318Y483617D01*
X363943Y483783D01*
X363443Y483867D01*
X363152Y484033D01*
X363027Y484325D01*
X363110Y484617D01*
X363318Y484825D01*
X363610Y484950D01*
X363902D01*
X364193Y484867D01*
X364443Y484658D01*
G01X366002Y482450D02*
Y484950D01*
X367043D01*
X367377Y484825D01*
X367585Y484658D01*
X367668Y484325D01*
X367585Y483992D01*
X367335Y483783D01*
X367043Y483658D01*
X366002D01*
G01X367043D02*
X367668Y482450D01*
G01X369852D02*
X369935Y482992D01*
X370060Y483450D01*
X370227Y483867D01*
X370435Y484325D01*
X370768Y484950D01*
X369102D01*
G01X373535Y482450D02*
Y484950D01*
X371993Y483158D01*
X374077D01*
G01X375343Y484533D02*
X375593Y484783D01*
X375885Y484908D01*
X376218Y484950D01*
X376635Y484867D01*
X376927Y484658D01*
X377010Y484408D01*
X376968Y484158D01*
X376802Y483950D01*
X375968Y483533D01*
X375593Y483242D01*
X375343Y482825D01*
X375260Y482450D01*
X377010D01*
G01X362948Y478116D02*
X363281Y477908D01*
X363656Y477783D01*
X363990D01*
X364323Y477908D01*
X364573Y478116D01*
X364698Y478408D01*
X364615Y478700D01*
X364406Y478950D01*
X364031Y479116D01*
X363531Y479200D01*
X363240Y479366D01*
X363115Y479658D01*
X363198Y479950D01*
X363406Y480158D01*
X363698Y480283D01*
X363990D01*
X364281Y480200D01*
X364531Y479991D01*
G01X366090Y477783D02*
Y480283D01*
X367131D01*
X367465Y480158D01*
X367673Y479991D01*
X367756Y479658D01*
X367673Y479325D01*
X367423Y479116D01*
X367131Y478991D01*
X366090D01*
G01X367131D02*
X367756Y477783D01*
G01X369940D02*
X370023Y478325D01*
X370148Y478783D01*
X370315Y479200D01*
X370523Y479658D01*
X370856Y480283D01*
X369190D01*
G01X373623Y477783D02*
Y480283D01*
X372081Y478491D01*
X374165D01*
G01X375306Y478283D02*
X375556Y477991D01*
X375890Y477825D01*
X376265Y477783D01*
X376598Y477825D01*
X376931Y478033D01*
X377140Y478283D01*
X377181Y478533D01*
X377098Y478825D01*
X376806Y479033D01*
X376515Y479116D01*
X376140D01*
G01X376515D02*
X376765Y479241D01*
X376973Y479450D01*
X377056Y479700D01*
X376973Y479950D01*
X376765Y480158D01*
X376390Y480283D01*
X376015Y480241D01*
X375640Y480075D01*
G01X353323Y484783D02*
Y480783D01*
X360723D01*
G01X362948Y488116D02*
X363281Y487908D01*
X363656Y487783D01*
X363990D01*
X364323Y487908D01*
X364573Y488116D01*
X364698Y488408D01*
X364615Y488700D01*
X364406Y488950D01*
X364031Y489116D01*
X363531Y489200D01*
X363240Y489366D01*
X363115Y489658D01*
X363198Y489950D01*
X363406Y490158D01*
X363698Y490283D01*
X363990D01*
X364281Y490200D01*
X364531Y489991D01*
G01X366090Y487783D02*
Y490283D01*
X367131D01*
X367465Y490158D01*
X367673Y489991D01*
X367756Y489658D01*
X367673Y489325D01*
X367423Y489116D01*
X367131Y488991D01*
X366090D01*
G01X367131D02*
X367756Y487783D01*
G01X369940D02*
X370023Y488325D01*
X370148Y488783D01*
X370315Y489200D01*
X370523Y489658D01*
X370856Y490283D01*
X369190D01*
G01X372206Y488158D02*
X372456Y487950D01*
X372748Y487825D01*
X373123Y487783D01*
X373498Y487866D01*
X373790Y488033D01*
X373998Y488325D01*
X374040Y488658D01*
X373956Y488991D01*
X373748Y489200D01*
X373456Y489366D01*
X373165Y489408D01*
X372873Y489366D01*
X372498Y489200D01*
X372623Y490283D01*
X373748D01*
G01X375431Y489866D02*
X375681Y490116D01*
X375973Y490241D01*
X376306Y490283D01*
X376723Y490200D01*
X377015Y489991D01*
X377098Y489741D01*
X377056Y489491D01*
X376890Y489283D01*
X376056Y488866D01*
X375681Y488575D01*
X375431Y488158D01*
X375348Y487783D01*
X377098D01*
G01X362948Y492616D02*
X363281Y492408D01*
X363656Y492283D01*
X363990D01*
X364323Y492408D01*
X364573Y492616D01*
X364698Y492908D01*
X364615Y493200D01*
X364406Y493450D01*
X364031Y493616D01*
X363531Y493700D01*
X363240Y493866D01*
X363115Y494158D01*
X363198Y494450D01*
X363406Y494658D01*
X363698Y494783D01*
X363990D01*
X364281Y494700D01*
X364531Y494491D01*
G01X366090Y492283D02*
Y494783D01*
X367131D01*
X367465Y494658D01*
X367673Y494491D01*
X367756Y494158D01*
X367673Y493825D01*
X367423Y493616D01*
X367131Y493491D01*
X366090D01*
G01X367131D02*
X367756Y492283D01*
G01X369940D02*
X370023Y492825D01*
X370148Y493283D01*
X370315Y493700D01*
X370523Y494158D01*
X370856Y494783D01*
X369190D01*
G01X372206Y492658D02*
X372456Y492450D01*
X372748Y492325D01*
X373123Y492283D01*
X373498Y492366D01*
X373790Y492533D01*
X373998Y492825D01*
X374040Y493158D01*
X373956Y493491D01*
X373748Y493700D01*
X373456Y493866D01*
X373165Y493908D01*
X372873Y493866D01*
X372498Y493700D01*
X372623Y494783D01*
X373748D01*
G01X375306Y492783D02*
X375556Y492491D01*
X375890Y492325D01*
X376265Y492283D01*
X376598Y492325D01*
X376931Y492533D01*
X377140Y492783D01*
X377181Y493033D01*
X377098Y493325D01*
X376806Y493533D01*
X376515Y493616D01*
X376140D01*
G01X376515D02*
X376765Y493741D01*
X376973Y493950D01*
X377056Y494200D01*
X376973Y494450D01*
X376765Y494658D01*
X376390Y494783D01*
X376015Y494741D01*
X375640Y494575D01*
G01X362948Y497116D02*
X363281Y496908D01*
X363656Y496783D01*
X363990D01*
X364323Y496908D01*
X364573Y497116D01*
X364698Y497408D01*
X364615Y497700D01*
X364406Y497950D01*
X364031Y498116D01*
X363531Y498200D01*
X363240Y498366D01*
X363115Y498658D01*
X363198Y498950D01*
X363406Y499158D01*
X363698Y499283D01*
X363990D01*
X364281Y499200D01*
X364531Y498991D01*
G01X366090Y496783D02*
Y499283D01*
X367131D01*
X367465Y499158D01*
X367673Y498991D01*
X367756Y498658D01*
X367673Y498325D01*
X367423Y498116D01*
X367131Y497991D01*
X366090D01*
G01X367131D02*
X367756Y496783D01*
G01X369940D02*
X370023Y497325D01*
X370148Y497783D01*
X370315Y498200D01*
X370523Y498658D01*
X370856Y499283D01*
X369190D01*
G01X372206Y497158D02*
X372456Y496950D01*
X372748Y496825D01*
X373123Y496783D01*
X373498Y496866D01*
X373790Y497033D01*
X373998Y497325D01*
X374040Y497658D01*
X373956Y497991D01*
X373748Y498200D01*
X373456Y498366D01*
X373165Y498408D01*
X372873Y498366D01*
X372498Y498200D01*
X372623Y499283D01*
X373748D01*
G01X376223Y496783D02*
Y499283D01*
X375723Y498783D01*
G01Y496783D02*
X376723D01*
G01X361398Y501116D02*
X361731Y500908D01*
X362106Y500783D01*
X362440D01*
X362773Y500908D01*
X363023Y501116D01*
X363148Y501408D01*
X363065Y501700D01*
X362856Y501950D01*
X362481Y502116D01*
X361981Y502200D01*
X361690Y502366D01*
X361565Y502658D01*
X361648Y502950D01*
X361856Y503158D01*
X362148Y503283D01*
X362440D01*
X362731Y503200D01*
X362981Y502991D01*
G01X366290Y503075D02*
X366040Y503200D01*
X365748Y503283D01*
X365415D01*
X365040Y503158D01*
X364748Y502950D01*
X364540Y502700D01*
X364373Y502283D01*
X364331Y501908D01*
X364415Y501533D01*
X364540Y501283D01*
X364790Y501033D01*
X365081Y500866D01*
X365373Y500783D01*
X365665D01*
X365956Y500866D01*
X366206Y500991D01*
X366415Y501158D01*
G01X368473Y500783D02*
Y503283D01*
X367973Y502783D01*
G01Y500783D02*
X368973D01*
G01X370781Y502866D02*
X371031Y503116D01*
X371323Y503241D01*
X371656Y503283D01*
X372073Y503200D01*
X372365Y502991D01*
X372448Y502741D01*
X372406Y502491D01*
X372240Y502283D01*
X371406Y501866D01*
X371031Y501575D01*
X370781Y501158D01*
X370698Y500783D01*
X372448D01*
G01X374673D02*
X374965Y500825D01*
X375298Y500950D01*
X375506Y501158D01*
X375590Y501450D01*
X375506Y501741D01*
X375256Y501991D01*
X374881Y502116D01*
X374465D01*
X374215Y502200D01*
X374006Y502408D01*
X373923Y502700D01*
X374048Y502991D01*
X374340Y503200D01*
X374673Y503283D01*
X375006Y503200D01*
X375298Y502991D01*
X375423Y502700D01*
X375340Y502408D01*
X375131Y502200D01*
X374881Y502116D01*
X374465D01*
X374090Y501991D01*
X373840Y501741D01*
X373756Y501450D01*
X373840Y501158D01*
X374048Y500950D01*
X374381Y500825D01*
X374673Y500783D01*
G01X376981Y502866D02*
X377231Y503116D01*
X377523Y503241D01*
X377856Y503283D01*
X378273Y503200D01*
X378565Y502991D01*
X378648Y502741D01*
X378606Y502491D01*
X378440Y502283D01*
X377606Y501866D01*
X377231Y501575D01*
X376981Y501158D01*
X376898Y500783D01*
X378648D01*
G01X350930Y506833D02*
X351263Y506625D01*
X351638Y506500D01*
X351972D01*
X352305Y506625D01*
X352555Y506833D01*
X352680Y507125D01*
X352597Y507417D01*
X352388Y507667D01*
X352013Y507833D01*
X351513Y507917D01*
X351222Y508083D01*
X351097Y508375D01*
X351180Y508667D01*
X351388Y508875D01*
X351680Y509000D01*
X351972D01*
X352263Y508917D01*
X352513Y508708D01*
G01X355822Y508792D02*
X355572Y508917D01*
X355280Y509000D01*
X354947D01*
X354572Y508875D01*
X354280Y508667D01*
X354072Y508417D01*
X353905Y508000D01*
X353863Y507625D01*
X353947Y507250D01*
X354072Y507000D01*
X354322Y506750D01*
X354613Y506583D01*
X354905Y506500D01*
X355197D01*
X355488Y506583D01*
X355738Y506708D01*
X355947Y506875D01*
G01X358005Y506500D02*
Y509000D01*
X357505Y508500D01*
G01Y506500D02*
X358505D01*
G01X361105D02*
Y509000D01*
X360605Y508500D01*
G01Y506500D02*
X361605D01*
G01X364205D02*
Y509000D01*
X363705Y508500D01*
G01Y506500D02*
X364705D01*
G01X367222D02*
X367305Y507042D01*
X367430Y507500D01*
X367597Y507917D01*
X367805Y508375D01*
X368138Y509000D01*
X366472D01*
G01X353055Y547300D02*
X357055D01*
Y554700D01*
G01X356055Y558017D02*
X353555D01*
Y559058D01*
X353680Y559392D01*
X353847Y559600D01*
X354180Y559683D01*
X354513Y559600D01*
X354722Y559350D01*
X354847Y559058D01*
Y558017D01*
G01Y559058D02*
X356055Y559683D01*
G01Y561950D02*
X353555D01*
X354055Y561450D01*
G01X356055D02*
Y562450D01*
G01X355680Y564133D02*
X355888Y564383D01*
X356013Y564675D01*
X356055Y565050D01*
X355972Y565425D01*
X355805Y565717D01*
X355513Y565925D01*
X355180Y565967D01*
X354847Y565883D01*
X354638Y565675D01*
X354472Y565383D01*
X354430Y565092D01*
X354472Y564800D01*
X354638Y564425D01*
X353555Y564550D01*
Y565675D01*
G01X356055Y568067D02*
X355513Y568150D01*
X355055Y568275D01*
X354638Y568442D01*
X354180Y568650D01*
X353555Y568983D01*
Y567317D01*
G01X356700Y876500D02*
Y880500D01*
X349300D01*
G01X356700Y882500D02*
Y886500D01*
X349300D01*
G01X356700Y891000D02*
Y895000D01*
X349300D01*
G01X356700Y887000D02*
Y891000D01*
X349300D01*
G01X353500Y908800D02*
X357500D01*
Y916200D01*
G01X349000Y908800D02*
X353000D01*
Y916200D01*
G01X357500Y908800D02*
X361500D01*
Y916200D01*
G01X352667Y959425D02*
X352875Y959758D01*
X353000Y960133D01*
Y960467D01*
X352875Y960800D01*
X352667Y961050D01*
X352375Y961175D01*
X352083Y961092D01*
X351833Y960883D01*
X351667Y960508D01*
X351583Y960008D01*
X351417Y959717D01*
X351125Y959592D01*
X350833Y959675D01*
X350625Y959883D01*
X350500Y960175D01*
Y960467D01*
X350583Y960758D01*
X350792Y961008D01*
G01X353000Y962567D02*
X350500D01*
Y963608D01*
X350625Y963942D01*
X350792Y964150D01*
X351125Y964233D01*
X351458Y964150D01*
X351667Y963900D01*
X351792Y963608D01*
Y962567D01*
G01Y963608D02*
X353000Y964233D01*
G01X352708Y965792D02*
X352917Y966083D01*
X353000Y966417D01*
X352917Y966750D01*
X352667Y967042D01*
X352292Y967250D01*
X351917Y967333D01*
X351458D01*
X351083Y967250D01*
X350750Y967042D01*
X350583Y966792D01*
X350500Y966500D01*
X350583Y966167D01*
X350750Y965917D01*
X351000Y965750D01*
X351333Y965667D01*
X351625Y965750D01*
X351917Y965958D01*
X352083Y966208D01*
X352125Y966500D01*
X352042Y966833D01*
X351833Y967083D01*
X351458Y967333D01*
G01X352625Y968683D02*
X352833Y968933D01*
X352958Y969225D01*
X353000Y969600D01*
X352917Y969975D01*
X352750Y970267D01*
X352458Y970475D01*
X352125Y970517D01*
X351792Y970433D01*
X351583Y970225D01*
X351417Y969933D01*
X351375Y969642D01*
X351417Y969350D01*
X351583Y968975D01*
X350500Y969100D01*
Y970225D01*
G01X353000Y973200D02*
X350500D01*
X352292Y971658D01*
Y973742D01*
G01X349500Y950800D02*
X353500D01*
Y958200D01*
G01X357167Y959425D02*
X357375Y959758D01*
X357500Y960133D01*
Y960467D01*
X357375Y960800D01*
X357167Y961050D01*
X356875Y961175D01*
X356583Y961092D01*
X356333Y960883D01*
X356167Y960508D01*
X356083Y960008D01*
X355917Y959717D01*
X355625Y959592D01*
X355333Y959675D01*
X355125Y959883D01*
X355000Y960175D01*
Y960467D01*
X355083Y960758D01*
X355292Y961008D01*
G01X357500Y962567D02*
X355000D01*
Y963608D01*
X355125Y963942D01*
X355292Y964150D01*
X355625Y964233D01*
X355958Y964150D01*
X356167Y963900D01*
X356292Y963608D01*
Y962567D01*
G01Y963608D02*
X357500Y964233D01*
G01X357208Y965792D02*
X357417Y966083D01*
X357500Y966417D01*
X357417Y966750D01*
X357167Y967042D01*
X356792Y967250D01*
X356417Y967333D01*
X355958D01*
X355583Y967250D01*
X355250Y967042D01*
X355083Y966792D01*
X355000Y966500D01*
X355083Y966167D01*
X355250Y965917D01*
X355500Y965750D01*
X355833Y965667D01*
X356125Y965750D01*
X356417Y965958D01*
X356583Y966208D01*
X356625Y966500D01*
X356542Y966833D01*
X356333Y967083D01*
X355958Y967333D01*
G01X357125Y968683D02*
X357333Y968933D01*
X357458Y969225D01*
X357500Y969600D01*
X357417Y969975D01*
X357250Y970267D01*
X356958Y970475D01*
X356625Y970517D01*
X356292Y970433D01*
X356083Y970225D01*
X355917Y969933D01*
X355875Y969642D01*
X355917Y969350D01*
X356083Y968975D01*
X355000Y969100D01*
Y970225D01*
G01X357125Y971783D02*
X357333Y972033D01*
X357458Y972325D01*
X357500Y972700D01*
X357417Y973075D01*
X357250Y973367D01*
X356958Y973575D01*
X356625Y973617D01*
X356292Y973533D01*
X356083Y973325D01*
X355917Y973033D01*
X355875Y972742D01*
X355917Y972450D01*
X356083Y972075D01*
X355000Y972200D01*
Y973325D01*
G01X354000Y950800D02*
X358000D01*
Y958200D01*
G01X361667Y959425D02*
X361875Y959758D01*
X362000Y960133D01*
Y960467D01*
X361875Y960800D01*
X361667Y961050D01*
X361375Y961175D01*
X361083Y961092D01*
X360833Y960883D01*
X360667Y960508D01*
X360583Y960008D01*
X360417Y959717D01*
X360125Y959592D01*
X359833Y959675D01*
X359625Y959883D01*
X359500Y960175D01*
Y960467D01*
X359583Y960758D01*
X359792Y961008D01*
G01X362000Y962567D02*
X359500D01*
Y963608D01*
X359625Y963942D01*
X359792Y964150D01*
X360125Y964233D01*
X360458Y964150D01*
X360667Y963900D01*
X360792Y963608D01*
Y962567D01*
G01Y963608D02*
X362000Y964233D01*
G01X361708Y965792D02*
X361917Y966083D01*
X362000Y966417D01*
X361917Y966750D01*
X361667Y967042D01*
X361292Y967250D01*
X360917Y967333D01*
X360458D01*
X360083Y967250D01*
X359750Y967042D01*
X359583Y966792D01*
X359500Y966500D01*
X359583Y966167D01*
X359750Y965917D01*
X360000Y965750D01*
X360333Y965667D01*
X360625Y965750D01*
X360917Y965958D01*
X361083Y966208D01*
X361125Y966500D01*
X361042Y966833D01*
X360833Y967083D01*
X360458Y967333D01*
G01X361625Y968683D02*
X361833Y968933D01*
X361958Y969225D01*
X362000Y969600D01*
X361917Y969975D01*
X361750Y970267D01*
X361458Y970475D01*
X361125Y970517D01*
X360792Y970433D01*
X360583Y970225D01*
X360417Y969933D01*
X360375Y969642D01*
X360417Y969350D01*
X360583Y968975D01*
X359500Y969100D01*
Y970225D01*
G01X360958Y971908D02*
X360667Y972200D01*
X360500Y972450D01*
X360417Y972783D01*
X360500Y973075D01*
X360667Y973283D01*
X360917Y973450D01*
X361208Y973492D01*
X361458Y973450D01*
X361708Y973283D01*
X361917Y973033D01*
X362000Y972742D01*
X361917Y972408D01*
X361667Y972117D01*
X361292Y971950D01*
X360875Y971908D01*
X360333Y971992D01*
X360042Y972117D01*
X359750Y972325D01*
X359542Y972617D01*
X359500Y972908D01*
X359583Y973200D01*
X359792Y973408D01*
G01X358500Y950800D02*
X362500D01*
Y958200D01*
G01X357178Y978017D02*
X354678D01*
Y979058D01*
X354803Y979392D01*
X354970Y979600D01*
X355303Y979683D01*
X355636Y979600D01*
X355845Y979350D01*
X355970Y979058D01*
Y978017D01*
G01Y979058D02*
X357178Y979683D01*
G01Y981950D02*
X354678D01*
X355178Y981450D01*
G01X357178D02*
Y982450D01*
G01X356803Y984133D02*
X357011Y984383D01*
X357136Y984675D01*
X357178Y985050D01*
X357095Y985425D01*
X356928Y985717D01*
X356636Y985925D01*
X356303Y985967D01*
X355970Y985883D01*
X355761Y985675D01*
X355595Y985383D01*
X355553Y985092D01*
X355595Y984800D01*
X355761Y984425D01*
X354678Y984550D01*
Y985675D01*
G01Y988150D02*
X354761Y987817D01*
X354970Y987567D01*
X355220Y987400D01*
X355553Y987275D01*
X355928Y987233D01*
X356303Y987275D01*
X356636Y987400D01*
X356886Y987567D01*
X357095Y987817D01*
X357178Y988150D01*
X357095Y988483D01*
X356886Y988733D01*
X356636Y988900D01*
X356303Y989025D01*
X355928Y989067D01*
X355553Y989025D01*
X355220Y988900D01*
X354970Y988733D01*
X354761Y988483D01*
X354678Y988150D01*
G01X363178Y987700D02*
X359178D01*
Y980300D01*
G01X370629Y4692D02*
X374904D01*
G01X370629Y11292D02*
Y4692D01*
G01X374904D02*
G03X385254I5175J1348D01*
G01X369000Y11200D02*
Y5700D01*
G01X370000Y23500D02*
X383500D01*
Y13000D01*
X382500D01*
G01X389529Y11292D02*
X370629D01*
G01X369000Y23300D02*
Y17800D01*
G01X373000Y30700D02*
Y36200D01*
G01X381000Y30700D02*
X373000D01*
G01X363000Y36200D02*
Y30700D01*
G01X364000D02*
Y36200D01*
G01X372000Y30700D02*
X364000D01*
G01X372000Y36200D02*
Y30700D01*
G01X373000Y48300D02*
X381000D01*
G01X373000Y42800D02*
Y48300D01*
G01X363000D02*
Y42800D01*
G01X372000Y48300D02*
Y42800D01*
G01X364000Y48300D02*
X372000D01*
G01X364000Y42800D02*
Y48300D01*
G01X373500Y49300D02*
X379700D01*
Y61700D01*
X373500D01*
G01X365500Y72967D02*
X363000D01*
Y73967D01*
X363125Y74300D01*
X363417Y74550D01*
X363750Y74633D01*
X364083Y74550D01*
X364333Y74342D01*
X364458Y73967D01*
Y72967D01*
G01X363208Y77817D02*
X363083Y77567D01*
X363000Y77275D01*
Y76942D01*
X363125Y76567D01*
X363333Y76275D01*
X363583Y76067D01*
X364000Y75900D01*
X364375Y75858D01*
X364750Y75942D01*
X365000Y76067D01*
X365250Y76317D01*
X365417Y76608D01*
X365500Y76900D01*
Y77192D01*
X365417Y77483D01*
X365292Y77733D01*
X365125Y77942D01*
G01X365500Y80000D02*
X363000D01*
X363500Y79500D01*
G01X365500D02*
Y80500D01*
G01X365208Y82392D02*
X365417Y82683D01*
X365500Y83017D01*
X365417Y83350D01*
X365167Y83642D01*
X364792Y83850D01*
X364417Y83933D01*
X363958D01*
X363583Y83850D01*
X363250Y83642D01*
X363083Y83392D01*
X363000Y83100D01*
X363083Y82767D01*
X363250Y82517D01*
X363500Y82350D01*
X363833Y82267D01*
X364125Y82350D01*
X364417Y82558D01*
X364583Y82808D01*
X364625Y83100D01*
X364542Y83433D01*
X364333Y83683D01*
X363958Y83933D01*
G01X365000Y85283D02*
X365292Y85533D01*
X365458Y85867D01*
X365500Y86242D01*
X365458Y86575D01*
X365250Y86908D01*
X365000Y87117D01*
X364750Y87158D01*
X364458Y87075D01*
X364250Y86783D01*
X364167Y86492D01*
Y86117D01*
G01Y86492D02*
X364042Y86742D01*
X363833Y86950D01*
X363583Y87033D01*
X363333Y86950D01*
X363125Y86742D01*
X363000Y86367D01*
X363042Y85992D01*
X363208Y85617D01*
G01X367967Y82500D02*
Y85000D01*
X368967D01*
X369300Y84875D01*
X369550Y84583D01*
X369633Y84250D01*
X369550Y83917D01*
X369342Y83667D01*
X368967Y83542D01*
X367967D01*
G01X372817Y84792D02*
X372567Y84917D01*
X372275Y85000D01*
X371942D01*
X371567Y84875D01*
X371275Y84667D01*
X371067Y84417D01*
X370900Y84000D01*
X370858Y83625D01*
X370942Y83250D01*
X371067Y83000D01*
X371317Y82750D01*
X371608Y82583D01*
X371900Y82500D01*
X372192D01*
X372483Y82583D01*
X372733Y82708D01*
X372942Y82875D01*
G01X374208Y84583D02*
X374458Y84833D01*
X374750Y84958D01*
X375083Y85000D01*
X375500Y84917D01*
X375792Y84708D01*
X375875Y84458D01*
X375833Y84208D01*
X375667Y84000D01*
X374833Y83583D01*
X374458Y83292D01*
X374208Y82875D01*
X374125Y82500D01*
X375875D01*
G01X378100D02*
Y85000D01*
X377600Y84500D01*
G01Y82500D02*
X378600D01*
G01X381700D02*
Y85000D01*
X380158Y83208D01*
X382242D01*
G01X367967Y78000D02*
Y80500D01*
X368967D01*
X369300Y80375D01*
X369550Y80083D01*
X369633Y79750D01*
X369550Y79417D01*
X369342Y79167D01*
X368967Y79042D01*
X367967D01*
G01X372817Y80292D02*
X372567Y80417D01*
X372275Y80500D01*
X371942D01*
X371567Y80375D01*
X371275Y80167D01*
X371067Y79917D01*
X370900Y79500D01*
X370858Y79125D01*
X370942Y78750D01*
X371067Y78500D01*
X371317Y78250D01*
X371608Y78083D01*
X371900Y78000D01*
X372192D01*
X372483Y78083D01*
X372733Y78208D01*
X372942Y78375D01*
G01X374208Y80083D02*
X374458Y80333D01*
X374750Y80458D01*
X375083Y80500D01*
X375500Y80417D01*
X375792Y80208D01*
X375875Y79958D01*
X375833Y79708D01*
X375667Y79500D01*
X374833Y79083D01*
X374458Y78792D01*
X374208Y78375D01*
X374125Y78000D01*
X375875D01*
G01X378100D02*
Y80500D01*
X377600Y80000D01*
G01Y78000D02*
X378600D01*
G01X381200D02*
X381492Y78042D01*
X381825Y78167D01*
X382033Y78375D01*
X382117Y78667D01*
X382033Y78958D01*
X381783Y79208D01*
X381408Y79333D01*
X380992D01*
X380742Y79417D01*
X380533Y79625D01*
X380450Y79917D01*
X380575Y80208D01*
X380867Y80417D01*
X381200Y80500D01*
X381533Y80417D01*
X381825Y80208D01*
X381950Y79917D01*
X381867Y79625D01*
X381658Y79417D01*
X381408Y79333D01*
X380992D01*
X380617Y79208D01*
X380367Y78958D01*
X380283Y78667D01*
X380367Y78375D01*
X380575Y78167D01*
X380908Y78042D01*
X381200Y78000D01*
G01X366667Y105925D02*
X366875Y106258D01*
X367000Y106633D01*
Y106967D01*
X366875Y107300D01*
X366667Y107550D01*
X366375Y107675D01*
X366083Y107592D01*
X365833Y107383D01*
X365667Y107008D01*
X365583Y106508D01*
X365417Y106217D01*
X365125Y106092D01*
X364833Y106175D01*
X364625Y106383D01*
X364500Y106675D01*
Y106967D01*
X364583Y107258D01*
X364792Y107508D01*
G01X367000Y109067D02*
X364500D01*
Y110108D01*
X364625Y110442D01*
X364792Y110650D01*
X365125Y110733D01*
X365458Y110650D01*
X365667Y110400D01*
X365792Y110108D01*
Y109067D01*
G01Y110108D02*
X367000Y110733D01*
G01X366625Y112083D02*
X366833Y112333D01*
X366958Y112625D01*
X367000Y113000D01*
X366917Y113375D01*
X366750Y113667D01*
X366458Y113875D01*
X366125Y113917D01*
X365792Y113833D01*
X365583Y113625D01*
X365417Y113333D01*
X365375Y113042D01*
X365417Y112750D01*
X365583Y112375D01*
X364500Y112500D01*
Y113625D01*
G01X367000Y116100D02*
X366958Y116392D01*
X366833Y116725D01*
X366625Y116933D01*
X366333Y117017D01*
X366042Y116933D01*
X365792Y116683D01*
X365667Y116308D01*
Y115892D01*
X365583Y115642D01*
X365375Y115433D01*
X365083Y115350D01*
X364792Y115475D01*
X364583Y115767D01*
X364500Y116100D01*
X364583Y116433D01*
X364792Y116725D01*
X365083Y116850D01*
X365375Y116767D01*
X365583Y116558D01*
X365667Y116308D01*
Y115892D01*
X365792Y115517D01*
X366042Y115267D01*
X366333Y115183D01*
X366625Y115267D01*
X366833Y115475D01*
X366958Y115808D01*
X367000Y116100D01*
G01Y119200D02*
X366958Y119492D01*
X366833Y119825D01*
X366625Y120033D01*
X366333Y120117D01*
X366042Y120033D01*
X365792Y119783D01*
X365667Y119408D01*
Y118992D01*
X365583Y118742D01*
X365375Y118533D01*
X365083Y118450D01*
X364792Y118575D01*
X364583Y118867D01*
X364500Y119200D01*
X364583Y119533D01*
X364792Y119825D01*
X365083Y119950D01*
X365375Y119867D01*
X365583Y119658D01*
X365667Y119408D01*
Y118992D01*
X365792Y118617D01*
X366042Y118367D01*
X366333Y118283D01*
X366625Y118367D01*
X366833Y118575D01*
X366958Y118908D01*
X367000Y119200D01*
G01X365467Y96000D02*
Y98500D01*
X366467D01*
X366800Y98375D01*
X367050Y98083D01*
X367133Y97750D01*
X367050Y97417D01*
X366842Y97167D01*
X366467Y97042D01*
X365467D01*
G01X368567Y96000D02*
Y98500D01*
X369608D01*
X369942Y98375D01*
X370150Y98208D01*
X370233Y97875D01*
X370150Y97542D01*
X369900Y97333D01*
X369608Y97208D01*
X368567D01*
G01X369608D02*
X370233Y96000D01*
G01X372500D02*
Y98500D01*
X372000Y98000D01*
G01Y96000D02*
X373000D01*
G01X374892Y96292D02*
X375183Y96083D01*
X375517Y96000D01*
X375850Y96083D01*
X376142Y96333D01*
X376350Y96708D01*
X376433Y97083D01*
Y97542D01*
X376350Y97917D01*
X376142Y98250D01*
X375892Y98417D01*
X375600Y98500D01*
X375267Y98417D01*
X375017Y98250D01*
X374850Y98000D01*
X374767Y97667D01*
X374850Y97375D01*
X375058Y97083D01*
X375308Y96917D01*
X375600Y96875D01*
X375933Y96958D01*
X376183Y97167D01*
X376433Y97542D01*
G01X378700Y98500D02*
X378367Y98417D01*
X378117Y98208D01*
X377950Y97958D01*
X377825Y97625D01*
X377783Y97250D01*
X377825Y96875D01*
X377950Y96542D01*
X378117Y96292D01*
X378367Y96083D01*
X378700Y96000D01*
X379033Y96083D01*
X379283Y96292D01*
X379450Y96542D01*
X379575Y96875D01*
X379617Y97250D01*
X379575Y97625D01*
X379450Y97958D01*
X379283Y98208D01*
X379033Y98417D01*
X378700Y98500D01*
G01X365467Y100500D02*
Y103000D01*
X366467D01*
X366800Y102875D01*
X367050Y102583D01*
X367133Y102250D01*
X367050Y101917D01*
X366842Y101667D01*
X366467Y101542D01*
X365467D01*
G01X368567Y100500D02*
Y103000D01*
X369608D01*
X369942Y102875D01*
X370150Y102708D01*
X370233Y102375D01*
X370150Y102042D01*
X369900Y101833D01*
X369608Y101708D01*
X368567D01*
G01X369608D02*
X370233Y100500D01*
G01X372500D02*
Y103000D01*
X372000Y102500D01*
G01Y100500D02*
X373000D01*
G01X374892Y100792D02*
X375183Y100583D01*
X375517Y100500D01*
X375850Y100583D01*
X376142Y100833D01*
X376350Y101208D01*
X376433Y101583D01*
Y102042D01*
X376350Y102417D01*
X376142Y102750D01*
X375892Y102917D01*
X375600Y103000D01*
X375267Y102917D01*
X375017Y102750D01*
X374850Y102500D01*
X374767Y102167D01*
X374850Y101875D01*
X375058Y101583D01*
X375308Y101417D01*
X375600Y101375D01*
X375933Y101458D01*
X376183Y101667D01*
X376433Y102042D01*
G01X379200Y100500D02*
Y103000D01*
X377658Y101208D01*
X379742D01*
G01X442048Y127952D02*
X363858D01*
G01X442048Y226378D02*
X363858D01*
G01X365596Y253425D02*
X365804Y253758D01*
X365929Y254133D01*
Y254467D01*
X365804Y254800D01*
X365596Y255050D01*
X365304Y255175D01*
X365012Y255092D01*
X364762Y254883D01*
X364596Y254508D01*
X364512Y254008D01*
X364346Y253717D01*
X364054Y253592D01*
X363762Y253675D01*
X363554Y253883D01*
X363429Y254175D01*
Y254467D01*
X363512Y254758D01*
X363721Y255008D01*
G01X365929Y256567D02*
X363429D01*
Y257608D01*
X363554Y257942D01*
X363721Y258150D01*
X364054Y258233D01*
X364387Y258150D01*
X364596Y257900D01*
X364721Y257608D01*
Y256567D01*
G01Y257608D02*
X365929Y258233D01*
G01X364887Y259708D02*
X364596Y260000D01*
X364429Y260250D01*
X364346Y260583D01*
X364429Y260875D01*
X364596Y261083D01*
X364846Y261250D01*
X365137Y261292D01*
X365387Y261250D01*
X365637Y261083D01*
X365846Y260833D01*
X365929Y260542D01*
X365846Y260208D01*
X365596Y259917D01*
X365221Y259750D01*
X364804Y259708D01*
X364262Y259792D01*
X363971Y259917D01*
X363679Y260125D01*
X363471Y260417D01*
X363429Y260708D01*
X363512Y261000D01*
X363721Y261208D01*
G01X365929Y263517D02*
X365387Y263600D01*
X364929Y263725D01*
X364512Y263892D01*
X364054Y264100D01*
X363429Y264433D01*
Y262767D01*
G01X365554Y265783D02*
X365762Y266033D01*
X365887Y266325D01*
X365929Y266700D01*
X365846Y267075D01*
X365679Y267367D01*
X365387Y267575D01*
X365054Y267617D01*
X364721Y267533D01*
X364512Y267325D01*
X364346Y267033D01*
X364304Y266742D01*
X364346Y266450D01*
X364512Y266075D01*
X363429Y266200D01*
Y267325D01*
G01X368429Y252200D02*
X364429D01*
Y244800D01*
G01X374596Y253425D02*
X374804Y253758D01*
X374929Y254133D01*
Y254467D01*
X374804Y254800D01*
X374596Y255050D01*
X374304Y255175D01*
X374012Y255092D01*
X373762Y254883D01*
X373596Y254508D01*
X373512Y254008D01*
X373346Y253717D01*
X373054Y253592D01*
X372762Y253675D01*
X372554Y253883D01*
X372429Y254175D01*
Y254467D01*
X372512Y254758D01*
X372721Y255008D01*
G01X374929Y256567D02*
X372429D01*
Y257608D01*
X372554Y257942D01*
X372721Y258150D01*
X373054Y258233D01*
X373387Y258150D01*
X373596Y257900D01*
X373721Y257608D01*
Y256567D01*
G01Y257608D02*
X374929Y258233D01*
G01X373887Y259708D02*
X373596Y260000D01*
X373429Y260250D01*
X373346Y260583D01*
X373429Y260875D01*
X373596Y261083D01*
X373846Y261250D01*
X374137Y261292D01*
X374387Y261250D01*
X374637Y261083D01*
X374846Y260833D01*
X374929Y260542D01*
X374846Y260208D01*
X374596Y259917D01*
X374221Y259750D01*
X373804Y259708D01*
X373262Y259792D01*
X372971Y259917D01*
X372679Y260125D01*
X372471Y260417D01*
X372429Y260708D01*
X372512Y261000D01*
X372721Y261208D01*
G01X374929Y263517D02*
X374387Y263600D01*
X373929Y263725D01*
X373512Y263892D01*
X373054Y264100D01*
X372429Y264433D01*
Y262767D01*
G01X373887Y265908D02*
X373596Y266200D01*
X373429Y266450D01*
X373346Y266783D01*
X373429Y267075D01*
X373596Y267283D01*
X373846Y267450D01*
X374137Y267492D01*
X374387Y267450D01*
X374637Y267283D01*
X374846Y267033D01*
X374929Y266742D01*
X374846Y266408D01*
X374596Y266117D01*
X374221Y265950D01*
X373804Y265908D01*
X373262Y265992D01*
X372971Y266117D01*
X372679Y266325D01*
X372471Y266617D01*
X372429Y266908D01*
X372512Y267200D01*
X372721Y267408D01*
G01X377429Y252200D02*
X373429D01*
Y244800D01*
G01X370096Y253425D02*
X370304Y253758D01*
X370429Y254133D01*
Y254467D01*
X370304Y254800D01*
X370096Y255050D01*
X369804Y255175D01*
X369512Y255092D01*
X369262Y254883D01*
X369096Y254508D01*
X369012Y254008D01*
X368846Y253717D01*
X368554Y253592D01*
X368262Y253675D01*
X368054Y253883D01*
X367929Y254175D01*
Y254467D01*
X368012Y254758D01*
X368221Y255008D01*
G01X370429Y256567D02*
X367929D01*
Y257608D01*
X368054Y257942D01*
X368221Y258150D01*
X368554Y258233D01*
X368887Y258150D01*
X369096Y257900D01*
X369221Y257608D01*
Y256567D01*
G01Y257608D02*
X370429Y258233D01*
G01X369387Y259708D02*
X369096Y260000D01*
X368929Y260250D01*
X368846Y260583D01*
X368929Y260875D01*
X369096Y261083D01*
X369346Y261250D01*
X369637Y261292D01*
X369887Y261250D01*
X370137Y261083D01*
X370346Y260833D01*
X370429Y260542D01*
X370346Y260208D01*
X370096Y259917D01*
X369721Y259750D01*
X369304Y259708D01*
X368762Y259792D01*
X368471Y259917D01*
X368179Y260125D01*
X367971Y260417D01*
X367929Y260708D01*
X368012Y261000D01*
X368221Y261208D01*
G01X370429Y263517D02*
X369887Y263600D01*
X369429Y263725D01*
X369012Y263892D01*
X368554Y264100D01*
X367929Y264433D01*
Y262767D01*
G01X370429Y266617D02*
X369887Y266700D01*
X369429Y266825D01*
X369012Y266992D01*
X368554Y267200D01*
X367929Y267533D01*
Y265867D01*
G01X372929Y252200D02*
X368929D01*
Y244800D01*
G01X379096Y253425D02*
X379304Y253758D01*
X379429Y254133D01*
Y254467D01*
X379304Y254800D01*
X379096Y255050D01*
X378804Y255175D01*
X378512Y255092D01*
X378262Y254883D01*
X378096Y254508D01*
X378012Y254008D01*
X377846Y253717D01*
X377554Y253592D01*
X377262Y253675D01*
X377054Y253883D01*
X376929Y254175D01*
Y254467D01*
X377012Y254758D01*
X377221Y255008D01*
G01X379429Y256567D02*
X376929D01*
Y257608D01*
X377054Y257942D01*
X377221Y258150D01*
X377554Y258233D01*
X377887Y258150D01*
X378096Y257900D01*
X378221Y257608D01*
Y256567D01*
G01Y257608D02*
X379429Y258233D01*
G01X378387Y259708D02*
X378096Y260000D01*
X377929Y260250D01*
X377846Y260583D01*
X377929Y260875D01*
X378096Y261083D01*
X378346Y261250D01*
X378637Y261292D01*
X378887Y261250D01*
X379137Y261083D01*
X379346Y260833D01*
X379429Y260542D01*
X379346Y260208D01*
X379096Y259917D01*
X378721Y259750D01*
X378304Y259708D01*
X377762Y259792D01*
X377471Y259917D01*
X377179Y260125D01*
X376971Y260417D01*
X376929Y260708D01*
X377012Y261000D01*
X377221Y261208D01*
G01X379429Y263517D02*
X378887Y263600D01*
X378429Y263725D01*
X378012Y263892D01*
X377554Y264100D01*
X376929Y264433D01*
Y262767D01*
G01X379137Y265992D02*
X379346Y266283D01*
X379429Y266617D01*
X379346Y266950D01*
X379096Y267242D01*
X378721Y267450D01*
X378346Y267533D01*
X377887D01*
X377512Y267450D01*
X377179Y267242D01*
X377012Y266992D01*
X376929Y266700D01*
X377012Y266367D01*
X377179Y266117D01*
X377429Y265950D01*
X377762Y265867D01*
X378054Y265950D01*
X378346Y266158D01*
X378512Y266408D01*
X378554Y266700D01*
X378471Y267033D01*
X378262Y267283D01*
X377887Y267533D01*
G01X381929Y252200D02*
X377929D01*
Y244800D01*
G01X367667Y269375D02*
X367875Y269708D01*
X368000Y270083D01*
Y270417D01*
X367875Y270750D01*
X367667Y271000D01*
X367375Y271125D01*
X367083Y271042D01*
X366833Y270833D01*
X366667Y270458D01*
X366583Y269958D01*
X366417Y269667D01*
X366125Y269542D01*
X365833Y269625D01*
X365625Y269833D01*
X365500Y270125D01*
Y270417D01*
X365583Y270708D01*
X365792Y270958D01*
G01X365708Y274267D02*
X365583Y274017D01*
X365500Y273725D01*
Y273392D01*
X365625Y273017D01*
X365833Y272725D01*
X366083Y272517D01*
X366500Y272350D01*
X366875Y272308D01*
X367250Y272392D01*
X367500Y272517D01*
X367750Y272767D01*
X367917Y273058D01*
X368000Y273350D01*
Y273642D01*
X367917Y273933D01*
X367792Y274183D01*
X367625Y274392D01*
G01X368000Y276450D02*
X365500D01*
X366000Y275950D01*
G01X368000D02*
Y276950D01*
G01X365500Y279550D02*
X365583Y279217D01*
X365792Y278967D01*
X366042Y278800D01*
X366375Y278675D01*
X366750Y278633D01*
X367125Y278675D01*
X367458Y278800D01*
X367708Y278967D01*
X367917Y279217D01*
X368000Y279550D01*
X367917Y279883D01*
X367708Y280133D01*
X367458Y280300D01*
X367125Y280425D01*
X366750Y280467D01*
X366375Y280425D01*
X366042Y280300D01*
X365792Y280133D01*
X365583Y279883D01*
X365500Y279550D01*
G01Y282650D02*
X365583Y282317D01*
X365792Y282067D01*
X366042Y281900D01*
X366375Y281775D01*
X366750Y281733D01*
X367125Y281775D01*
X367458Y281900D01*
X367708Y282067D01*
X367917Y282317D01*
X368000Y282650D01*
X367917Y282983D01*
X367708Y283233D01*
X367458Y283400D01*
X367125Y283525D01*
X366750Y283567D01*
X366375Y283525D01*
X366042Y283400D01*
X365792Y283233D01*
X365583Y282983D01*
X365500Y282650D01*
G01X367625Y284833D02*
X367833Y285083D01*
X367958Y285375D01*
X368000Y285750D01*
X367917Y286125D01*
X367750Y286417D01*
X367458Y286625D01*
X367125Y286667D01*
X366792Y286583D01*
X366583Y286375D01*
X366417Y286083D01*
X366375Y285792D01*
X366417Y285500D01*
X366583Y285125D01*
X365500Y285250D01*
Y286375D01*
G01X375667Y277925D02*
X375875Y278258D01*
X376000Y278633D01*
Y278967D01*
X375875Y279300D01*
X375667Y279550D01*
X375375Y279675D01*
X375083Y279592D01*
X374833Y279383D01*
X374667Y279008D01*
X374583Y278508D01*
X374417Y278217D01*
X374125Y278092D01*
X373833Y278175D01*
X373625Y278383D01*
X373500Y278675D01*
Y278967D01*
X373583Y279258D01*
X373792Y279508D01*
G01X373708Y282817D02*
X373583Y282567D01*
X373500Y282275D01*
Y281942D01*
X373625Y281567D01*
X373833Y281275D01*
X374083Y281067D01*
X374500Y280900D01*
X374875Y280858D01*
X375250Y280942D01*
X375500Y281067D01*
X375750Y281317D01*
X375917Y281608D01*
X376000Y281900D01*
Y282192D01*
X375917Y282483D01*
X375792Y282733D01*
X375625Y282942D01*
G01X375708Y284292D02*
X375917Y284583D01*
X376000Y284917D01*
X375917Y285250D01*
X375667Y285542D01*
X375292Y285750D01*
X374917Y285833D01*
X374458D01*
X374083Y285750D01*
X373750Y285542D01*
X373583Y285292D01*
X373500Y285000D01*
X373583Y284667D01*
X373750Y284417D01*
X374000Y284250D01*
X374333Y284167D01*
X374625Y284250D01*
X374917Y284458D01*
X375083Y284708D01*
X375125Y285000D01*
X375042Y285333D01*
X374833Y285583D01*
X374458Y285833D01*
G01X374958Y287308D02*
X374667Y287600D01*
X374500Y287850D01*
X374417Y288183D01*
X374500Y288475D01*
X374667Y288683D01*
X374917Y288850D01*
X375208Y288892D01*
X375458Y288850D01*
X375708Y288683D01*
X375917Y288433D01*
X376000Y288142D01*
X375917Y287808D01*
X375667Y287517D01*
X375292Y287350D01*
X374875Y287308D01*
X374333Y287392D01*
X374042Y287517D01*
X373750Y287725D01*
X373542Y288017D01*
X373500Y288308D01*
X373583Y288600D01*
X373792Y288808D01*
G01X376000Y291200D02*
X375958Y291492D01*
X375833Y291825D01*
X375625Y292033D01*
X375333Y292117D01*
X375042Y292033D01*
X374792Y291783D01*
X374667Y291408D01*
Y290992D01*
X374583Y290742D01*
X374375Y290533D01*
X374083Y290450D01*
X373792Y290575D01*
X373583Y290867D01*
X373500Y291200D01*
X373583Y291533D01*
X373792Y291825D01*
X374083Y291950D01*
X374375Y291867D01*
X374583Y291658D01*
X374667Y291408D01*
Y290992D01*
X374792Y290617D01*
X375042Y290367D01*
X375333Y290283D01*
X375625Y290367D01*
X375833Y290575D01*
X375958Y290908D01*
X376000Y291200D01*
G01X380167Y277925D02*
X380375Y278258D01*
X380500Y278633D01*
Y278967D01*
X380375Y279300D01*
X380167Y279550D01*
X379875Y279675D01*
X379583Y279592D01*
X379333Y279383D01*
X379167Y279008D01*
X379083Y278508D01*
X378917Y278217D01*
X378625Y278092D01*
X378333Y278175D01*
X378125Y278383D01*
X378000Y278675D01*
Y278967D01*
X378083Y279258D01*
X378292Y279508D01*
G01X378208Y282817D02*
X378083Y282567D01*
X378000Y282275D01*
Y281942D01*
X378125Y281567D01*
X378333Y281275D01*
X378583Y281067D01*
X379000Y280900D01*
X379375Y280858D01*
X379750Y280942D01*
X380000Y281067D01*
X380250Y281317D01*
X380417Y281608D01*
X380500Y281900D01*
Y282192D01*
X380417Y282483D01*
X380292Y282733D01*
X380125Y282942D01*
G01X380208Y284292D02*
X380417Y284583D01*
X380500Y284917D01*
X380417Y285250D01*
X380167Y285542D01*
X379792Y285750D01*
X379417Y285833D01*
X378958D01*
X378583Y285750D01*
X378250Y285542D01*
X378083Y285292D01*
X378000Y285000D01*
X378083Y284667D01*
X378250Y284417D01*
X378500Y284250D01*
X378833Y284167D01*
X379125Y284250D01*
X379417Y284458D01*
X379583Y284708D01*
X379625Y285000D01*
X379542Y285333D01*
X379333Y285583D01*
X378958Y285833D01*
G01X380500Y288017D02*
X379958Y288100D01*
X379500Y288225D01*
X379083Y288392D01*
X378625Y288600D01*
X378000Y288933D01*
Y287267D01*
G01Y291200D02*
X378083Y290867D01*
X378292Y290617D01*
X378542Y290450D01*
X378875Y290325D01*
X379250Y290283D01*
X379625Y290325D01*
X379958Y290450D01*
X380208Y290617D01*
X380417Y290867D01*
X380500Y291200D01*
X380417Y291533D01*
X380208Y291783D01*
X379958Y291950D01*
X379625Y292075D01*
X379250Y292117D01*
X378875Y292075D01*
X378542Y291950D01*
X378292Y291783D01*
X378083Y291533D01*
X378000Y291200D01*
G01X381255Y310500D02*
Y314500D01*
X373855D01*
G01X381255Y315000D02*
Y319000D01*
X373855D01*
G01X381255Y319500D02*
Y323500D01*
X373855D01*
G01Y332500D02*
Y328500D01*
X381255D01*
G01Y324000D02*
Y328000D01*
X373855D01*
G01Y337000D02*
Y333000D01*
X381255D01*
G01X365596Y349875D02*
X365804Y350208D01*
X365929Y350583D01*
Y350917D01*
X365804Y351250D01*
X365596Y351500D01*
X365304Y351625D01*
X365012Y351542D01*
X364762Y351333D01*
X364596Y350958D01*
X364512Y350458D01*
X364346Y350167D01*
X364054Y350042D01*
X363762Y350125D01*
X363554Y350333D01*
X363429Y350625D01*
Y350917D01*
X363512Y351208D01*
X363721Y351458D01*
G01X363637Y354767D02*
X363512Y354517D01*
X363429Y354225D01*
Y353892D01*
X363554Y353517D01*
X363762Y353225D01*
X364012Y353017D01*
X364429Y352850D01*
X364804Y352808D01*
X365179Y352892D01*
X365429Y353017D01*
X365679Y353267D01*
X365846Y353558D01*
X365929Y353850D01*
Y354142D01*
X365846Y354433D01*
X365721Y354683D01*
X365554Y354892D01*
G01X365929Y356950D02*
X363429D01*
X363929Y356450D01*
G01X365929D02*
Y357450D01*
G01Y360050D02*
X363429D01*
X363929Y359550D01*
G01X365929D02*
Y360550D01*
G01Y363650D02*
X363429D01*
X365221Y362108D01*
Y364192D01*
G01X365637Y365542D02*
X365846Y365833D01*
X365929Y366167D01*
X365846Y366500D01*
X365596Y366792D01*
X365221Y367000D01*
X364846Y367083D01*
X364387D01*
X364012Y367000D01*
X363679Y366792D01*
X363512Y366542D01*
X363429Y366250D01*
X363512Y365917D01*
X363679Y365667D01*
X363929Y365500D01*
X364262Y365417D01*
X364554Y365500D01*
X364846Y365708D01*
X365012Y365958D01*
X365054Y366250D01*
X364971Y366583D01*
X364762Y366833D01*
X364387Y367083D01*
G01X373855Y341500D02*
Y337500D01*
X381255D01*
G01X373855Y346000D02*
Y342000D01*
X381255D01*
G01Y346500D02*
Y350500D01*
X373855D01*
G01X371667Y361925D02*
X371875Y362258D01*
X372000Y362633D01*
Y362967D01*
X371875Y363300D01*
X371667Y363550D01*
X371375Y363675D01*
X371083Y363592D01*
X370833Y363383D01*
X370667Y363008D01*
X370583Y362508D01*
X370417Y362217D01*
X370125Y362092D01*
X369833Y362175D01*
X369625Y362383D01*
X369500Y362675D01*
Y362967D01*
X369583Y363258D01*
X369792Y363508D01*
G01X369500Y365900D02*
X372000D01*
G01X369500Y364942D02*
Y366858D01*
G01X372000Y368167D02*
X369500D01*
Y369167D01*
X369625Y369500D01*
X369917Y369750D01*
X370250Y369833D01*
X370583Y369750D01*
X370833Y369542D01*
X370958Y369167D01*
Y368167D01*
G01X371708Y371392D02*
X371917Y371683D01*
X372000Y372017D01*
X371917Y372350D01*
X371667Y372642D01*
X371292Y372850D01*
X370917Y372933D01*
X370458D01*
X370083Y372850D01*
X369750Y372642D01*
X369583Y372392D01*
X369500Y372100D01*
X369583Y371767D01*
X369750Y371517D01*
X370000Y371350D01*
X370333Y371267D01*
X370625Y371350D01*
X370917Y371558D01*
X371083Y371808D01*
X371125Y372100D01*
X371042Y372433D01*
X370833Y372683D01*
X370458Y372933D01*
G01X371708Y374492D02*
X371917Y374783D01*
X372000Y375117D01*
X371917Y375450D01*
X371667Y375742D01*
X371292Y375950D01*
X370917Y376033D01*
X370458D01*
X370083Y375950D01*
X369750Y375742D01*
X369583Y375492D01*
X369500Y375200D01*
X369583Y374867D01*
X369750Y374617D01*
X370000Y374450D01*
X370333Y374367D01*
X370625Y374450D01*
X370917Y374658D01*
X371083Y374908D01*
X371125Y375200D01*
X371042Y375533D01*
X370833Y375783D01*
X370458Y376033D01*
G01X381255Y364500D02*
Y368500D01*
X373855D01*
G01Y359500D02*
Y355500D01*
X381255D01*
G01Y351000D02*
Y355000D01*
X373855D01*
G01Y364000D02*
Y360000D01*
X381255D01*
G01X370667Y377925D02*
X370875Y378258D01*
X371000Y378633D01*
Y378967D01*
X370875Y379300D01*
X370667Y379550D01*
X370375Y379675D01*
X370083Y379592D01*
X369833Y379383D01*
X369667Y379008D01*
X369583Y378508D01*
X369417Y378217D01*
X369125Y378092D01*
X368833Y378175D01*
X368625Y378383D01*
X368500Y378675D01*
Y378967D01*
X368583Y379258D01*
X368792Y379508D01*
G01X371000Y381067D02*
X368500D01*
Y382108D01*
X368625Y382442D01*
X368792Y382650D01*
X369125Y382733D01*
X369458Y382650D01*
X369667Y382400D01*
X369792Y382108D01*
Y381067D01*
G01Y382108D02*
X371000Y382733D01*
G01Y385000D02*
X370958Y385292D01*
X370833Y385625D01*
X370625Y385833D01*
X370333Y385917D01*
X370042Y385833D01*
X369792Y385583D01*
X369667Y385208D01*
Y384792D01*
X369583Y384542D01*
X369375Y384333D01*
X369083Y384250D01*
X368792Y384375D01*
X368583Y384667D01*
X368500Y385000D01*
X368583Y385333D01*
X368792Y385625D01*
X369083Y385750D01*
X369375Y385667D01*
X369583Y385458D01*
X369667Y385208D01*
Y384792D01*
X369792Y384417D01*
X370042Y384167D01*
X370333Y384083D01*
X370625Y384167D01*
X370833Y384375D01*
X370958Y384708D01*
X371000Y385000D01*
G01X368500Y388100D02*
X368583Y387767D01*
X368792Y387517D01*
X369042Y387350D01*
X369375Y387225D01*
X369750Y387183D01*
X370125Y387225D01*
X370458Y387350D01*
X370708Y387517D01*
X370917Y387767D01*
X371000Y388100D01*
X370917Y388433D01*
X370708Y388683D01*
X370458Y388850D01*
X370125Y388975D01*
X369750Y389017D01*
X369375Y388975D01*
X369042Y388850D01*
X368792Y388683D01*
X368583Y388433D01*
X368500Y388100D01*
G01X371000Y391700D02*
X368500D01*
X370292Y390158D01*
Y392242D01*
G01X381255Y369000D02*
Y373000D01*
X373855D01*
G01X374425Y379833D02*
X374758Y379625D01*
X375133Y379500D01*
X375467D01*
X375800Y379625D01*
X376050Y379833D01*
X376175Y380125D01*
X376092Y380417D01*
X375883Y380667D01*
X375508Y380833D01*
X375008Y380917D01*
X374717Y381083D01*
X374592Y381375D01*
X374675Y381667D01*
X374883Y381875D01*
X375175Y382000D01*
X375467D01*
X375758Y381917D01*
X376008Y381708D01*
G01X377567Y379500D02*
Y382000D01*
X378608D01*
X378942Y381875D01*
X379150Y381708D01*
X379233Y381375D01*
X379150Y381042D01*
X378900Y380833D01*
X378608Y380708D01*
X377567D01*
G01X378608D02*
X379233Y379500D01*
G01X381417D02*
X381500Y380042D01*
X381625Y380500D01*
X381792Y380917D01*
X382000Y381375D01*
X382333Y382000D01*
X380667D01*
G01X384600Y379500D02*
X384892Y379542D01*
X385225Y379667D01*
X385433Y379875D01*
X385517Y380167D01*
X385433Y380458D01*
X385183Y380708D01*
X384808Y380833D01*
X384392D01*
X384142Y380917D01*
X383933Y381125D01*
X383850Y381417D01*
X383975Y381708D01*
X384267Y381917D01*
X384600Y382000D01*
X384933Y381917D01*
X385225Y381708D01*
X385350Y381417D01*
X385267Y381125D01*
X385058Y380917D01*
X384808Y380833D01*
X384392D01*
X384017Y380708D01*
X383767Y380458D01*
X383683Y380167D01*
X383767Y379875D01*
X383975Y379667D01*
X384308Y379542D01*
X384600Y379500D01*
G01X386908Y381583D02*
X387158Y381833D01*
X387450Y381958D01*
X387783Y382000D01*
X388200Y381917D01*
X388492Y381708D01*
X388575Y381458D01*
X388533Y381208D01*
X388367Y381000D01*
X387533Y380583D01*
X387158Y380292D01*
X386908Y379875D01*
X386825Y379500D01*
X388575D01*
G01X381255Y373500D02*
Y377500D01*
X373855D01*
G01X374370Y396333D02*
X374703Y396125D01*
X375078Y396000D01*
X375412D01*
X375745Y396125D01*
X375995Y396333D01*
X376120Y396625D01*
X376037Y396917D01*
X375828Y397167D01*
X375453Y397333D01*
X374953Y397417D01*
X374662Y397583D01*
X374537Y397875D01*
X374620Y398167D01*
X374828Y398375D01*
X375120Y398500D01*
X375412D01*
X375703Y398417D01*
X375953Y398208D01*
G01X378345Y398500D02*
Y396000D01*
G01X377387Y398500D02*
X379303D01*
G01X380612Y396000D02*
Y398500D01*
X381612D01*
X381945Y398375D01*
X382195Y398083D01*
X382278Y397750D01*
X382195Y397417D01*
X381987Y397167D01*
X381612Y397042D01*
X380612D01*
G01X384545Y396000D02*
X384837Y396042D01*
X385170Y396167D01*
X385378Y396375D01*
X385462Y396667D01*
X385378Y396958D01*
X385128Y397208D01*
X384753Y397333D01*
X384337D01*
X384087Y397417D01*
X383878Y397625D01*
X383795Y397917D01*
X383920Y398208D01*
X384212Y398417D01*
X384545Y398500D01*
X384878Y398417D01*
X385170Y398208D01*
X385295Y397917D01*
X385212Y397625D01*
X385003Y397417D01*
X384753Y397333D01*
X384337D01*
X383962Y397208D01*
X383712Y396958D01*
X383628Y396667D01*
X383712Y396375D01*
X383920Y396167D01*
X384253Y396042D01*
X384545Y396000D01*
G01X387645D02*
Y398500D01*
X387145Y398000D01*
G01Y396000D02*
X388145D01*
G01X382223Y385783D02*
Y389783D01*
X374823D01*
G01X370352Y404925D02*
X370560Y405258D01*
X370685Y405633D01*
Y405967D01*
X370560Y406300D01*
X370352Y406550D01*
X370060Y406675D01*
X369768Y406592D01*
X369518Y406383D01*
X369352Y406008D01*
X369268Y405508D01*
X369102Y405217D01*
X368810Y405092D01*
X368518Y405175D01*
X368310Y405383D01*
X368185Y405675D01*
Y405967D01*
X368268Y406258D01*
X368477Y406508D01*
G01X368185Y408900D02*
X370685D01*
G01X368185Y407942D02*
Y409858D01*
G01X370685Y411167D02*
X368185D01*
Y412167D01*
X368310Y412500D01*
X368602Y412750D01*
X368935Y412833D01*
X369268Y412750D01*
X369518Y412542D01*
X369643Y412167D01*
Y411167D01*
G01X370685Y415100D02*
X370643Y415392D01*
X370518Y415725D01*
X370310Y415933D01*
X370018Y416017D01*
X369727Y415933D01*
X369477Y415683D01*
X369352Y415308D01*
Y414892D01*
X369268Y414642D01*
X369060Y414433D01*
X368768Y414350D01*
X368477Y414475D01*
X368268Y414767D01*
X368185Y415100D01*
X368268Y415433D01*
X368477Y415725D01*
X368768Y415850D01*
X369060Y415767D01*
X369268Y415558D01*
X369352Y415308D01*
Y414892D01*
X369477Y414517D01*
X369727Y414267D01*
X370018Y414183D01*
X370310Y414267D01*
X370518Y414475D01*
X370643Y414808D01*
X370685Y415100D01*
G01Y418200D02*
X370643Y418492D01*
X370518Y418825D01*
X370310Y419033D01*
X370018Y419117D01*
X369727Y419033D01*
X369477Y418783D01*
X369352Y418408D01*
Y417992D01*
X369268Y417742D01*
X369060Y417533D01*
X368768Y417450D01*
X368477Y417575D01*
X368268Y417867D01*
X368185Y418200D01*
X368268Y418533D01*
X368477Y418825D01*
X368768Y418950D01*
X369060Y418867D01*
X369268Y418658D01*
X369352Y418408D01*
Y417992D01*
X369477Y417617D01*
X369727Y417367D01*
X370018Y417283D01*
X370310Y417367D01*
X370518Y417575D01*
X370643Y417908D01*
X370685Y418200D01*
G01X380475Y401780D02*
Y405780D01*
X373075D01*
G01X380505Y406500D02*
Y410500D01*
X373105D01*
G01X380505Y411000D02*
Y415000D01*
X373105D01*
G01X380505Y415500D02*
Y419500D01*
X373105D01*
G01X380505Y424500D02*
Y428500D01*
X373105D01*
G01X380505Y420000D02*
Y424000D01*
X373105D01*
G01X380505Y429000D02*
Y433000D01*
X373105D01*
G01X371730Y444333D02*
X372063Y444125D01*
X372438Y444000D01*
X372772D01*
X373105Y444125D01*
X373355Y444333D01*
X373480Y444625D01*
X373397Y444917D01*
X373188Y445167D01*
X372813Y445333D01*
X372313Y445417D01*
X372022Y445583D01*
X371897Y445875D01*
X371980Y446167D01*
X372188Y446375D01*
X372480Y446500D01*
X372772D01*
X373063Y446417D01*
X373313Y446208D01*
G01X374872Y444000D02*
Y446500D01*
X375913D01*
X376247Y446375D01*
X376455Y446208D01*
X376538Y445875D01*
X376455Y445542D01*
X376205Y445333D01*
X375913Y445208D01*
X374872D01*
G01X375913D02*
X376538Y444000D01*
G01X378722D02*
X378805Y444542D01*
X378930Y445000D01*
X379097Y445417D01*
X379305Y445875D01*
X379638Y446500D01*
X377972D01*
G01X380988Y444500D02*
X381238Y444208D01*
X381572Y444042D01*
X381947Y444000D01*
X382280Y444042D01*
X382613Y444250D01*
X382822Y444500D01*
X382863Y444750D01*
X382780Y445042D01*
X382488Y445250D01*
X382197Y445333D01*
X381822D01*
G01X382197D02*
X382447Y445458D01*
X382655Y445667D01*
X382738Y445917D01*
X382655Y446167D01*
X382447Y446375D01*
X382072Y446500D01*
X381697Y446458D01*
X381322Y446292D01*
G01X384088Y444375D02*
X384338Y444167D01*
X384630Y444042D01*
X385005Y444000D01*
X385380Y444083D01*
X385672Y444250D01*
X385880Y444542D01*
X385922Y444875D01*
X385838Y445208D01*
X385630Y445417D01*
X385338Y445583D01*
X385047Y445625D01*
X384755Y445583D01*
X384380Y445417D01*
X384505Y446500D01*
X385630D01*
G01X371730Y439833D02*
X372063Y439625D01*
X372438Y439500D01*
X372772D01*
X373105Y439625D01*
X373355Y439833D01*
X373480Y440125D01*
X373397Y440417D01*
X373188Y440667D01*
X372813Y440833D01*
X372313Y440917D01*
X372022Y441083D01*
X371897Y441375D01*
X371980Y441667D01*
X372188Y441875D01*
X372480Y442000D01*
X372772D01*
X373063Y441917D01*
X373313Y441708D01*
G01X374872Y439500D02*
Y442000D01*
X375913D01*
X376247Y441875D01*
X376455Y441708D01*
X376538Y441375D01*
X376455Y441042D01*
X376205Y440833D01*
X375913Y440708D01*
X374872D01*
G01X375913D02*
X376538Y439500D01*
G01X378722D02*
X378805Y440042D01*
X378930Y440500D01*
X379097Y440917D01*
X379305Y441375D01*
X379638Y442000D01*
X377972D01*
G01X380988Y440000D02*
X381238Y439708D01*
X381572Y439542D01*
X381947Y439500D01*
X382280Y439542D01*
X382613Y439750D01*
X382822Y440000D01*
X382863Y440250D01*
X382780Y440542D01*
X382488Y440750D01*
X382197Y440833D01*
X381822D01*
G01X382197D02*
X382447Y440958D01*
X382655Y441167D01*
X382738Y441417D01*
X382655Y441667D01*
X382447Y441875D01*
X382072Y442000D01*
X381697Y441958D01*
X381322Y441792D01*
G01X384213Y440542D02*
X384505Y440833D01*
X384755Y441000D01*
X385088Y441083D01*
X385380Y441000D01*
X385588Y440833D01*
X385755Y440583D01*
X385797Y440292D01*
X385755Y440042D01*
X385588Y439792D01*
X385338Y439583D01*
X385047Y439500D01*
X384713Y439583D01*
X384422Y439833D01*
X384255Y440208D01*
X384213Y440625D01*
X384297Y441167D01*
X384422Y441458D01*
X384630Y441750D01*
X384922Y441958D01*
X385213Y442000D01*
X385505Y441917D01*
X385713Y441708D01*
G01X380505Y433500D02*
Y437500D01*
X373105D01*
G01X371730Y448833D02*
X372063Y448625D01*
X372438Y448500D01*
X372772D01*
X373105Y448625D01*
X373355Y448833D01*
X373480Y449125D01*
X373397Y449417D01*
X373188Y449667D01*
X372813Y449833D01*
X372313Y449917D01*
X372022Y450083D01*
X371897Y450375D01*
X371980Y450667D01*
X372188Y450875D01*
X372480Y451000D01*
X372772D01*
X373063Y450917D01*
X373313Y450708D01*
G01X374872Y448500D02*
Y451000D01*
X375913D01*
X376247Y450875D01*
X376455Y450708D01*
X376538Y450375D01*
X376455Y450042D01*
X376205Y449833D01*
X375913Y449708D01*
X374872D01*
G01X375913D02*
X376538Y448500D01*
G01X378722D02*
X378805Y449042D01*
X378930Y449500D01*
X379097Y449917D01*
X379305Y450375D01*
X379638Y451000D01*
X377972D01*
G01X382405Y448500D02*
Y451000D01*
X380863Y449208D01*
X382947D01*
G01X385505Y448500D02*
Y451000D01*
X383963Y449208D01*
X386047D01*
G01X378555Y462050D02*
X382555D01*
Y469450D01*
G01X373055Y462050D02*
X377055D01*
Y469450D01*
G01X371730Y453333D02*
X372063Y453125D01*
X372438Y453000D01*
X372772D01*
X373105Y453125D01*
X373355Y453333D01*
X373480Y453625D01*
X373397Y453917D01*
X373188Y454167D01*
X372813Y454333D01*
X372313Y454417D01*
X372022Y454583D01*
X371897Y454875D01*
X371980Y455167D01*
X372188Y455375D01*
X372480Y455500D01*
X372772D01*
X373063Y455417D01*
X373313Y455208D01*
G01X374872Y453000D02*
Y455500D01*
X375913D01*
X376247Y455375D01*
X376455Y455208D01*
X376538Y454875D01*
X376455Y454542D01*
X376205Y454333D01*
X375913Y454208D01*
X374872D01*
G01X375913D02*
X376538Y453000D01*
G01X378722D02*
X378805Y453542D01*
X378930Y454000D01*
X379097Y454417D01*
X379305Y454875D01*
X379638Y455500D01*
X377972D01*
G01X380988Y453500D02*
X381238Y453208D01*
X381572Y453042D01*
X381947Y453000D01*
X382280Y453042D01*
X382613Y453250D01*
X382822Y453500D01*
X382863Y453750D01*
X382780Y454042D01*
X382488Y454250D01*
X382197Y454333D01*
X381822D01*
G01X382197D02*
X382447Y454458D01*
X382655Y454667D01*
X382738Y454917D01*
X382655Y455167D01*
X382447Y455375D01*
X382072Y455500D01*
X381697Y455458D01*
X381322Y455292D01*
G01X384297Y453292D02*
X384588Y453083D01*
X384922Y453000D01*
X385255Y453083D01*
X385547Y453333D01*
X385755Y453708D01*
X385838Y454083D01*
Y454542D01*
X385755Y454917D01*
X385547Y455250D01*
X385297Y455417D01*
X385005Y455500D01*
X384672Y455417D01*
X384422Y455250D01*
X384255Y455000D01*
X384172Y454667D01*
X384255Y454375D01*
X384463Y454083D01*
X384713Y453917D01*
X385005Y453875D01*
X385338Y453958D01*
X385588Y454167D01*
X385838Y454542D01*
G01X373222Y523475D02*
X373430Y523808D01*
X373555Y524183D01*
Y524517D01*
X373430Y524850D01*
X373222Y525100D01*
X372930Y525225D01*
X372638Y525142D01*
X372388Y524933D01*
X372222Y524558D01*
X372138Y524058D01*
X371972Y523767D01*
X371680Y523642D01*
X371388Y523725D01*
X371180Y523933D01*
X371055Y524225D01*
Y524517D01*
X371138Y524808D01*
X371347Y525058D01*
G01X371055Y526533D02*
X372847D01*
X373222Y526700D01*
X373472Y527033D01*
X373555Y527450D01*
X373472Y527867D01*
X373222Y528200D01*
X372847Y528367D01*
X371055D01*
G01X373555Y530467D02*
X373013Y530550D01*
X372555Y530675D01*
X372138Y530842D01*
X371680Y531050D01*
X371055Y531383D01*
Y529717D01*
G01X373555Y533650D02*
X371055D01*
X371555Y533150D01*
G01X373555D02*
Y534150D01*
G01X365448Y523594D02*
Y534594D01*
G01X363085Y804780D02*
X365335D01*
G01X363085Y798900D02*
Y804780D01*
G01X365335Y798900D02*
X363085D01*
G01X364435Y801935D02*
X363085D01*
G01X368835Y800570D02*
Y804780D01*
G01X368605Y799685D02*
X368835Y800570D01*
G01X368155Y799100D02*
X368605Y799685D01*
G01X367590Y798900D02*
X368155Y799100D01*
G01X367025D02*
X367590Y798900D01*
G01X366575Y799685D02*
X367025Y799100D01*
G01X366350Y800570D02*
X366575Y799685D01*
G01X366350Y804780D02*
Y800570D01*
G01X374800Y798995D02*
X374355Y798900D01*
G01X375200Y799390D02*
X374800Y798995D01*
G01X375535Y799980D02*
X375200Y799390D01*
G01X375765Y800665D02*
X375535Y799980D01*
G01X375875Y801450D02*
X375765Y800665D01*
G01X375875Y802230D02*
Y801450D01*
G01X375765Y803015D02*
X375875Y802230D01*
G01X375535Y803700D02*
X375765Y803015D01*
G01X375200Y804290D02*
X375535Y803700D01*
G01X374800Y804685D02*
X375200Y804290D01*
G01X374355Y804780D02*
X374800Y804685D01*
G01X373905D02*
X374355Y804780D01*
G01X373505Y804290D02*
X373905Y804685D01*
G01X373170Y803700D02*
X373505Y804290D01*
G01X372940Y803015D02*
X373170Y803700D01*
G01X372830Y802230D02*
X372940Y803015D01*
G01X372830Y801450D02*
Y802230D01*
G01X372940Y800665D02*
X372830Y801450D01*
G01X373170Y799980D02*
X372940Y800665D01*
G01X373505Y799390D02*
X373170Y799980D01*
G01X373905Y798995D02*
X373505Y799390D01*
G01X374355Y798900D02*
X373905Y798995D01*
G01X376780Y798900D02*
Y802820D01*
G01X378690Y801640D02*
Y798900D01*
G01X378520Y802330D02*
X378690Y801640D01*
G01X378180Y802720D02*
X378520Y802330D01*
G01X377790Y802820D02*
X378180Y802720D01*
G01X377335D02*
X377790Y802820D01*
G01X377000Y802330D02*
X377335Y802720D01*
G01X376780Y801840D02*
X377000Y802330D01*
G01X376667Y852425D02*
X376875Y852758D01*
X377000Y853133D01*
Y853467D01*
X376875Y853800D01*
X376667Y854050D01*
X376375Y854175D01*
X376083Y854092D01*
X375833Y853883D01*
X375667Y853508D01*
X375583Y853008D01*
X375417Y852717D01*
X375125Y852592D01*
X374833Y852675D01*
X374625Y852883D01*
X374500Y853175D01*
Y853467D01*
X374583Y853758D01*
X374792Y854008D01*
G01X377000Y855567D02*
X374500D01*
Y856608D01*
X374625Y856942D01*
X374792Y857150D01*
X375125Y857233D01*
X375458Y857150D01*
X375667Y856900D01*
X375792Y856608D01*
Y855567D01*
G01Y856608D02*
X377000Y857233D01*
G01X376500Y858583D02*
X376792Y858833D01*
X376958Y859167D01*
X377000Y859542D01*
X376958Y859875D01*
X376750Y860208D01*
X376500Y860417D01*
X376250Y860458D01*
X375958Y860375D01*
X375750Y860083D01*
X375667Y859792D01*
Y859417D01*
G01Y859792D02*
X375542Y860042D01*
X375333Y860250D01*
X375083Y860333D01*
X374833Y860250D01*
X374625Y860042D01*
X374500Y859667D01*
X374542Y859292D01*
X374708Y858917D01*
G01X377000Y862600D02*
X374500D01*
X375000Y862100D01*
G01X377000D02*
Y863100D01*
G01X374917Y864908D02*
X374667Y865158D01*
X374542Y865450D01*
X374500Y865783D01*
X374583Y866200D01*
X374792Y866492D01*
X375042Y866575D01*
X375292Y866533D01*
X375500Y866367D01*
X375917Y865533D01*
X376208Y865158D01*
X376625Y864908D01*
X377000Y864825D01*
Y866575D01*
G01X372167Y852425D02*
X372375Y852758D01*
X372500Y853133D01*
Y853467D01*
X372375Y853800D01*
X372167Y854050D01*
X371875Y854175D01*
X371583Y854092D01*
X371333Y853883D01*
X371167Y853508D01*
X371083Y853008D01*
X370917Y852717D01*
X370625Y852592D01*
X370333Y852675D01*
X370125Y852883D01*
X370000Y853175D01*
Y853467D01*
X370083Y853758D01*
X370292Y854008D01*
G01X372500Y855567D02*
X370000D01*
Y856608D01*
X370125Y856942D01*
X370292Y857150D01*
X370625Y857233D01*
X370958Y857150D01*
X371167Y856900D01*
X371292Y856608D01*
Y855567D01*
G01Y856608D02*
X372500Y857233D01*
G01X372000Y858583D02*
X372292Y858833D01*
X372458Y859167D01*
X372500Y859542D01*
X372458Y859875D01*
X372250Y860208D01*
X372000Y860417D01*
X371750Y860458D01*
X371458Y860375D01*
X371250Y860083D01*
X371167Y859792D01*
Y859417D01*
G01Y859792D02*
X371042Y860042D01*
X370833Y860250D01*
X370583Y860333D01*
X370333Y860250D01*
X370125Y860042D01*
X370000Y859667D01*
X370042Y859292D01*
X370208Y858917D01*
G01X372500Y862600D02*
X370000D01*
X370500Y862100D01*
G01X372500D02*
Y863100D01*
G01Y866200D02*
X370000D01*
X371792Y864658D01*
Y866742D01*
G01X368167Y852425D02*
X368375Y852758D01*
X368500Y853133D01*
Y853467D01*
X368375Y853800D01*
X368167Y854050D01*
X367875Y854175D01*
X367583Y854092D01*
X367333Y853883D01*
X367167Y853508D01*
X367083Y853008D01*
X366917Y852717D01*
X366625Y852592D01*
X366333Y852675D01*
X366125Y852883D01*
X366000Y853175D01*
Y853467D01*
X366083Y853758D01*
X366292Y854008D01*
G01X366208Y857317D02*
X366083Y857067D01*
X366000Y856775D01*
Y856442D01*
X366125Y856067D01*
X366333Y855775D01*
X366583Y855567D01*
X367000Y855400D01*
X367375Y855358D01*
X367750Y855442D01*
X368000Y855567D01*
X368250Y855817D01*
X368417Y856108D01*
X368500Y856400D01*
Y856692D01*
X368417Y856983D01*
X368292Y857233D01*
X368125Y857442D01*
G01X368500Y860000D02*
X366000D01*
X367792Y858458D01*
Y860542D01*
G01X368000Y861683D02*
X368292Y861933D01*
X368458Y862267D01*
X368500Y862642D01*
X368458Y862975D01*
X368250Y863308D01*
X368000Y863517D01*
X367750Y863558D01*
X367458Y863475D01*
X367250Y863183D01*
X367167Y862892D01*
Y862517D01*
G01Y862892D02*
X367042Y863142D01*
X366833Y863350D01*
X366583Y863433D01*
X366333Y863350D01*
X366125Y863142D01*
X366000Y862767D01*
X366042Y862392D01*
X366208Y862017D01*
G01X368000Y864783D02*
X368292Y865033D01*
X368458Y865367D01*
X368500Y865742D01*
X368458Y866075D01*
X368250Y866408D01*
X368000Y866617D01*
X367750Y866658D01*
X367458Y866575D01*
X367250Y866283D01*
X367167Y865992D01*
Y865617D01*
G01Y865992D02*
X367042Y866242D01*
X366833Y866450D01*
X366583Y866533D01*
X366333Y866450D01*
X366125Y866242D01*
X366000Y865867D01*
X366042Y865492D01*
X366208Y865117D01*
G01X378000Y875200D02*
X374000D01*
Y867800D01*
G01X373500Y875200D02*
X369500D01*
Y867800D01*
G01X373000Y880300D02*
Y911000D01*
G01Y880300D02*
X387000D01*
G01X380000Y881400D02*
X378900Y880300D01*
G01X373000Y911000D02*
X387000D01*
G01X369100Y925800D02*
Y938200D01*
G01D02*
Y925800D01*
G01X382000Y924200D02*
X378000D01*
Y916800D01*
G01X376167Y925925D02*
X376375Y926258D01*
X376500Y926633D01*
Y926967D01*
X376375Y927300D01*
X376167Y927550D01*
X375875Y927675D01*
X375583Y927592D01*
X375333Y927383D01*
X375167Y927008D01*
X375083Y926508D01*
X374917Y926217D01*
X374625Y926092D01*
X374333Y926175D01*
X374125Y926383D01*
X374000Y926675D01*
Y926967D01*
X374083Y927258D01*
X374292Y927508D01*
G01X376500Y929067D02*
X374000D01*
Y930108D01*
X374125Y930442D01*
X374292Y930650D01*
X374625Y930733D01*
X374958Y930650D01*
X375167Y930400D01*
X375292Y930108D01*
Y929067D01*
G01Y930108D02*
X376500Y930733D01*
G01X376208Y932292D02*
X376417Y932583D01*
X376500Y932917D01*
X376417Y933250D01*
X376167Y933542D01*
X375792Y933750D01*
X375417Y933833D01*
X374958D01*
X374583Y933750D01*
X374250Y933542D01*
X374083Y933292D01*
X374000Y933000D01*
X374083Y932667D01*
X374250Y932417D01*
X374500Y932250D01*
X374833Y932167D01*
X375125Y932250D01*
X375417Y932458D01*
X375583Y932708D01*
X375625Y933000D01*
X375542Y933333D01*
X375333Y933583D01*
X374958Y933833D01*
G01X376125Y935183D02*
X376333Y935433D01*
X376458Y935725D01*
X376500Y936100D01*
X376417Y936475D01*
X376250Y936767D01*
X375958Y936975D01*
X375625Y937017D01*
X375292Y936933D01*
X375083Y936725D01*
X374917Y936433D01*
X374875Y936142D01*
X374917Y935850D01*
X375083Y935475D01*
X374000Y935600D01*
Y936725D01*
G01Y939200D02*
X374083Y938867D01*
X374292Y938617D01*
X374542Y938450D01*
X374875Y938325D01*
X375250Y938283D01*
X375625Y938325D01*
X375958Y938450D01*
X376208Y938617D01*
X376417Y938867D01*
X376500Y939200D01*
X376417Y939533D01*
X376208Y939783D01*
X375958Y939950D01*
X375625Y940075D01*
X375250Y940117D01*
X374875Y940075D01*
X374542Y939950D01*
X374292Y939783D01*
X374083Y939533D01*
X374000Y939200D01*
G01X377500Y924200D02*
X373500D01*
Y916800D01*
G01X381000Y927517D02*
X378500D01*
Y928558D01*
X378625Y928892D01*
X378792Y929100D01*
X379125Y929183D01*
X379458Y929100D01*
X379667Y928850D01*
X379792Y928558D01*
Y927517D01*
G01Y928558D02*
X381000Y929183D01*
G01X379958Y930658D02*
X379667Y930950D01*
X379500Y931200D01*
X379417Y931533D01*
X379500Y931825D01*
X379667Y932033D01*
X379917Y932200D01*
X380208Y932242D01*
X380458Y932200D01*
X380708Y932033D01*
X380917Y931783D01*
X381000Y931492D01*
X380917Y931158D01*
X380667Y930867D01*
X380292Y930700D01*
X379875Y930658D01*
X379333Y930742D01*
X379042Y930867D01*
X378750Y931075D01*
X378542Y931367D01*
X378500Y931658D01*
X378583Y931950D01*
X378792Y932158D01*
G01X379958Y933758D02*
X379667Y934050D01*
X379500Y934300D01*
X379417Y934633D01*
X379500Y934925D01*
X379667Y935133D01*
X379917Y935300D01*
X380208Y935342D01*
X380458Y935300D01*
X380708Y935133D01*
X380917Y934883D01*
X381000Y934592D01*
X380917Y934258D01*
X380667Y933967D01*
X380292Y933800D01*
X379875Y933758D01*
X379333Y933842D01*
X379042Y933967D01*
X378750Y934175D01*
X378542Y934467D01*
X378500Y934758D01*
X378583Y935050D01*
X378792Y935258D01*
G01X381000Y937650D02*
X378500D01*
X379000Y937150D01*
G01X381000D02*
Y938150D01*
G01X372425Y950333D02*
X372758Y950125D01*
X373133Y950000D01*
X373467D01*
X373800Y950125D01*
X374050Y950333D01*
X374175Y950625D01*
X374092Y950917D01*
X373883Y951167D01*
X373508Y951333D01*
X373008Y951417D01*
X372717Y951583D01*
X372592Y951875D01*
X372675Y952167D01*
X372883Y952375D01*
X373175Y952500D01*
X373467D01*
X373758Y952417D01*
X374008Y952208D01*
G01X377317Y952292D02*
X377067Y952417D01*
X376775Y952500D01*
X376442D01*
X376067Y952375D01*
X375775Y952167D01*
X375567Y951917D01*
X375400Y951500D01*
X375358Y951125D01*
X375442Y950750D01*
X375567Y950500D01*
X375817Y950250D01*
X376108Y950083D01*
X376400Y950000D01*
X376692D01*
X376983Y950083D01*
X377233Y950208D01*
X377442Y950375D01*
G01X380000Y950000D02*
Y952500D01*
X378458Y950708D01*
X380542D01*
G01X381683Y950500D02*
X381933Y950208D01*
X382267Y950042D01*
X382642Y950000D01*
X382975Y950042D01*
X383308Y950250D01*
X383517Y950500D01*
X383558Y950750D01*
X383475Y951042D01*
X383183Y951250D01*
X382892Y951333D01*
X382517D01*
G01X382892D02*
X383142Y951458D01*
X383350Y951667D01*
X383433Y951917D01*
X383350Y952167D01*
X383142Y952375D01*
X382767Y952500D01*
X382392Y952458D01*
X382017Y952292D01*
G01X386200Y950000D02*
Y952500D01*
X384658Y950708D01*
X386742D01*
G01X372425Y954833D02*
X372758Y954625D01*
X373133Y954500D01*
X373467D01*
X373800Y954625D01*
X374050Y954833D01*
X374175Y955125D01*
X374092Y955417D01*
X373883Y955667D01*
X373508Y955833D01*
X373008Y955917D01*
X372717Y956083D01*
X372592Y956375D01*
X372675Y956667D01*
X372883Y956875D01*
X373175Y957000D01*
X373467D01*
X373758Y956917D01*
X374008Y956708D01*
G01X377317Y956792D02*
X377067Y956917D01*
X376775Y957000D01*
X376442D01*
X376067Y956875D01*
X375775Y956667D01*
X375567Y956417D01*
X375400Y956000D01*
X375358Y955625D01*
X375442Y955250D01*
X375567Y955000D01*
X375817Y954750D01*
X376108Y954583D01*
X376400Y954500D01*
X376692D01*
X376983Y954583D01*
X377233Y954708D01*
X377442Y954875D01*
G01X380000Y954500D02*
Y957000D01*
X378458Y955208D01*
X380542D01*
G01X381683Y955000D02*
X381933Y954708D01*
X382267Y954542D01*
X382642Y954500D01*
X382975Y954542D01*
X383308Y954750D01*
X383517Y955000D01*
X383558Y955250D01*
X383475Y955542D01*
X383183Y955750D01*
X382892Y955833D01*
X382517D01*
G01X382892D02*
X383142Y955958D01*
X383350Y956167D01*
X383433Y956417D01*
X383350Y956667D01*
X383142Y956875D01*
X382767Y957000D01*
X382392Y956958D01*
X382017Y956792D01*
G01X384783Y954875D02*
X385033Y954667D01*
X385325Y954542D01*
X385700Y954500D01*
X386075Y954583D01*
X386367Y954750D01*
X386575Y955042D01*
X386617Y955375D01*
X386533Y955708D01*
X386325Y955917D01*
X386033Y956083D01*
X385742Y956125D01*
X385450Y956083D01*
X385075Y955917D01*
X385200Y957000D01*
X386325D01*
G01X369678Y978017D02*
X367178D01*
Y979058D01*
X367303Y979392D01*
X367470Y979600D01*
X367803Y979683D01*
X368136Y979600D01*
X368345Y979350D01*
X368470Y979058D01*
Y978017D01*
G01Y979058D02*
X369678Y979683D01*
G01Y981950D02*
X367178D01*
X367678Y981450D01*
G01X369678D02*
Y982450D01*
G01Y985550D02*
X367178D01*
X368970Y984008D01*
Y986092D01*
G01X369386Y987442D02*
X369595Y987733D01*
X369678Y988067D01*
X369595Y988400D01*
X369345Y988692D01*
X368970Y988900D01*
X368595Y988983D01*
X368136D01*
X367761Y988900D01*
X367428Y988692D01*
X367261Y988442D01*
X367178Y988150D01*
X367261Y987817D01*
X367428Y987567D01*
X367678Y987400D01*
X368011Y987317D01*
X368303Y987400D01*
X368595Y987608D01*
X368761Y987858D01*
X368803Y988150D01*
X368720Y988483D01*
X368511Y988733D01*
X368136Y988983D01*
G01X375678Y987700D02*
X371678D01*
Y980300D01*
G01X393017Y9000D02*
Y6500D01*
X394683D01*
G01X397783D02*
X396117D01*
Y9000D01*
X397783D01*
G01X397117Y7792D02*
X396117D01*
G01X399133Y6500D02*
Y9000D01*
X399967D01*
X400300Y8875D01*
X400550Y8708D01*
X400758Y8458D01*
X400925Y8167D01*
X400967Y7750D01*
X400925Y7333D01*
X400758Y7042D01*
X400550Y6792D01*
X400300Y6625D01*
X399967Y6500D01*
X399133D01*
G01X402233Y6875D02*
X402483Y6667D01*
X402775Y6542D01*
X403150Y6500D01*
X403525Y6583D01*
X403817Y6750D01*
X404025Y7042D01*
X404067Y7375D01*
X403983Y7708D01*
X403775Y7917D01*
X403483Y8083D01*
X403192Y8125D01*
X402900Y8083D01*
X402525Y7917D01*
X402650Y9000D01*
X403775D01*
G01X389529Y4692D02*
Y11292D01*
G01X385254Y4692D02*
X389529D01*
G01X383500Y23500D02*
X396000D01*
Y44500D01*
X406000D01*
X403000Y47500D01*
Y41500D01*
X406000Y44500D01*
G01X389000Y34700D02*
X382000D01*
Y48100D01*
X389000D01*
Y34700D01*
G01X381000Y36200D02*
Y30700D01*
G01X395500Y49467D02*
X393000D01*
Y50467D01*
X393125Y50800D01*
X393417Y51050D01*
X393750Y51133D01*
X394083Y51050D01*
X394333Y50842D01*
X394458Y50467D01*
Y49467D01*
G01X393208Y54317D02*
X393083Y54067D01*
X393000Y53775D01*
Y53442D01*
X393125Y53067D01*
X393333Y52775D01*
X393583Y52567D01*
X394000Y52400D01*
X394375Y52358D01*
X394750Y52442D01*
X395000Y52567D01*
X395250Y52817D01*
X395417Y53108D01*
X395500Y53400D01*
Y53692D01*
X395417Y53983D01*
X395292Y54233D01*
X395125Y54442D01*
G01X393417Y55708D02*
X393167Y55958D01*
X393042Y56250D01*
X393000Y56583D01*
X393083Y57000D01*
X393292Y57292D01*
X393542Y57375D01*
X393792Y57333D01*
X394000Y57167D01*
X394417Y56333D01*
X394708Y55958D01*
X395125Y55708D01*
X395500Y55625D01*
Y57375D01*
G01X393000Y59600D02*
X393083Y59267D01*
X393292Y59017D01*
X393542Y58850D01*
X393875Y58725D01*
X394250Y58683D01*
X394625Y58725D01*
X394958Y58850D01*
X395208Y59017D01*
X395417Y59267D01*
X395500Y59600D01*
X395417Y59933D01*
X395208Y60183D01*
X394958Y60350D01*
X394625Y60475D01*
X394250Y60517D01*
X393875Y60475D01*
X393542Y60350D01*
X393292Y60183D01*
X393083Y59933D01*
X393000Y59600D01*
G01Y62700D02*
X393083Y62367D01*
X393292Y62117D01*
X393542Y61950D01*
X393875Y61825D01*
X394250Y61783D01*
X394625Y61825D01*
X394958Y61950D01*
X395208Y62117D01*
X395417Y62367D01*
X395500Y62700D01*
X395417Y63033D01*
X395208Y63283D01*
X394958Y63450D01*
X394625Y63575D01*
X394250Y63617D01*
X393875Y63575D01*
X393542Y63450D01*
X393292Y63283D01*
X393083Y63033D01*
X393000Y62700D01*
G01X381000Y48300D02*
Y42800D01*
G01X386500Y49467D02*
X384000D01*
Y50467D01*
X384125Y50800D01*
X384417Y51050D01*
X384750Y51133D01*
X385083Y51050D01*
X385333Y50842D01*
X385458Y50467D01*
Y49467D01*
G01X384208Y54317D02*
X384083Y54067D01*
X384000Y53775D01*
Y53442D01*
X384125Y53067D01*
X384333Y52775D01*
X384583Y52567D01*
X385000Y52400D01*
X385375Y52358D01*
X385750Y52442D01*
X386000Y52567D01*
X386250Y52817D01*
X386417Y53108D01*
X386500Y53400D01*
Y53692D01*
X386417Y53983D01*
X386292Y54233D01*
X386125Y54442D01*
G01X384417Y55708D02*
X384167Y55958D01*
X384042Y56250D01*
X384000Y56583D01*
X384083Y57000D01*
X384292Y57292D01*
X384542Y57375D01*
X384792Y57333D01*
X385000Y57167D01*
X385417Y56333D01*
X385708Y55958D01*
X386125Y55708D01*
X386500Y55625D01*
Y57375D01*
G01X384000Y59600D02*
X384083Y59267D01*
X384292Y59017D01*
X384542Y58850D01*
X384875Y58725D01*
X385250Y58683D01*
X385625Y58725D01*
X385958Y58850D01*
X386208Y59017D01*
X386417Y59267D01*
X386500Y59600D01*
X386417Y59933D01*
X386208Y60183D01*
X385958Y60350D01*
X385625Y60475D01*
X385250Y60517D01*
X384875Y60475D01*
X384542Y60350D01*
X384292Y60183D01*
X384083Y59933D01*
X384000Y59600D01*
G01X386500Y62700D02*
X384000D01*
X384500Y62200D01*
G01X386500D02*
Y63200D01*
G01X391000Y49467D02*
X388500D01*
Y50467D01*
X388625Y50800D01*
X388917Y51050D01*
X389250Y51133D01*
X389583Y51050D01*
X389833Y50842D01*
X389958Y50467D01*
Y49467D01*
G01X388708Y54317D02*
X388583Y54067D01*
X388500Y53775D01*
Y53442D01*
X388625Y53067D01*
X388833Y52775D01*
X389083Y52567D01*
X389500Y52400D01*
X389875Y52358D01*
X390250Y52442D01*
X390500Y52567D01*
X390750Y52817D01*
X390917Y53108D01*
X391000Y53400D01*
Y53692D01*
X390917Y53983D01*
X390792Y54233D01*
X390625Y54442D01*
G01X388917Y55708D02*
X388667Y55958D01*
X388542Y56250D01*
X388500Y56583D01*
X388583Y57000D01*
X388792Y57292D01*
X389042Y57375D01*
X389292Y57333D01*
X389500Y57167D01*
X389917Y56333D01*
X390208Y55958D01*
X390625Y55708D01*
X391000Y55625D01*
Y57375D01*
G01X388500Y59600D02*
X388583Y59267D01*
X388792Y59017D01*
X389042Y58850D01*
X389375Y58725D01*
X389750Y58683D01*
X390125Y58725D01*
X390458Y58850D01*
X390708Y59017D01*
X390917Y59267D01*
X391000Y59600D01*
X390917Y59933D01*
X390708Y60183D01*
X390458Y60350D01*
X390125Y60475D01*
X389750Y60517D01*
X389375Y60475D01*
X389042Y60350D01*
X388792Y60183D01*
X388583Y59933D01*
X388500Y59600D01*
G01X390500Y61783D02*
X390792Y62033D01*
X390958Y62367D01*
X391000Y62742D01*
X390958Y63075D01*
X390750Y63408D01*
X390500Y63617D01*
X390250Y63658D01*
X389958Y63575D01*
X389750Y63283D01*
X389667Y62992D01*
Y62617D01*
G01Y62992D02*
X389542Y63242D01*
X389333Y63450D01*
X389083Y63533D01*
X388833Y63450D01*
X388625Y63242D01*
X388500Y62867D01*
X388542Y62492D01*
X388708Y62117D01*
G01X386425Y65333D02*
X386758Y65125D01*
X387133Y65000D01*
X387467D01*
X387800Y65125D01*
X388050Y65333D01*
X388175Y65625D01*
X388092Y65917D01*
X387883Y66167D01*
X387508Y66333D01*
X387008Y66417D01*
X386717Y66583D01*
X386592Y66875D01*
X386675Y67167D01*
X386883Y67375D01*
X387175Y67500D01*
X387467D01*
X387758Y67417D01*
X388008Y67208D01*
G01X391317Y67292D02*
X391067Y67417D01*
X390775Y67500D01*
X390442D01*
X390067Y67375D01*
X389775Y67167D01*
X389567Y66917D01*
X389400Y66500D01*
X389358Y66125D01*
X389442Y65750D01*
X389567Y65500D01*
X389817Y65250D01*
X390108Y65083D01*
X390400Y65000D01*
X390692D01*
X390983Y65083D01*
X391233Y65208D01*
X391442Y65375D01*
G01X392792Y65292D02*
X393083Y65083D01*
X393417Y65000D01*
X393750Y65083D01*
X394042Y65333D01*
X394250Y65708D01*
X394333Y66083D01*
Y66542D01*
X394250Y66917D01*
X394042Y67250D01*
X393792Y67417D01*
X393500Y67500D01*
X393167Y67417D01*
X392917Y67250D01*
X392750Y67000D01*
X392667Y66667D01*
X392750Y66375D01*
X392958Y66083D01*
X393208Y65917D01*
X393500Y65875D01*
X393833Y65958D01*
X394083Y66167D01*
X394333Y66542D01*
G01X397100Y65000D02*
Y67500D01*
X395558Y65708D01*
X397642D01*
G01X398783Y65375D02*
X399033Y65167D01*
X399325Y65042D01*
X399700Y65000D01*
X400075Y65083D01*
X400367Y65250D01*
X400575Y65542D01*
X400617Y65875D01*
X400533Y66208D01*
X400325Y66417D01*
X400033Y66583D01*
X399742Y66625D01*
X399450Y66583D01*
X399075Y66417D01*
X399200Y67500D01*
X400325D01*
G01X386425Y69833D02*
X386758Y69625D01*
X387133Y69500D01*
X387467D01*
X387800Y69625D01*
X388050Y69833D01*
X388175Y70125D01*
X388092Y70417D01*
X387883Y70667D01*
X387508Y70833D01*
X387008Y70917D01*
X386717Y71083D01*
X386592Y71375D01*
X386675Y71667D01*
X386883Y71875D01*
X387175Y72000D01*
X387467D01*
X387758Y71917D01*
X388008Y71708D01*
G01X391317Y71792D02*
X391067Y71917D01*
X390775Y72000D01*
X390442D01*
X390067Y71875D01*
X389775Y71667D01*
X389567Y71417D01*
X389400Y71000D01*
X389358Y70625D01*
X389442Y70250D01*
X389567Y70000D01*
X389817Y69750D01*
X390108Y69583D01*
X390400Y69500D01*
X390692D01*
X390983Y69583D01*
X391233Y69708D01*
X391442Y69875D01*
G01X392792Y69792D02*
X393083Y69583D01*
X393417Y69500D01*
X393750Y69583D01*
X394042Y69833D01*
X394250Y70208D01*
X394333Y70583D01*
Y71042D01*
X394250Y71417D01*
X394042Y71750D01*
X393792Y71917D01*
X393500Y72000D01*
X393167Y71917D01*
X392917Y71750D01*
X392750Y71500D01*
X392667Y71167D01*
X392750Y70875D01*
X392958Y70583D01*
X393208Y70417D01*
X393500Y70375D01*
X393833Y70458D01*
X394083Y70667D01*
X394333Y71042D01*
G01X397100Y69500D02*
Y72000D01*
X395558Y70208D01*
X397642D01*
G01X398908Y70542D02*
X399200Y70833D01*
X399450Y71000D01*
X399783Y71083D01*
X400075Y71000D01*
X400283Y70833D01*
X400450Y70583D01*
X400492Y70292D01*
X400450Y70042D01*
X400283Y69792D01*
X400033Y69583D01*
X399742Y69500D01*
X399408Y69583D01*
X399117Y69833D01*
X398950Y70208D01*
X398908Y70625D01*
X398992Y71167D01*
X399117Y71458D01*
X399325Y71750D01*
X399617Y71958D01*
X399908Y72000D01*
X400200Y71917D01*
X400408Y71708D01*
G01X384467Y82500D02*
Y85000D01*
X385467D01*
X385800Y84875D01*
X386050Y84583D01*
X386133Y84250D01*
X386050Y83917D01*
X385842Y83667D01*
X385467Y83542D01*
X384467D01*
G01X387567Y82500D02*
Y85000D01*
X388608D01*
X388942Y84875D01*
X389150Y84708D01*
X389233Y84375D01*
X389150Y84042D01*
X388900Y83833D01*
X388608Y83708D01*
X387567D01*
G01X388608D02*
X389233Y82500D01*
G01X391500D02*
Y85000D01*
X391000Y84500D01*
G01Y82500D02*
X392000D01*
G01X394600D02*
X394892Y82542D01*
X395225Y82667D01*
X395433Y82875D01*
X395517Y83167D01*
X395433Y83458D01*
X395183Y83708D01*
X394808Y83833D01*
X394392D01*
X394142Y83917D01*
X393933Y84125D01*
X393850Y84417D01*
X393975Y84708D01*
X394267Y84917D01*
X394600Y85000D01*
X394933Y84917D01*
X395225Y84708D01*
X395350Y84417D01*
X395267Y84125D01*
X395058Y83917D01*
X394808Y83833D01*
X394392D01*
X394017Y83708D01*
X393767Y83458D01*
X393683Y83167D01*
X393767Y82875D01*
X393975Y82667D01*
X394308Y82542D01*
X394600Y82500D01*
G01X396783Y83000D02*
X397033Y82708D01*
X397367Y82542D01*
X397742Y82500D01*
X398075Y82542D01*
X398408Y82750D01*
X398617Y83000D01*
X398658Y83250D01*
X398575Y83542D01*
X398283Y83750D01*
X397992Y83833D01*
X397617D01*
G01X397992D02*
X398242Y83958D01*
X398450Y84167D01*
X398533Y84417D01*
X398450Y84667D01*
X398242Y84875D01*
X397867Y85000D01*
X397492Y84958D01*
X397117Y84792D01*
G01X384467Y78000D02*
Y80500D01*
X385467D01*
X385800Y80375D01*
X386050Y80083D01*
X386133Y79750D01*
X386050Y79417D01*
X385842Y79167D01*
X385467Y79042D01*
X384467D01*
G01X389317Y80292D02*
X389067Y80417D01*
X388775Y80500D01*
X388442D01*
X388067Y80375D01*
X387775Y80167D01*
X387567Y79917D01*
X387400Y79500D01*
X387358Y79125D01*
X387442Y78750D01*
X387567Y78500D01*
X387817Y78250D01*
X388108Y78083D01*
X388400Y78000D01*
X388692D01*
X388983Y78083D01*
X389233Y78208D01*
X389442Y78375D01*
G01X390708Y80083D02*
X390958Y80333D01*
X391250Y80458D01*
X391583Y80500D01*
X392000Y80417D01*
X392292Y80208D01*
X392375Y79958D01*
X392333Y79708D01*
X392167Y79500D01*
X391333Y79083D01*
X390958Y78792D01*
X390708Y78375D01*
X390625Y78000D01*
X392375D01*
G01X394600D02*
Y80500D01*
X394100Y80000D01*
G01Y78000D02*
X395100D01*
G01X396992Y78292D02*
X397283Y78083D01*
X397617Y78000D01*
X397950Y78083D01*
X398242Y78333D01*
X398450Y78708D01*
X398533Y79083D01*
Y79542D01*
X398450Y79917D01*
X398242Y80250D01*
X397992Y80417D01*
X397700Y80500D01*
X397367Y80417D01*
X397117Y80250D01*
X396950Y80000D01*
X396867Y79667D01*
X396950Y79375D01*
X397158Y79083D01*
X397408Y78917D01*
X397700Y78875D01*
X398033Y78958D01*
X398283Y79167D01*
X398533Y79542D01*
G01X388500Y91967D02*
X386000D01*
Y92967D01*
X386125Y93300D01*
X386417Y93550D01*
X386750Y93633D01*
X387083Y93550D01*
X387333Y93342D01*
X387458Y92967D01*
Y91967D01*
G01X388500Y95067D02*
X386000D01*
Y96108D01*
X386125Y96442D01*
X386292Y96650D01*
X386625Y96733D01*
X386958Y96650D01*
X387167Y96400D01*
X387292Y96108D01*
Y95067D01*
G01Y96108D02*
X388500Y96733D01*
G01Y99000D02*
X386000D01*
X386500Y98500D01*
G01X388500D02*
Y99500D01*
G01Y102100D02*
X388458Y102392D01*
X388333Y102725D01*
X388125Y102933D01*
X387833Y103017D01*
X387542Y102933D01*
X387292Y102683D01*
X387167Y102308D01*
Y101892D01*
X387083Y101642D01*
X386875Y101433D01*
X386583Y101350D01*
X386292Y101475D01*
X386083Y101767D01*
X386000Y102100D01*
X386083Y102433D01*
X386292Y102725D01*
X386583Y102850D01*
X386875Y102767D01*
X387083Y102558D01*
X387167Y102308D01*
Y101892D01*
X387292Y101517D01*
X387542Y101267D01*
X387833Y101183D01*
X388125Y101267D01*
X388333Y101475D01*
X388458Y101808D01*
X388500Y102100D01*
G01Y105200D02*
X388458Y105492D01*
X388333Y105825D01*
X388125Y106033D01*
X387833Y106117D01*
X387542Y106033D01*
X387292Y105783D01*
X387167Y105408D01*
Y104992D01*
X387083Y104742D01*
X386875Y104533D01*
X386583Y104450D01*
X386292Y104575D01*
X386083Y104867D01*
X386000Y105200D01*
X386083Y105533D01*
X386292Y105825D01*
X386583Y105950D01*
X386875Y105867D01*
X387083Y105658D01*
X387167Y105408D01*
Y104992D01*
X387292Y104617D01*
X387542Y104367D01*
X387833Y104283D01*
X388125Y104367D01*
X388333Y104575D01*
X388458Y104908D01*
X388500Y105200D01*
G01X396500Y91967D02*
X394000D01*
Y92967D01*
X394125Y93300D01*
X394417Y93550D01*
X394750Y93633D01*
X395083Y93550D01*
X395333Y93342D01*
X395458Y92967D01*
Y91967D01*
G01X396500Y95067D02*
X394000D01*
Y96108D01*
X394125Y96442D01*
X394292Y96650D01*
X394625Y96733D01*
X394958Y96650D01*
X395167Y96400D01*
X395292Y96108D01*
Y95067D01*
G01Y96108D02*
X396500Y96733D01*
G01Y99000D02*
X394000D01*
X394500Y98500D01*
G01X396500D02*
Y99500D01*
G01Y102100D02*
X396458Y102392D01*
X396333Y102725D01*
X396125Y102933D01*
X395833Y103017D01*
X395542Y102933D01*
X395292Y102683D01*
X395167Y102308D01*
Y101892D01*
X395083Y101642D01*
X394875Y101433D01*
X394583Y101350D01*
X394292Y101475D01*
X394083Y101767D01*
X394000Y102100D01*
X394083Y102433D01*
X394292Y102725D01*
X394583Y102850D01*
X394875Y102767D01*
X395083Y102558D01*
X395167Y102308D01*
Y101892D01*
X395292Y101517D01*
X395542Y101267D01*
X395833Y101183D01*
X396125Y101267D01*
X396333Y101475D01*
X396458Y101808D01*
X396500Y102100D01*
G01Y105200D02*
X394000D01*
X394500Y104700D01*
G01X396500D02*
Y105700D01*
G01X392500Y91967D02*
X390000D01*
Y92967D01*
X390125Y93300D01*
X390417Y93550D01*
X390750Y93633D01*
X391083Y93550D01*
X391333Y93342D01*
X391458Y92967D01*
Y91967D01*
G01X390208Y96817D02*
X390083Y96567D01*
X390000Y96275D01*
Y95942D01*
X390125Y95567D01*
X390333Y95275D01*
X390583Y95067D01*
X391000Y94900D01*
X391375Y94858D01*
X391750Y94942D01*
X392000Y95067D01*
X392250Y95317D01*
X392417Y95608D01*
X392500Y95900D01*
Y96192D01*
X392417Y96483D01*
X392292Y96733D01*
X392125Y96942D01*
G01X390417Y98208D02*
X390167Y98458D01*
X390042Y98750D01*
X390000Y99083D01*
X390083Y99500D01*
X390292Y99792D01*
X390542Y99875D01*
X390792Y99833D01*
X391000Y99667D01*
X391417Y98833D01*
X391708Y98458D01*
X392125Y98208D01*
X392500Y98125D01*
Y99875D01*
G01Y102100D02*
X390000D01*
X390500Y101600D01*
G01X392500D02*
Y102600D01*
G01Y105117D02*
X391958Y105200D01*
X391500Y105325D01*
X391083Y105492D01*
X390625Y105700D01*
X390000Y106033D01*
Y104367D01*
G01X384000Y91967D02*
X381500D01*
Y92967D01*
X381625Y93300D01*
X381917Y93550D01*
X382250Y93633D01*
X382583Y93550D01*
X382833Y93342D01*
X382958Y92967D01*
Y91967D01*
G01X381708Y96817D02*
X381583Y96567D01*
X381500Y96275D01*
Y95942D01*
X381625Y95567D01*
X381833Y95275D01*
X382083Y95067D01*
X382500Y94900D01*
X382875Y94858D01*
X383250Y94942D01*
X383500Y95067D01*
X383750Y95317D01*
X383917Y95608D01*
X384000Y95900D01*
Y96192D01*
X383917Y96483D01*
X383792Y96733D01*
X383625Y96942D01*
G01X381917Y98208D02*
X381667Y98458D01*
X381542Y98750D01*
X381500Y99083D01*
X381583Y99500D01*
X381792Y99792D01*
X382042Y99875D01*
X382292Y99833D01*
X382500Y99667D01*
X382917Y98833D01*
X383208Y98458D01*
X383625Y98208D01*
X384000Y98125D01*
Y99875D01*
G01X381917Y101308D02*
X381667Y101558D01*
X381542Y101850D01*
X381500Y102183D01*
X381583Y102600D01*
X381792Y102892D01*
X382042Y102975D01*
X382292Y102933D01*
X382500Y102767D01*
X382917Y101933D01*
X383208Y101558D01*
X383625Y101308D01*
X384000Y101225D01*
Y102975D01*
G01Y105200D02*
X381500D01*
X382000Y104700D01*
G01X384000D02*
Y105700D01*
G01X386525Y117333D02*
X386858Y117125D01*
X387233Y117000D01*
X387567D01*
X387900Y117125D01*
X388150Y117333D01*
X388275Y117625D01*
X388192Y117917D01*
X387983Y118167D01*
X387608Y118333D01*
X387108Y118417D01*
X386817Y118583D01*
X386692Y118875D01*
X386775Y119167D01*
X386983Y119375D01*
X387275Y119500D01*
X387567D01*
X387858Y119417D01*
X388108Y119208D01*
G01X389583Y119500D02*
Y117708D01*
X389750Y117333D01*
X390083Y117083D01*
X390500Y117000D01*
X390917Y117083D01*
X391250Y117333D01*
X391417Y117708D01*
Y119500D01*
G01X392808Y119083D02*
X393058Y119333D01*
X393350Y119458D01*
X393683Y119500D01*
X394100Y119417D01*
X394392Y119208D01*
X394475Y118958D01*
X394433Y118708D01*
X394267Y118500D01*
X393433Y118083D01*
X393058Y117792D01*
X392808Y117375D01*
X392725Y117000D01*
X394475D01*
G01X398929Y259200D02*
X394929D01*
Y251800D01*
G01X382479Y248050D02*
Y245050D01*
X385479D01*
G01X394379Y248050D02*
Y245050D01*
X391379D01*
G01X388429Y246050D02*
Y244050D01*
G01X407200Y274900D02*
Y267900D01*
X393800D01*
Y274900D01*
X407200D01*
G01X390167Y261425D02*
X390375Y261758D01*
X390500Y262133D01*
Y262467D01*
X390375Y262800D01*
X390167Y263050D01*
X389875Y263175D01*
X389583Y263092D01*
X389333Y262883D01*
X389167Y262508D01*
X389083Y262008D01*
X388917Y261717D01*
X388625Y261592D01*
X388333Y261675D01*
X388125Y261883D01*
X388000Y262175D01*
Y262467D01*
X388083Y262758D01*
X388292Y263008D01*
G01X390500Y264567D02*
X388000D01*
Y265608D01*
X388125Y265942D01*
X388292Y266150D01*
X388625Y266233D01*
X388958Y266150D01*
X389167Y265900D01*
X389292Y265608D01*
Y264567D01*
G01Y265608D02*
X390500Y266233D01*
G01X389458Y267708D02*
X389167Y268000D01*
X389000Y268250D01*
X388917Y268583D01*
X389000Y268875D01*
X389167Y269083D01*
X389417Y269250D01*
X389708Y269292D01*
X389958Y269250D01*
X390208Y269083D01*
X390417Y268833D01*
X390500Y268542D01*
X390417Y268208D01*
X390167Y267917D01*
X389792Y267750D01*
X389375Y267708D01*
X388833Y267792D01*
X388542Y267917D01*
X388250Y268125D01*
X388042Y268417D01*
X388000Y268708D01*
X388083Y269000D01*
X388292Y269208D01*
G01X390500Y272100D02*
X388000D01*
X389792Y270558D01*
Y272642D01*
G01X390500Y274700D02*
X390458Y274992D01*
X390333Y275325D01*
X390125Y275533D01*
X389833Y275617D01*
X389542Y275533D01*
X389292Y275283D01*
X389167Y274908D01*
Y274492D01*
X389083Y274242D01*
X388875Y274033D01*
X388583Y273950D01*
X388292Y274075D01*
X388083Y274367D01*
X388000Y274700D01*
X388083Y275033D01*
X388292Y275325D01*
X388583Y275450D01*
X388875Y275367D01*
X389083Y275158D01*
X389167Y274908D01*
Y274492D01*
X389292Y274117D01*
X389542Y273867D01*
X389833Y273783D01*
X390125Y273867D01*
X390333Y274075D01*
X390458Y274408D01*
X390500Y274700D01*
G01X385667Y261475D02*
X385875Y261808D01*
X386000Y262183D01*
Y262517D01*
X385875Y262850D01*
X385667Y263100D01*
X385375Y263225D01*
X385083Y263142D01*
X384833Y262933D01*
X384667Y262558D01*
X384583Y262058D01*
X384417Y261767D01*
X384125Y261642D01*
X383833Y261725D01*
X383625Y261933D01*
X383500Y262225D01*
Y262517D01*
X383583Y262808D01*
X383792Y263058D01*
G01X383500Y264533D02*
X385292D01*
X385667Y264700D01*
X385917Y265033D01*
X386000Y265450D01*
X385917Y265867D01*
X385667Y266200D01*
X385292Y266367D01*
X383500D01*
G01X385625Y267633D02*
X385833Y267883D01*
X385958Y268175D01*
X386000Y268550D01*
X385917Y268925D01*
X385750Y269217D01*
X385458Y269425D01*
X385125Y269467D01*
X384792Y269383D01*
X384583Y269175D01*
X384417Y268883D01*
X384375Y268592D01*
X384417Y268300D01*
X384583Y267925D01*
X383500Y268050D01*
Y269175D01*
G01X386000Y271567D02*
X385458Y271650D01*
X385000Y271775D01*
X384583Y271942D01*
X384125Y272150D01*
X383500Y272483D01*
Y270817D01*
G01X382479Y255950D02*
Y258950D01*
X385479D01*
G01X391025Y284833D02*
X391358Y284625D01*
X391733Y284500D01*
X392067D01*
X392400Y284625D01*
X392650Y284833D01*
X392775Y285125D01*
X392692Y285417D01*
X392483Y285667D01*
X392108Y285833D01*
X391608Y285917D01*
X391317Y286083D01*
X391192Y286375D01*
X391275Y286667D01*
X391483Y286875D01*
X391775Y287000D01*
X392067D01*
X392358Y286917D01*
X392608Y286708D01*
G01X394167Y287000D02*
Y284500D01*
X395833D01*
G01X397183Y285000D02*
X397433Y284708D01*
X397767Y284542D01*
X398142Y284500D01*
X398475Y284542D01*
X398808Y284750D01*
X399017Y285000D01*
X399058Y285250D01*
X398975Y285542D01*
X398683Y285750D01*
X398392Y285833D01*
X398017D01*
G01X398392D02*
X398642Y285958D01*
X398850Y286167D01*
X398933Y286417D01*
X398850Y286667D01*
X398642Y286875D01*
X398267Y287000D01*
X397892Y286958D01*
X397517Y286792D01*
G01X394925Y276833D02*
X395258Y276625D01*
X395633Y276500D01*
X395967D01*
X396300Y276625D01*
X396550Y276833D01*
X396675Y277125D01*
X396592Y277417D01*
X396383Y277667D01*
X396008Y277833D01*
X395508Y277917D01*
X395217Y278083D01*
X395092Y278375D01*
X395175Y278667D01*
X395383Y278875D01*
X395675Y279000D01*
X395967D01*
X396258Y278917D01*
X396508Y278708D01*
G01X398067Y276500D02*
Y279000D01*
X399108D01*
X399442Y278875D01*
X399650Y278708D01*
X399733Y278375D01*
X399650Y278042D01*
X399400Y277833D01*
X399108Y277708D01*
X398067D01*
G01X399108D02*
X399733Y276500D01*
G01X401917D02*
X402000Y277042D01*
X402125Y277500D01*
X402292Y277917D01*
X402500Y278375D01*
X402833Y279000D01*
X401167D01*
G01X405100D02*
X404767Y278917D01*
X404517Y278708D01*
X404350Y278458D01*
X404225Y278125D01*
X404183Y277750D01*
X404225Y277375D01*
X404350Y277042D01*
X404517Y276792D01*
X404767Y276583D01*
X405100Y276500D01*
X405433Y276583D01*
X405683Y276792D01*
X405850Y277042D01*
X405975Y277375D01*
X406017Y277750D01*
X405975Y278125D01*
X405850Y278458D01*
X405683Y278708D01*
X405433Y278917D01*
X405100Y279000D01*
G01X407492Y276792D02*
X407783Y276583D01*
X408117Y276500D01*
X408450Y276583D01*
X408742Y276833D01*
X408950Y277208D01*
X409033Y277583D01*
Y278042D01*
X408950Y278417D01*
X408742Y278750D01*
X408492Y278917D01*
X408200Y279000D01*
X407867Y278917D01*
X407617Y278750D01*
X407450Y278500D01*
X407367Y278167D01*
X407450Y277875D01*
X407658Y277583D01*
X407908Y277417D01*
X408200Y277375D01*
X408533Y277458D01*
X408783Y277667D01*
X409033Y278042D01*
G01X386000Y309000D02*
X382500D01*
Y293000D01*
X410500D01*
Y272500D01*
G01X388555Y304700D02*
X384555D01*
Y297300D01*
G01X389055D02*
X393055D01*
Y304700D01*
G01X397555D02*
X393555D01*
Y297300D01*
G01X393500Y312500D02*
X387500D01*
Y311000D01*
G01X393667Y321875D02*
X393875Y322208D01*
X394000Y322583D01*
Y322917D01*
X393875Y323250D01*
X393667Y323500D01*
X393375Y323625D01*
X393083Y323542D01*
X392833Y323333D01*
X392667Y322958D01*
X392583Y322458D01*
X392417Y322167D01*
X392125Y322042D01*
X391833Y322125D01*
X391625Y322333D01*
X391500Y322625D01*
Y322917D01*
X391583Y323208D01*
X391792Y323458D01*
G01X391500Y325850D02*
X394000D01*
G01X391500Y324892D02*
Y326808D01*
G01X394000Y328117D02*
X391500D01*
Y329117D01*
X391625Y329450D01*
X391917Y329700D01*
X392250Y329783D01*
X392583Y329700D01*
X392833Y329492D01*
X392958Y329117D01*
Y328117D01*
G01X394000Y332050D02*
X391500D01*
X392000Y331550D01*
G01X394000D02*
Y332550D01*
G01X391500Y335150D02*
X391583Y334817D01*
X391792Y334567D01*
X392042Y334400D01*
X392375Y334275D01*
X392750Y334233D01*
X393125Y334275D01*
X393458Y334400D01*
X393708Y334567D01*
X393917Y334817D01*
X394000Y335150D01*
X393917Y335483D01*
X393708Y335733D01*
X393458Y335900D01*
X393125Y336025D01*
X392750Y336067D01*
X392375Y336025D01*
X392042Y335900D01*
X391792Y335733D01*
X391583Y335483D01*
X391500Y335150D01*
G01Y338250D02*
X391583Y337917D01*
X391792Y337667D01*
X392042Y337500D01*
X392375Y337375D01*
X392750Y337333D01*
X393125Y337375D01*
X393458Y337500D01*
X393708Y337667D01*
X393917Y337917D01*
X394000Y338250D01*
X393917Y338583D01*
X393708Y338833D01*
X393458Y339000D01*
X393125Y339125D01*
X392750Y339167D01*
X392375Y339125D01*
X392042Y339000D01*
X391792Y338833D01*
X391583Y338583D01*
X391500Y338250D01*
G01X389667Y337875D02*
X389875Y338208D01*
X390000Y338583D01*
Y338917D01*
X389875Y339250D01*
X389667Y339500D01*
X389375Y339625D01*
X389083Y339542D01*
X388833Y339333D01*
X388667Y338958D01*
X388583Y338458D01*
X388417Y338167D01*
X388125Y338042D01*
X387833Y338125D01*
X387625Y338333D01*
X387500Y338625D01*
Y338917D01*
X387583Y339208D01*
X387792Y339458D01*
G01X387500Y341850D02*
X390000D01*
G01X387500Y340892D02*
Y342808D01*
G01X390000Y344117D02*
X387500D01*
Y345117D01*
X387625Y345450D01*
X387917Y345700D01*
X388250Y345783D01*
X388583Y345700D01*
X388833Y345492D01*
X388958Y345117D01*
Y344117D01*
G01X390000Y348050D02*
X387500D01*
X388000Y347550D01*
G01X390000D02*
Y348550D01*
G01Y351650D02*
X387500D01*
X389292Y350108D01*
Y352192D01*
G01X390000Y354750D02*
X387500D01*
X389292Y353208D01*
Y355292D01*
G01X382425Y365833D02*
X382758Y365625D01*
X383133Y365500D01*
X383467D01*
X383800Y365625D01*
X384050Y365833D01*
X384175Y366125D01*
X384092Y366417D01*
X383883Y366667D01*
X383508Y366833D01*
X383008Y366917D01*
X382717Y367083D01*
X382592Y367375D01*
X382675Y367667D01*
X382883Y367875D01*
X383175Y368000D01*
X383467D01*
X383758Y367917D01*
X384008Y367708D01*
G01X385567Y365500D02*
Y368000D01*
X386608D01*
X386942Y367875D01*
X387150Y367708D01*
X387233Y367375D01*
X387150Y367042D01*
X386900Y366833D01*
X386608Y366708D01*
X385567D01*
G01X386608D02*
X387233Y365500D01*
G01X389500D02*
X389792Y365542D01*
X390125Y365667D01*
X390333Y365875D01*
X390417Y366167D01*
X390333Y366458D01*
X390083Y366708D01*
X389708Y366833D01*
X389292D01*
X389042Y366917D01*
X388833Y367125D01*
X388750Y367417D01*
X388875Y367708D01*
X389167Y367917D01*
X389500Y368000D01*
X389833Y367917D01*
X390125Y367708D01*
X390250Y367417D01*
X390167Y367125D01*
X389958Y366917D01*
X389708Y366833D01*
X389292D01*
X388917Y366708D01*
X388667Y366458D01*
X388583Y366167D01*
X388667Y365875D01*
X388875Y365667D01*
X389208Y365542D01*
X389500Y365500D01*
G01X392600D02*
Y368000D01*
X392100Y367500D01*
G01Y365500D02*
X393100D01*
G01X396200D02*
Y368000D01*
X394658Y366208D01*
X396742D01*
G01X382425Y357833D02*
X382758Y357625D01*
X383133Y357500D01*
X383467D01*
X383800Y357625D01*
X384050Y357833D01*
X384175Y358125D01*
X384092Y358417D01*
X383883Y358667D01*
X383508Y358833D01*
X383008Y358917D01*
X382717Y359083D01*
X382592Y359375D01*
X382675Y359667D01*
X382883Y359875D01*
X383175Y360000D01*
X383467D01*
X383758Y359917D01*
X384008Y359708D01*
G01X385567Y357500D02*
Y360000D01*
X386608D01*
X386942Y359875D01*
X387150Y359708D01*
X387233Y359375D01*
X387150Y359042D01*
X386900Y358833D01*
X386608Y358708D01*
X385567D01*
G01X386608D02*
X387233Y357500D01*
G01X389417D02*
X389500Y358042D01*
X389625Y358500D01*
X389792Y358917D01*
X390000Y359375D01*
X390333Y360000D01*
X388667D01*
G01X391892Y357792D02*
X392183Y357583D01*
X392517Y357500D01*
X392850Y357583D01*
X393142Y357833D01*
X393350Y358208D01*
X393433Y358583D01*
Y359042D01*
X393350Y359417D01*
X393142Y359750D01*
X392892Y359917D01*
X392600Y360000D01*
X392267Y359917D01*
X392017Y359750D01*
X391850Y359500D01*
X391767Y359167D01*
X391850Y358875D01*
X392058Y358583D01*
X392308Y358417D01*
X392600Y358375D01*
X392933Y358458D01*
X393183Y358667D01*
X393433Y359042D01*
G01X394908Y358542D02*
X395200Y358833D01*
X395450Y359000D01*
X395783Y359083D01*
X396075Y359000D01*
X396283Y358833D01*
X396450Y358583D01*
X396492Y358292D01*
X396450Y358042D01*
X396283Y357792D01*
X396033Y357583D01*
X395742Y357500D01*
X395408Y357583D01*
X395117Y357833D01*
X394950Y358208D01*
X394908Y358625D01*
X394992Y359167D01*
X395117Y359458D01*
X395325Y359750D01*
X395617Y359958D01*
X395908Y360000D01*
X396200Y359917D01*
X396408Y359708D01*
G01X382425Y361833D02*
X382758Y361625D01*
X383133Y361500D01*
X383467D01*
X383800Y361625D01*
X384050Y361833D01*
X384175Y362125D01*
X384092Y362417D01*
X383883Y362667D01*
X383508Y362833D01*
X383008Y362917D01*
X382717Y363083D01*
X382592Y363375D01*
X382675Y363667D01*
X382883Y363875D01*
X383175Y364000D01*
X383467D01*
X383758Y363917D01*
X384008Y363708D01*
G01X385567Y361500D02*
Y364000D01*
X386608D01*
X386942Y363875D01*
X387150Y363708D01*
X387233Y363375D01*
X387150Y363042D01*
X386900Y362833D01*
X386608Y362708D01*
X385567D01*
G01X386608D02*
X387233Y361500D01*
G01X389417D02*
X389500Y362042D01*
X389625Y362500D01*
X389792Y362917D01*
X390000Y363375D01*
X390333Y364000D01*
X388667D01*
G01X392517Y361500D02*
X392600Y362042D01*
X392725Y362500D01*
X392892Y362917D01*
X393100Y363375D01*
X393433Y364000D01*
X391767D01*
G01X396200Y361500D02*
Y364000D01*
X394658Y362208D01*
X396742D01*
G01X392167Y369425D02*
X392375Y369758D01*
X392500Y370133D01*
Y370467D01*
X392375Y370800D01*
X392167Y371050D01*
X391875Y371175D01*
X391583Y371092D01*
X391333Y370883D01*
X391167Y370508D01*
X391083Y370008D01*
X390917Y369717D01*
X390625Y369592D01*
X390333Y369675D01*
X390125Y369883D01*
X390000Y370175D01*
Y370467D01*
X390083Y370758D01*
X390292Y371008D01*
G01X392500Y372567D02*
X390000D01*
Y373608D01*
X390125Y373942D01*
X390292Y374150D01*
X390625Y374233D01*
X390958Y374150D01*
X391167Y373900D01*
X391292Y373608D01*
Y372567D01*
G01Y373608D02*
X392500Y374233D01*
G01Y376500D02*
X392458Y376792D01*
X392333Y377125D01*
X392125Y377333D01*
X391833Y377417D01*
X391542Y377333D01*
X391292Y377083D01*
X391167Y376708D01*
Y376292D01*
X391083Y376042D01*
X390875Y375833D01*
X390583Y375750D01*
X390292Y375875D01*
X390083Y376167D01*
X390000Y376500D01*
X390083Y376833D01*
X390292Y377125D01*
X390583Y377250D01*
X390875Y377167D01*
X391083Y376958D01*
X391167Y376708D01*
Y376292D01*
X391292Y375917D01*
X391542Y375667D01*
X391833Y375583D01*
X392125Y375667D01*
X392333Y375875D01*
X392458Y376208D01*
X392500Y376500D01*
G01X390000Y379600D02*
X390083Y379267D01*
X390292Y379017D01*
X390542Y378850D01*
X390875Y378725D01*
X391250Y378683D01*
X391625Y378725D01*
X391958Y378850D01*
X392208Y379017D01*
X392417Y379267D01*
X392500Y379600D01*
X392417Y379933D01*
X392208Y380183D01*
X391958Y380350D01*
X391625Y380475D01*
X391250Y380517D01*
X390875Y380475D01*
X390542Y380350D01*
X390292Y380183D01*
X390083Y379933D01*
X390000Y379600D01*
G01X391458Y381908D02*
X391167Y382200D01*
X391000Y382450D01*
X390917Y382783D01*
X391000Y383075D01*
X391167Y383283D01*
X391417Y383450D01*
X391708Y383492D01*
X391958Y383450D01*
X392208Y383283D01*
X392417Y383033D01*
X392500Y382742D01*
X392417Y382408D01*
X392167Y382117D01*
X391792Y381950D01*
X391375Y381908D01*
X390833Y381992D01*
X390542Y382117D01*
X390250Y382325D01*
X390042Y382617D01*
X390000Y382908D01*
X390083Y383200D01*
X390292Y383408D01*
G01X392167Y387425D02*
X392375Y387758D01*
X392500Y388133D01*
Y388467D01*
X392375Y388800D01*
X392167Y389050D01*
X391875Y389175D01*
X391583Y389092D01*
X391333Y388883D01*
X391167Y388508D01*
X391083Y388008D01*
X390917Y387717D01*
X390625Y387592D01*
X390333Y387675D01*
X390125Y387883D01*
X390000Y388175D01*
Y388467D01*
X390083Y388758D01*
X390292Y389008D01*
G01X390000Y391400D02*
X392500D01*
G01X390000Y390442D02*
Y392358D01*
G01X392500Y393667D02*
X390000D01*
Y394667D01*
X390125Y395000D01*
X390417Y395250D01*
X390750Y395333D01*
X391083Y395250D01*
X391333Y395042D01*
X391458Y394667D01*
Y393667D01*
G01X392208Y396892D02*
X392417Y397183D01*
X392500Y397517D01*
X392417Y397850D01*
X392167Y398142D01*
X391792Y398350D01*
X391417Y398433D01*
X390958D01*
X390583Y398350D01*
X390250Y398142D01*
X390083Y397892D01*
X390000Y397600D01*
X390083Y397267D01*
X390250Y397017D01*
X390500Y396850D01*
X390833Y396767D01*
X391125Y396850D01*
X391417Y397058D01*
X391583Y397308D01*
X391625Y397600D01*
X391542Y397933D01*
X391333Y398183D01*
X390958Y398433D01*
G01X391458Y399908D02*
X391167Y400200D01*
X391000Y400450D01*
X390917Y400783D01*
X391000Y401075D01*
X391167Y401283D01*
X391417Y401450D01*
X391708Y401492D01*
X391958Y401450D01*
X392208Y401283D01*
X392417Y401033D01*
X392500Y400742D01*
X392417Y400408D01*
X392167Y400117D01*
X391792Y399950D01*
X391375Y399908D01*
X390833Y399992D01*
X390542Y400117D01*
X390250Y400325D01*
X390042Y400617D01*
X390000Y400908D01*
X390083Y401200D01*
X390292Y401408D01*
G01X388167Y415425D02*
X388375Y415758D01*
X388500Y416133D01*
Y416467D01*
X388375Y416800D01*
X388167Y417050D01*
X387875Y417175D01*
X387583Y417092D01*
X387333Y416883D01*
X387167Y416508D01*
X387083Y416008D01*
X386917Y415717D01*
X386625Y415592D01*
X386333Y415675D01*
X386125Y415883D01*
X386000Y416175D01*
Y416467D01*
X386083Y416758D01*
X386292Y417008D01*
G01X386000Y419400D02*
X388500D01*
G01X386000Y418442D02*
Y420358D01*
G01X388500Y421667D02*
X386000D01*
Y422667D01*
X386125Y423000D01*
X386417Y423250D01*
X386750Y423333D01*
X387083Y423250D01*
X387333Y423042D01*
X387458Y422667D01*
Y421667D01*
G01X388500Y425600D02*
X388458Y425892D01*
X388333Y426225D01*
X388125Y426433D01*
X387833Y426517D01*
X387542Y426433D01*
X387292Y426183D01*
X387167Y425808D01*
Y425392D01*
X387083Y425142D01*
X386875Y424933D01*
X386583Y424850D01*
X386292Y424975D01*
X386083Y425267D01*
X386000Y425600D01*
X386083Y425933D01*
X386292Y426225D01*
X386583Y426350D01*
X386875Y426267D01*
X387083Y426058D01*
X387167Y425808D01*
Y425392D01*
X387292Y425017D01*
X387542Y424767D01*
X387833Y424683D01*
X388125Y424767D01*
X388333Y424975D01*
X388458Y425308D01*
X388500Y425600D01*
G01X388208Y427992D02*
X388417Y428283D01*
X388500Y428617D01*
X388417Y428950D01*
X388167Y429242D01*
X387792Y429450D01*
X387417Y429533D01*
X386958D01*
X386583Y429450D01*
X386250Y429242D01*
X386083Y428992D01*
X386000Y428700D01*
X386083Y428367D01*
X386250Y428117D01*
X386500Y427950D01*
X386833Y427867D01*
X387125Y427950D01*
X387417Y428158D01*
X387583Y428408D01*
X387625Y428700D01*
X387542Y429033D01*
X387333Y429283D01*
X386958Y429533D01*
G01X384167Y419425D02*
X384375Y419758D01*
X384500Y420133D01*
Y420467D01*
X384375Y420800D01*
X384167Y421050D01*
X383875Y421175D01*
X383583Y421092D01*
X383333Y420883D01*
X383167Y420508D01*
X383083Y420008D01*
X382917Y419717D01*
X382625Y419592D01*
X382333Y419675D01*
X382125Y419883D01*
X382000Y420175D01*
Y420467D01*
X382083Y420758D01*
X382292Y421008D01*
G01X384500Y422567D02*
X382000D01*
Y423608D01*
X382125Y423942D01*
X382292Y424150D01*
X382625Y424233D01*
X382958Y424150D01*
X383167Y423900D01*
X383292Y423608D01*
Y422567D01*
G01Y423608D02*
X384500Y424233D01*
G01Y426417D02*
X383958Y426500D01*
X383500Y426625D01*
X383083Y426792D01*
X382625Y427000D01*
X382000Y427333D01*
Y425667D01*
G01X384500Y429600D02*
X384458Y429892D01*
X384333Y430225D01*
X384125Y430433D01*
X383833Y430517D01*
X383542Y430433D01*
X383292Y430183D01*
X383167Y429808D01*
Y429392D01*
X383083Y429142D01*
X382875Y428933D01*
X382583Y428850D01*
X382292Y428975D01*
X382083Y429267D01*
X382000Y429600D01*
X382083Y429933D01*
X382292Y430225D01*
X382583Y430350D01*
X382875Y430267D01*
X383083Y430058D01*
X383167Y429808D01*
Y429392D01*
X383292Y429017D01*
X383542Y428767D01*
X383833Y428683D01*
X384125Y428767D01*
X384333Y428975D01*
X384458Y429308D01*
X384500Y429600D01*
G01Y432700D02*
X384458Y432992D01*
X384333Y433325D01*
X384125Y433533D01*
X383833Y433617D01*
X383542Y433533D01*
X383292Y433283D01*
X383167Y432908D01*
Y432492D01*
X383083Y432242D01*
X382875Y432033D01*
X382583Y431950D01*
X382292Y432075D01*
X382083Y432367D01*
X382000Y432700D01*
X382083Y433033D01*
X382292Y433325D01*
X382583Y433450D01*
X382875Y433367D01*
X383083Y433158D01*
X383167Y432908D01*
Y432492D01*
X383292Y432117D01*
X383542Y431867D01*
X383833Y431783D01*
X384125Y431867D01*
X384333Y432075D01*
X384458Y432408D01*
X384500Y432700D01*
G01X388730Y431333D02*
X389063Y431125D01*
X389438Y431000D01*
X389772D01*
X390105Y431125D01*
X390355Y431333D01*
X390480Y431625D01*
X390397Y431917D01*
X390188Y432167D01*
X389813Y432333D01*
X389313Y432417D01*
X389022Y432583D01*
X388897Y432875D01*
X388980Y433167D01*
X389188Y433375D01*
X389480Y433500D01*
X389772D01*
X390063Y433417D01*
X390313Y433208D01*
G01X391872Y431000D02*
Y433500D01*
X392913D01*
X393247Y433375D01*
X393455Y433208D01*
X393538Y432875D01*
X393455Y432542D01*
X393205Y432333D01*
X392913Y432208D01*
X391872D01*
G01X392913D02*
X393538Y431000D01*
G01X395722D02*
X395805Y431542D01*
X395930Y432000D01*
X396097Y432417D01*
X396305Y432875D01*
X396638Y433500D01*
X394972D01*
G01X398197Y431292D02*
X398488Y431083D01*
X398822Y431000D01*
X399155Y431083D01*
X399447Y431333D01*
X399655Y431708D01*
X399738Y432083D01*
Y432542D01*
X399655Y432917D01*
X399447Y433250D01*
X399197Y433417D01*
X398905Y433500D01*
X398572Y433417D01*
X398322Y433250D01*
X398155Y433000D01*
X398072Y432667D01*
X398155Y432375D01*
X398363Y432083D01*
X398613Y431917D01*
X398905Y431875D01*
X399238Y431958D01*
X399488Y432167D01*
X399738Y432542D01*
G01X402005Y433500D02*
X401672Y433417D01*
X401422Y433208D01*
X401255Y432958D01*
X401130Y432625D01*
X401088Y432250D01*
X401130Y431875D01*
X401255Y431542D01*
X401422Y431292D01*
X401672Y431083D01*
X402005Y431000D01*
X402338Y431083D01*
X402588Y431292D01*
X402755Y431542D01*
X402880Y431875D01*
X402922Y432250D01*
X402880Y432625D01*
X402755Y432958D01*
X402588Y433208D01*
X402338Y433417D01*
X402005Y433500D01*
G01X388730Y440333D02*
X389063Y440125D01*
X389438Y440000D01*
X389772D01*
X390105Y440125D01*
X390355Y440333D01*
X390480Y440625D01*
X390397Y440917D01*
X390188Y441167D01*
X389813Y441333D01*
X389313Y441417D01*
X389022Y441583D01*
X388897Y441875D01*
X388980Y442167D01*
X389188Y442375D01*
X389480Y442500D01*
X389772D01*
X390063Y442417D01*
X390313Y442208D01*
G01X391872Y440000D02*
Y442500D01*
X392913D01*
X393247Y442375D01*
X393455Y442208D01*
X393538Y441875D01*
X393455Y441542D01*
X393205Y441333D01*
X392913Y441208D01*
X391872D01*
G01X392913D02*
X393538Y440000D01*
G01X395722D02*
X395805Y440542D01*
X395930Y441000D01*
X396097Y441417D01*
X396305Y441875D01*
X396638Y442500D01*
X394972D01*
G01X398197Y440292D02*
X398488Y440083D01*
X398822Y440000D01*
X399155Y440083D01*
X399447Y440333D01*
X399655Y440708D01*
X399738Y441083D01*
Y441542D01*
X399655Y441917D01*
X399447Y442250D01*
X399197Y442417D01*
X398905Y442500D01*
X398572Y442417D01*
X398322Y442250D01*
X398155Y442000D01*
X398072Y441667D01*
X398155Y441375D01*
X398363Y441083D01*
X398613Y440917D01*
X398905Y440875D01*
X399238Y440958D01*
X399488Y441167D01*
X399738Y441542D01*
G01X401213Y442083D02*
X401463Y442333D01*
X401755Y442458D01*
X402088Y442500D01*
X402505Y442417D01*
X402797Y442208D01*
X402880Y441958D01*
X402838Y441708D01*
X402672Y441500D01*
X401838Y441083D01*
X401463Y440792D01*
X401213Y440375D01*
X401130Y440000D01*
X402880D01*
G01X388730Y435833D02*
X389063Y435625D01*
X389438Y435500D01*
X389772D01*
X390105Y435625D01*
X390355Y435833D01*
X390480Y436125D01*
X390397Y436417D01*
X390188Y436667D01*
X389813Y436833D01*
X389313Y436917D01*
X389022Y437083D01*
X388897Y437375D01*
X388980Y437667D01*
X389188Y437875D01*
X389480Y438000D01*
X389772D01*
X390063Y437917D01*
X390313Y437708D01*
G01X391872Y435500D02*
Y438000D01*
X392913D01*
X393247Y437875D01*
X393455Y437708D01*
X393538Y437375D01*
X393455Y437042D01*
X393205Y436833D01*
X392913Y436708D01*
X391872D01*
G01X392913D02*
X393538Y435500D01*
G01X395722D02*
X395805Y436042D01*
X395930Y436500D01*
X396097Y436917D01*
X396305Y437375D01*
X396638Y438000D01*
X394972D01*
G01X398197Y435792D02*
X398488Y435583D01*
X398822Y435500D01*
X399155Y435583D01*
X399447Y435833D01*
X399655Y436208D01*
X399738Y436583D01*
Y437042D01*
X399655Y437417D01*
X399447Y437750D01*
X399197Y437917D01*
X398905Y438000D01*
X398572Y437917D01*
X398322Y437750D01*
X398155Y437500D01*
X398072Y437167D01*
X398155Y436875D01*
X398363Y436583D01*
X398613Y436417D01*
X398905Y436375D01*
X399238Y436458D01*
X399488Y436667D01*
X399738Y437042D01*
G01X401088Y436000D02*
X401338Y435708D01*
X401672Y435542D01*
X402047Y435500D01*
X402380Y435542D01*
X402713Y435750D01*
X402922Y436000D01*
X402963Y436250D01*
X402880Y436542D01*
X402588Y436750D01*
X402297Y436833D01*
X401922D01*
G01X402297D02*
X402547Y436958D01*
X402755Y437167D01*
X402838Y437417D01*
X402755Y437667D01*
X402547Y437875D01*
X402172Y438000D01*
X401797Y437958D01*
X401422Y437792D01*
G01X389555Y462050D02*
X393555D01*
Y469450D01*
G01X384055Y462050D02*
X388055D01*
Y469450D01*
G01X392055Y477800D02*
X394555D01*
G01X392055Y476842D02*
Y478758D01*
G01X394555Y480067D02*
X392055D01*
Y481067D01*
X392180Y481400D01*
X392472Y481650D01*
X392805Y481733D01*
X393138Y481650D01*
X393388Y481442D01*
X393513Y481067D01*
Y480067D01*
G01X392472Y483208D02*
X392222Y483458D01*
X392097Y483750D01*
X392055Y484083D01*
X392138Y484500D01*
X392347Y484792D01*
X392597Y484875D01*
X392847Y484833D01*
X393055Y484667D01*
X393472Y483833D01*
X393763Y483458D01*
X394180Y483208D01*
X394555Y483125D01*
Y484875D01*
G01X393513Y486308D02*
X393222Y486600D01*
X393055Y486850D01*
X392972Y487183D01*
X393055Y487475D01*
X393222Y487683D01*
X393472Y487850D01*
X393763Y487892D01*
X394013Y487850D01*
X394263Y487683D01*
X394472Y487433D01*
X394555Y487142D01*
X394472Y486808D01*
X394222Y486517D01*
X393847Y486350D01*
X393430Y486308D01*
X392888Y486392D01*
X392597Y486517D01*
X392305Y486725D01*
X392097Y487017D01*
X392055Y487308D01*
X392138Y487600D01*
X392347Y487808D01*
G01X394555Y490200D02*
X392055D01*
X392555Y489700D01*
G01X394555D02*
Y490700D01*
G01X379655Y481800D02*
X382155D01*
G01X379655Y480842D02*
Y482758D01*
G01X382155Y484067D02*
X379655D01*
Y485067D01*
X379780Y485400D01*
X380072Y485650D01*
X380405Y485733D01*
X380738Y485650D01*
X380988Y485442D01*
X381113Y485067D01*
Y484067D01*
G01X380072Y487208D02*
X379822Y487458D01*
X379697Y487750D01*
X379655Y488083D01*
X379738Y488500D01*
X379947Y488792D01*
X380197Y488875D01*
X380447Y488833D01*
X380655Y488667D01*
X381072Y487833D01*
X381363Y487458D01*
X381780Y487208D01*
X382155Y487125D01*
Y488875D01*
G01X381113Y490308D02*
X380822Y490600D01*
X380655Y490850D01*
X380572Y491183D01*
X380655Y491475D01*
X380822Y491683D01*
X381072Y491850D01*
X381363Y491892D01*
X381613Y491850D01*
X381863Y491683D01*
X382072Y491433D01*
X382155Y491142D01*
X382072Y490808D01*
X381822Y490517D01*
X381447Y490350D01*
X381030Y490308D01*
X380488Y490392D01*
X380197Y490517D01*
X379905Y490725D01*
X379697Y491017D01*
X379655Y491308D01*
X379738Y491600D01*
X379947Y491808D01*
G01X381113Y493408D02*
X380822Y493700D01*
X380655Y493950D01*
X380572Y494283D01*
X380655Y494575D01*
X380822Y494783D01*
X381072Y494950D01*
X381363Y494992D01*
X381613Y494950D01*
X381863Y494783D01*
X382072Y494533D01*
X382155Y494242D01*
X382072Y493908D01*
X381822Y493617D01*
X381447Y493450D01*
X381030Y493408D01*
X380488Y493492D01*
X380197Y493617D01*
X379905Y493825D01*
X379697Y494117D01*
X379655Y494408D01*
X379738Y494700D01*
X379947Y494908D01*
G01X392222Y493175D02*
X392430Y493508D01*
X392555Y493883D01*
Y494217D01*
X392430Y494550D01*
X392222Y494800D01*
X391930Y494925D01*
X391638Y494842D01*
X391388Y494633D01*
X391222Y494258D01*
X391138Y493758D01*
X390972Y493467D01*
X390680Y493342D01*
X390388Y493425D01*
X390180Y493633D01*
X390055Y493925D01*
Y494217D01*
X390138Y494508D01*
X390347Y494758D01*
G01X392555Y496317D02*
X390055D01*
Y497358D01*
X390180Y497692D01*
X390347Y497900D01*
X390680Y497983D01*
X391013Y497900D01*
X391222Y497650D01*
X391347Y497358D01*
Y496317D01*
G01Y497358D02*
X392555Y497983D01*
G01Y500167D02*
X392013Y500250D01*
X391555Y500375D01*
X391138Y500542D01*
X390680Y500750D01*
X390055Y501083D01*
Y499417D01*
G01X392555Y503850D02*
X390055D01*
X391847Y502308D01*
Y504392D01*
G01X392180Y505533D02*
X392388Y505783D01*
X392513Y506075D01*
X392555Y506450D01*
X392472Y506825D01*
X392305Y507117D01*
X392013Y507325D01*
X391680Y507367D01*
X391347Y507283D01*
X391138Y507075D01*
X390972Y506783D01*
X390930Y506492D01*
X390972Y506200D01*
X391138Y505825D01*
X390055Y505950D01*
Y507075D01*
G01X397722Y493175D02*
X397930Y493508D01*
X398055Y493883D01*
Y494217D01*
X397930Y494550D01*
X397722Y494800D01*
X397430Y494925D01*
X397138Y494842D01*
X396888Y494633D01*
X396722Y494258D01*
X396638Y493758D01*
X396472Y493467D01*
X396180Y493342D01*
X395888Y493425D01*
X395680Y493633D01*
X395555Y493925D01*
Y494217D01*
X395638Y494508D01*
X395847Y494758D01*
G01X398055Y496317D02*
X395555D01*
Y497358D01*
X395680Y497692D01*
X395847Y497900D01*
X396180Y497983D01*
X396513Y497900D01*
X396722Y497650D01*
X396847Y497358D01*
Y496317D01*
G01Y497358D02*
X398055Y497983D01*
G01Y500167D02*
X397513Y500250D01*
X397055Y500375D01*
X396638Y500542D01*
X396180Y500750D01*
X395555Y501083D01*
Y499417D01*
G01X398055Y503850D02*
X395555D01*
X397347Y502308D01*
Y504392D01*
G01X397763Y505742D02*
X397972Y506033D01*
X398055Y506367D01*
X397972Y506700D01*
X397722Y506992D01*
X397347Y507200D01*
X396972Y507283D01*
X396513D01*
X396138Y507200D01*
X395805Y506992D01*
X395638Y506742D01*
X395555Y506450D01*
X395638Y506117D01*
X395805Y505867D01*
X396055Y505700D01*
X396388Y505617D01*
X396680Y505700D01*
X396972Y505908D01*
X397138Y506158D01*
X397180Y506450D01*
X397097Y506783D01*
X396888Y507033D01*
X396513Y507283D01*
G01X386722Y493175D02*
X386930Y493508D01*
X387055Y493883D01*
Y494217D01*
X386930Y494550D01*
X386722Y494800D01*
X386430Y494925D01*
X386138Y494842D01*
X385888Y494633D01*
X385722Y494258D01*
X385638Y493758D01*
X385472Y493467D01*
X385180Y493342D01*
X384888Y493425D01*
X384680Y493633D01*
X384555Y493925D01*
Y494217D01*
X384638Y494508D01*
X384847Y494758D01*
G01X387055Y496317D02*
X384555D01*
Y497358D01*
X384680Y497692D01*
X384847Y497900D01*
X385180Y497983D01*
X385513Y497900D01*
X385722Y497650D01*
X385847Y497358D01*
Y496317D01*
G01Y497358D02*
X387055Y497983D01*
G01Y500167D02*
X386513Y500250D01*
X386055Y500375D01*
X385638Y500542D01*
X385180Y500750D01*
X384555Y501083D01*
Y499417D01*
G01X386680Y502433D02*
X386888Y502683D01*
X387013Y502975D01*
X387055Y503350D01*
X386972Y503725D01*
X386805Y504017D01*
X386513Y504225D01*
X386180Y504267D01*
X385847Y504183D01*
X385638Y503975D01*
X385472Y503683D01*
X385430Y503392D01*
X385472Y503100D01*
X385638Y502725D01*
X384555Y502850D01*
Y503975D01*
G01Y506450D02*
X384638Y506117D01*
X384847Y505867D01*
X385097Y505700D01*
X385430Y505575D01*
X385805Y505533D01*
X386180Y505575D01*
X386513Y505700D01*
X386763Y505867D01*
X386972Y506117D01*
X387055Y506450D01*
X386972Y506783D01*
X386763Y507033D01*
X386513Y507200D01*
X386180Y507325D01*
X385805Y507367D01*
X385430Y507325D01*
X385097Y507200D01*
X384847Y507033D01*
X384638Y506783D01*
X384555Y506450D01*
G01X381115Y798900D02*
Y804780D01*
G01X384945Y799585D02*
X385680Y802820D01*
G01X384605Y798020D02*
X384945Y799585D01*
G01X384385Y797525D02*
X384605Y798020D01*
G01X384100Y797135D02*
X384385Y797525D01*
G01X383650Y796940D02*
X384100Y797135D01*
G01X383310D02*
X383650Y796940D01*
G01X383880Y802820D02*
X384945Y799585D01*
G01X385500Y854517D02*
X383000D01*
Y855558D01*
X383125Y855892D01*
X383292Y856100D01*
X383625Y856183D01*
X383958Y856100D01*
X384167Y855850D01*
X384292Y855558D01*
Y854517D01*
G01Y855558D02*
X385500Y856183D01*
G01X384458Y857658D02*
X384167Y857950D01*
X384000Y858200D01*
X383917Y858533D01*
X384000Y858825D01*
X384167Y859033D01*
X384417Y859200D01*
X384708Y859242D01*
X384958Y859200D01*
X385208Y859033D01*
X385417Y858783D01*
X385500Y858492D01*
X385417Y858158D01*
X385167Y857867D01*
X384792Y857700D01*
X384375Y857658D01*
X383833Y857742D01*
X383542Y857867D01*
X383250Y858075D01*
X383042Y858367D01*
X383000Y858658D01*
X383083Y858950D01*
X383292Y859158D01*
G01X385000Y860633D02*
X385292Y860883D01*
X385458Y861217D01*
X385500Y861592D01*
X385458Y861925D01*
X385250Y862258D01*
X385000Y862467D01*
X384750Y862508D01*
X384458Y862425D01*
X384250Y862133D01*
X384167Y861842D01*
Y861467D01*
G01Y861842D02*
X384042Y862092D01*
X383833Y862300D01*
X383583Y862383D01*
X383333Y862300D01*
X383125Y862092D01*
X383000Y861717D01*
X383042Y861342D01*
X383208Y860967D01*
G01X385208Y863942D02*
X385417Y864233D01*
X385500Y864567D01*
X385417Y864900D01*
X385167Y865192D01*
X384792Y865400D01*
X384417Y865483D01*
X383958D01*
X383583Y865400D01*
X383250Y865192D01*
X383083Y864942D01*
X383000Y864650D01*
X383083Y864317D01*
X383250Y864067D01*
X383500Y863900D01*
X383833Y863817D01*
X384125Y863900D01*
X384417Y864108D01*
X384583Y864358D01*
X384625Y864650D01*
X384542Y864983D01*
X384333Y865233D01*
X383958Y865483D01*
G01X390000Y854517D02*
X387500D01*
Y855558D01*
X387625Y855892D01*
X387792Y856100D01*
X388125Y856183D01*
X388458Y856100D01*
X388667Y855850D01*
X388792Y855558D01*
Y854517D01*
G01Y855558D02*
X390000Y856183D01*
G01X388958Y857658D02*
X388667Y857950D01*
X388500Y858200D01*
X388417Y858533D01*
X388500Y858825D01*
X388667Y859033D01*
X388917Y859200D01*
X389208Y859242D01*
X389458Y859200D01*
X389708Y859033D01*
X389917Y858783D01*
X390000Y858492D01*
X389917Y858158D01*
X389667Y857867D01*
X389292Y857700D01*
X388875Y857658D01*
X388333Y857742D01*
X388042Y857867D01*
X387750Y858075D01*
X387542Y858367D01*
X387500Y858658D01*
X387583Y858950D01*
X387792Y859158D01*
G01X390000Y862050D02*
X387500D01*
X389292Y860508D01*
Y862592D01*
G01X387500Y864650D02*
X387583Y864317D01*
X387792Y864067D01*
X388042Y863900D01*
X388375Y863775D01*
X388750Y863733D01*
X389125Y863775D01*
X389458Y863900D01*
X389708Y864067D01*
X389917Y864317D01*
X390000Y864650D01*
X389917Y864983D01*
X389708Y865233D01*
X389458Y865400D01*
X389125Y865525D01*
X388750Y865567D01*
X388375Y865525D01*
X388042Y865400D01*
X387792Y865233D01*
X387583Y864983D01*
X387500Y864650D01*
G01X394500Y854517D02*
X392000D01*
Y855558D01*
X392125Y855892D01*
X392292Y856100D01*
X392625Y856183D01*
X392958Y856100D01*
X393167Y855850D01*
X393292Y855558D01*
Y854517D01*
G01Y855558D02*
X394500Y856183D01*
G01X393458Y857658D02*
X393167Y857950D01*
X393000Y858200D01*
X392917Y858533D01*
X393000Y858825D01*
X393167Y859033D01*
X393417Y859200D01*
X393708Y859242D01*
X393958Y859200D01*
X394208Y859033D01*
X394417Y858783D01*
X394500Y858492D01*
X394417Y858158D01*
X394167Y857867D01*
X393792Y857700D01*
X393375Y857658D01*
X392833Y857742D01*
X392542Y857867D01*
X392250Y858075D01*
X392042Y858367D01*
X392000Y858658D01*
X392083Y858950D01*
X392292Y859158D01*
G01X394500Y862050D02*
X392000D01*
X393792Y860508D01*
Y862592D01*
G01X394000Y863733D02*
X394292Y863983D01*
X394458Y864317D01*
X394500Y864692D01*
X394458Y865025D01*
X394250Y865358D01*
X394000Y865567D01*
X393750Y865608D01*
X393458Y865525D01*
X393250Y865233D01*
X393167Y864942D01*
Y864567D01*
G01Y864942D02*
X393042Y865192D01*
X392833Y865400D01*
X392583Y865483D01*
X392333Y865400D01*
X392125Y865192D01*
X392000Y864817D01*
X392042Y864442D01*
X392208Y864067D01*
G01X386500Y875700D02*
X382500D01*
Y868300D01*
G01X387000D02*
X391000D01*
Y875700D01*
G01X391500Y868300D02*
X395500D01*
Y875700D01*
G01X387000Y911000D02*
Y880300D01*
G01X380000Y881400D02*
X381100Y880300D01*
G01X389300Y930800D02*
Y926300D01*
G01X421100D02*
X389300D01*
G01X386000Y924200D02*
X382000D01*
Y916800D01*
G01X389300Y930800D02*
Y934200D01*
G01X391000Y932500D02*
X389300Y930800D01*
G01Y934200D02*
X391000Y932500D01*
G01X389300Y938700D02*
X421100D01*
G01X389300Y934200D02*
Y938700D01*
G01X385000Y927517D02*
X382500D01*
Y928558D01*
X382625Y928892D01*
X382792Y929100D01*
X383125Y929183D01*
X383458Y929100D01*
X383667Y928850D01*
X383792Y928558D01*
Y927517D01*
G01Y928558D02*
X385000Y929183D01*
G01X383958Y930658D02*
X383667Y930950D01*
X383500Y931200D01*
X383417Y931533D01*
X383500Y931825D01*
X383667Y932033D01*
X383917Y932200D01*
X384208Y932242D01*
X384458Y932200D01*
X384708Y932033D01*
X384917Y931783D01*
X385000Y931492D01*
X384917Y931158D01*
X384667Y930867D01*
X384292Y930700D01*
X383875Y930658D01*
X383333Y930742D01*
X383042Y930867D01*
X382750Y931075D01*
X382542Y931367D01*
X382500Y931658D01*
X382583Y931950D01*
X382792Y932158D01*
G01X383958Y933758D02*
X383667Y934050D01*
X383500Y934300D01*
X383417Y934633D01*
X383500Y934925D01*
X383667Y935133D01*
X383917Y935300D01*
X384208Y935342D01*
X384458Y935300D01*
X384708Y935133D01*
X384917Y934883D01*
X385000Y934592D01*
X384917Y934258D01*
X384667Y933967D01*
X384292Y933800D01*
X383875Y933758D01*
X383333Y933842D01*
X383042Y933967D01*
X382750Y934175D01*
X382542Y934467D01*
X382500Y934758D01*
X382583Y935050D01*
X382792Y935258D01*
G01X382500Y937650D02*
X382583Y937317D01*
X382792Y937067D01*
X383042Y936900D01*
X383375Y936775D01*
X383750Y936733D01*
X384125Y936775D01*
X384458Y936900D01*
X384708Y937067D01*
X384917Y937317D01*
X385000Y937650D01*
X384917Y937983D01*
X384708Y938233D01*
X384458Y938400D01*
X384125Y938525D01*
X383750Y938567D01*
X383375Y938525D01*
X383042Y938400D01*
X382792Y938233D01*
X382583Y937983D01*
X382500Y937650D01*
G01X392167Y959425D02*
X392375Y959758D01*
X392500Y960133D01*
Y960467D01*
X392375Y960800D01*
X392167Y961050D01*
X391875Y961175D01*
X391583Y961092D01*
X391333Y960883D01*
X391167Y960508D01*
X391083Y960008D01*
X390917Y959717D01*
X390625Y959592D01*
X390333Y959675D01*
X390125Y959883D01*
X390000Y960175D01*
Y960467D01*
X390083Y960758D01*
X390292Y961008D01*
G01X392500Y962567D02*
X390000D01*
Y963608D01*
X390125Y963942D01*
X390292Y964150D01*
X390625Y964233D01*
X390958Y964150D01*
X391167Y963900D01*
X391292Y963608D01*
Y962567D01*
G01Y963608D02*
X392500Y964233D01*
G01X390417Y965708D02*
X390167Y965958D01*
X390042Y966250D01*
X390000Y966583D01*
X390083Y967000D01*
X390292Y967292D01*
X390542Y967375D01*
X390792Y967333D01*
X391000Y967167D01*
X391417Y966333D01*
X391708Y965958D01*
X392125Y965708D01*
X392500Y965625D01*
Y967375D01*
G01X391458Y968808D02*
X391167Y969100D01*
X391000Y969350D01*
X390917Y969683D01*
X391000Y969975D01*
X391167Y970183D01*
X391417Y970350D01*
X391708Y970392D01*
X391958Y970350D01*
X392208Y970183D01*
X392417Y969933D01*
X392500Y969642D01*
X392417Y969308D01*
X392167Y969017D01*
X391792Y968850D01*
X391375Y968808D01*
X390833Y968892D01*
X390542Y969017D01*
X390250Y969225D01*
X390042Y969517D01*
X390000Y969808D01*
X390083Y970100D01*
X390292Y970308D01*
G01X392125Y971783D02*
X392333Y972033D01*
X392458Y972325D01*
X392500Y972700D01*
X392417Y973075D01*
X392250Y973367D01*
X391958Y973575D01*
X391625Y973617D01*
X391292Y973533D01*
X391083Y973325D01*
X390917Y973033D01*
X390875Y972742D01*
X390917Y972450D01*
X391083Y972075D01*
X390000Y972200D01*
Y973325D01*
G01Y949800D02*
X394000D01*
Y957200D01*
G01X403273Y26872D02*
G02X423105I9916J-3450D01*
G01X426689D01*
Y20372D01*
X423236D01*
G02X423163Y20143I-10040J3074D01*
G02X423115Y19997I-9998J3206D01*
G02X421735Y17322I-9925J3427D01*
G01X404643D01*
G02X403263Y19997I8545J6102D01*
G02X403215Y20143I9950J3352D01*
G02X403142Y20372I9967J3303D01*
G01X399689D01*
Y26872D01*
X403273D01*
G01X410000Y38000D02*
X430500D01*
Y58500D01*
X406500D01*
Y38000D01*
X410000D01*
G01X411000Y39967D02*
X408500D01*
Y40967D01*
X408625Y41300D01*
X408917Y41550D01*
X409250Y41633D01*
X409583Y41550D01*
X409833Y41342D01*
X409958Y40967D01*
Y39967D01*
G01X408708Y44817D02*
X408583Y44567D01*
X408500Y44275D01*
Y43942D01*
X408625Y43567D01*
X408833Y43275D01*
X409083Y43067D01*
X409500Y42900D01*
X409875Y42858D01*
X410250Y42942D01*
X410500Y43067D01*
X410750Y43317D01*
X410917Y43608D01*
X411000Y43900D01*
Y44192D01*
X410917Y44483D01*
X410792Y44733D01*
X410625Y44942D01*
G01X411000Y47000D02*
X408500D01*
X409000Y46500D01*
G01X411000D02*
Y47500D01*
G01X410708Y49392D02*
X410917Y49683D01*
X411000Y50017D01*
X410917Y50350D01*
X410667Y50642D01*
X410292Y50850D01*
X409917Y50933D01*
X409458D01*
X409083Y50850D01*
X408750Y50642D01*
X408583Y50392D01*
X408500Y50100D01*
X408583Y49767D01*
X408750Y49517D01*
X409000Y49350D01*
X409333Y49267D01*
X409625Y49350D01*
X409917Y49558D01*
X410083Y49808D01*
X410125Y50100D01*
X410042Y50433D01*
X409833Y50683D01*
X409458Y50933D01*
G01X411000Y53117D02*
X410458Y53200D01*
X410000Y53325D01*
X409583Y53492D01*
X409125Y53700D01*
X408500Y54033D01*
Y52367D01*
G01X399167Y53025D02*
X399375Y53358D01*
X399500Y53733D01*
Y54067D01*
X399375Y54400D01*
X399167Y54650D01*
X398875Y54775D01*
X398583Y54692D01*
X398333Y54483D01*
X398167Y54108D01*
X398083Y53608D01*
X397917Y53317D01*
X397625Y53192D01*
X397333Y53275D01*
X397125Y53483D01*
X397000Y53775D01*
Y54067D01*
X397083Y54358D01*
X397292Y54608D01*
G01X397000Y56167D02*
X399500D01*
Y57833D01*
G01Y60100D02*
X399458Y60392D01*
X399333Y60725D01*
X399125Y60933D01*
X398833Y61017D01*
X398542Y60933D01*
X398292Y60683D01*
X398167Y60308D01*
Y59892D01*
X398083Y59642D01*
X397875Y59433D01*
X397583Y59350D01*
X397292Y59475D01*
X397083Y59767D01*
X397000Y60100D01*
X397083Y60433D01*
X397292Y60725D01*
X397583Y60850D01*
X397875Y60767D01*
X398083Y60558D01*
X398167Y60308D01*
Y59892D01*
X398292Y59517D01*
X398542Y59267D01*
X398833Y59183D01*
X399125Y59267D01*
X399333Y59475D01*
X399458Y59808D01*
X399500Y60100D01*
G01X403667Y49525D02*
X403875Y49858D01*
X404000Y50233D01*
Y50567D01*
X403875Y50900D01*
X403667Y51150D01*
X403375Y51275D01*
X403083Y51192D01*
X402833Y50983D01*
X402667Y50608D01*
X402583Y50108D01*
X402417Y49817D01*
X402125Y49692D01*
X401833Y49775D01*
X401625Y49983D01*
X401500Y50275D01*
Y50567D01*
X401583Y50858D01*
X401792Y51108D01*
G01X404000Y52667D02*
X401500D01*
Y53708D01*
X401625Y54042D01*
X401792Y54250D01*
X402125Y54333D01*
X402458Y54250D01*
X402667Y54000D01*
X402792Y53708D01*
Y52667D01*
G01Y53708D02*
X404000Y54333D01*
G01Y56517D02*
X403458Y56600D01*
X403000Y56725D01*
X402583Y56892D01*
X402125Y57100D01*
X401500Y57433D01*
Y55767D01*
G01X404000Y59700D02*
X401500D01*
X402000Y59200D01*
G01X404000D02*
Y60200D01*
G01X403625Y61883D02*
X403833Y62133D01*
X403958Y62425D01*
X404000Y62800D01*
X403917Y63175D01*
X403750Y63467D01*
X403458Y63675D01*
X403125Y63717D01*
X402792Y63633D01*
X402583Y63425D01*
X402417Y63133D01*
X402375Y62842D01*
X402417Y62550D01*
X402583Y62175D01*
X401500Y62300D01*
Y63425D01*
G01X411667Y96425D02*
X411875Y96758D01*
X412000Y97133D01*
Y97467D01*
X411875Y97800D01*
X411667Y98050D01*
X411375Y98175D01*
X411083Y98092D01*
X410833Y97883D01*
X410667Y97508D01*
X410583Y97008D01*
X410417Y96717D01*
X410125Y96592D01*
X409833Y96675D01*
X409625Y96883D01*
X409500Y97175D01*
Y97467D01*
X409583Y97758D01*
X409792Y98008D01*
G01X409500Y100400D02*
X412000D01*
G01X409500Y99442D02*
Y101358D01*
G01X412000Y102667D02*
X409500D01*
Y103667D01*
X409625Y104000D01*
X409917Y104250D01*
X410250Y104333D01*
X410583Y104250D01*
X410833Y104042D01*
X410958Y103667D01*
Y102667D01*
G01X412000Y107100D02*
X409500D01*
X411292Y105558D01*
Y107642D01*
G01X411500Y108783D02*
X411792Y109033D01*
X411958Y109367D01*
X412000Y109742D01*
X411958Y110075D01*
X411750Y110408D01*
X411500Y110617D01*
X411250Y110658D01*
X410958Y110575D01*
X410750Y110283D01*
X410667Y109992D01*
Y109617D01*
G01Y109992D02*
X410542Y110242D01*
X410333Y110450D01*
X410083Y110533D01*
X409833Y110450D01*
X409625Y110242D01*
X409500Y109867D01*
X409542Y109492D01*
X409708Y109117D01*
G01X405925Y114833D02*
X406258Y114625D01*
X406633Y114500D01*
X406967D01*
X407300Y114625D01*
X407550Y114833D01*
X407675Y115125D01*
X407592Y115417D01*
X407383Y115667D01*
X407008Y115833D01*
X406508Y115917D01*
X406217Y116083D01*
X406092Y116375D01*
X406175Y116667D01*
X406383Y116875D01*
X406675Y117000D01*
X406967D01*
X407258Y116917D01*
X407508Y116708D01*
G01X409900Y117000D02*
Y114500D01*
G01X408942Y117000D02*
X410858D01*
G01X412167Y114500D02*
Y117000D01*
X413167D01*
X413500Y116875D01*
X413750Y116583D01*
X413833Y116250D01*
X413750Y115917D01*
X413542Y115667D01*
X413167Y115542D01*
X412167D01*
G01X416600Y114500D02*
Y117000D01*
X415058Y115208D01*
X417142D01*
G01X419200Y117000D02*
X418867Y116917D01*
X418617Y116708D01*
X418450Y116458D01*
X418325Y116125D01*
X418283Y115750D01*
X418325Y115375D01*
X418450Y115042D01*
X418617Y114792D01*
X418867Y114583D01*
X419200Y114500D01*
X419533Y114583D01*
X419783Y114792D01*
X419950Y115042D01*
X420075Y115375D01*
X420117Y115750D01*
X420075Y116125D01*
X419950Y116458D01*
X419783Y116708D01*
X419533Y116917D01*
X419200Y117000D01*
G01X402925Y119833D02*
X403258Y119625D01*
X403633Y119500D01*
X403967D01*
X404300Y119625D01*
X404550Y119833D01*
X404675Y120125D01*
X404592Y120417D01*
X404383Y120667D01*
X404008Y120833D01*
X403508Y120917D01*
X403217Y121083D01*
X403092Y121375D01*
X403175Y121667D01*
X403383Y121875D01*
X403675Y122000D01*
X403967D01*
X404258Y121917D01*
X404508Y121708D01*
G01X406067Y119500D02*
Y122000D01*
X407108D01*
X407442Y121875D01*
X407650Y121708D01*
X407733Y121375D01*
X407650Y121042D01*
X407400Y120833D01*
X407108Y120708D01*
X406067D01*
G01X407108D02*
X407733Y119500D01*
G01X409208Y120542D02*
X409500Y120833D01*
X409750Y121000D01*
X410083Y121083D01*
X410375Y121000D01*
X410583Y120833D01*
X410750Y120583D01*
X410792Y120292D01*
X410750Y120042D01*
X410583Y119792D01*
X410333Y119583D01*
X410042Y119500D01*
X409708Y119583D01*
X409417Y119833D01*
X409250Y120208D01*
X409208Y120625D01*
X409292Y121167D01*
X409417Y121458D01*
X409625Y121750D01*
X409917Y121958D01*
X410208Y122000D01*
X410500Y121917D01*
X410708Y121708D01*
G01X413600Y119500D02*
Y122000D01*
X412058Y120208D01*
X414142D01*
G01X416117Y119500D02*
X416200Y120042D01*
X416325Y120500D01*
X416492Y120917D01*
X416700Y121375D01*
X417033Y122000D01*
X415367D01*
G01X401500Y259500D02*
Y248500D01*
G01Y241000D02*
Y238500D01*
X413500D01*
Y242500D01*
X431500D01*
G01X422500Y272000D02*
X408500D01*
Y264500D01*
X406500D01*
G01X396800Y267400D02*
Y263400D01*
X404200D01*
G01X414500Y270700D02*
X410500D01*
Y263300D01*
G01X412167Y277500D02*
X415500Y284500D01*
X418833Y277500D01*
G01X417633Y279950D02*
X413367D01*
G01X402555Y304700D02*
X398555D01*
Y297300D01*
G01X407555Y304700D02*
X403555D01*
Y297300D01*
G01X411555Y304700D02*
X407555D01*
Y297300D01*
G01X416055Y304700D02*
X412055D01*
Y297300D01*
G01X460500Y315000D02*
X401000D01*
Y313000D01*
X399000D01*
G01X400865Y320275D02*
G03I-1850J0D01*
G01X410708D02*
G03I-1850J0D01*
G01X407008D02*
X400865D01*
G01X493622D02*
X410708D01*
G01X399015Y331968D02*
Y414882D01*
G01Y322125D02*
Y328268D01*
G01X400865Y330118D02*
G03I-1850J0D01*
G01Y416732D02*
G03I-1850J0D01*
G01X407008Y426575D02*
X400865D01*
G01D02*
G03I-1850J0D01*
G01X410708D02*
X493622D01*
G01X399015Y418582D02*
Y424725D01*
G01X410708Y426575D02*
G03I-1850J0D01*
G01X407222Y455375D02*
X407430Y455708D01*
X407555Y456083D01*
Y456417D01*
X407430Y456750D01*
X407222Y457000D01*
X406930Y457125D01*
X406638Y457042D01*
X406388Y456833D01*
X406222Y456458D01*
X406138Y455958D01*
X405972Y455667D01*
X405680Y455542D01*
X405388Y455625D01*
X405180Y455833D01*
X405055Y456125D01*
Y456417D01*
X405138Y456708D01*
X405347Y456958D01*
G01X405263Y460267D02*
X405138Y460017D01*
X405055Y459725D01*
Y459392D01*
X405180Y459017D01*
X405388Y458725D01*
X405638Y458517D01*
X406055Y458350D01*
X406430Y458308D01*
X406805Y458392D01*
X407055Y458517D01*
X407305Y458767D01*
X407472Y459058D01*
X407555Y459350D01*
Y459642D01*
X407472Y459933D01*
X407347Y460183D01*
X407180Y460392D01*
G01X407555Y462450D02*
X405055D01*
X405555Y461950D01*
G01X407555D02*
Y462950D01*
G01X405055Y465550D02*
X405138Y465217D01*
X405347Y464967D01*
X405597Y464800D01*
X405930Y464675D01*
X406305Y464633D01*
X406680Y464675D01*
X407013Y464800D01*
X407263Y464967D01*
X407472Y465217D01*
X407555Y465550D01*
X407472Y465883D01*
X407263Y466133D01*
X407013Y466300D01*
X406680Y466425D01*
X406305Y466467D01*
X405930Y466425D01*
X405597Y466300D01*
X405347Y466133D01*
X405138Y465883D01*
X405055Y465550D01*
G01X407555Y468650D02*
X407513Y468942D01*
X407388Y469275D01*
X407180Y469483D01*
X406888Y469567D01*
X406597Y469483D01*
X406347Y469233D01*
X406222Y468858D01*
Y468442D01*
X406138Y468192D01*
X405930Y467983D01*
X405638Y467900D01*
X405347Y468025D01*
X405138Y468317D01*
X405055Y468650D01*
X405138Y468983D01*
X405347Y469275D01*
X405638Y469400D01*
X405930Y469317D01*
X406138Y469108D01*
X406222Y468858D01*
Y468442D01*
X406347Y468067D01*
X406597Y467817D01*
X406888Y467733D01*
X407180Y467817D01*
X407388Y468025D01*
X407513Y468358D01*
X407555Y468650D01*
G01Y471667D02*
X407013Y471750D01*
X406555Y471875D01*
X406138Y472042D01*
X405680Y472250D01*
X405055Y472583D01*
Y470917D01*
G01X411222Y455375D02*
X411430Y455708D01*
X411555Y456083D01*
Y456417D01*
X411430Y456750D01*
X411222Y457000D01*
X410930Y457125D01*
X410638Y457042D01*
X410388Y456833D01*
X410222Y456458D01*
X410138Y455958D01*
X409972Y455667D01*
X409680Y455542D01*
X409388Y455625D01*
X409180Y455833D01*
X409055Y456125D01*
Y456417D01*
X409138Y456708D01*
X409347Y456958D01*
G01X409263Y460267D02*
X409138Y460017D01*
X409055Y459725D01*
Y459392D01*
X409180Y459017D01*
X409388Y458725D01*
X409638Y458517D01*
X410055Y458350D01*
X410430Y458308D01*
X410805Y458392D01*
X411055Y458517D01*
X411305Y458767D01*
X411472Y459058D01*
X411555Y459350D01*
Y459642D01*
X411472Y459933D01*
X411347Y460183D01*
X411180Y460392D01*
G01X411555Y462450D02*
X409055D01*
X409555Y461950D01*
G01X411555D02*
Y462950D01*
G01X409055Y465550D02*
X409138Y465217D01*
X409347Y464967D01*
X409597Y464800D01*
X409930Y464675D01*
X410305Y464633D01*
X410680Y464675D01*
X411013Y464800D01*
X411263Y464967D01*
X411472Y465217D01*
X411555Y465550D01*
X411472Y465883D01*
X411263Y466133D01*
X411013Y466300D01*
X410680Y466425D01*
X410305Y466467D01*
X409930Y466425D01*
X409597Y466300D01*
X409347Y466133D01*
X409138Y465883D01*
X409055Y465550D01*
G01X411555Y468650D02*
X411513Y468942D01*
X411388Y469275D01*
X411180Y469483D01*
X410888Y469567D01*
X410597Y469483D01*
X410347Y469233D01*
X410222Y468858D01*
Y468442D01*
X410138Y468192D01*
X409930Y467983D01*
X409638Y467900D01*
X409347Y468025D01*
X409138Y468317D01*
X409055Y468650D01*
X409138Y468983D01*
X409347Y469275D01*
X409638Y469400D01*
X409930Y469317D01*
X410138Y469108D01*
X410222Y468858D01*
Y468442D01*
X410347Y468067D01*
X410597Y467817D01*
X410888Y467733D01*
X411180Y467817D01*
X411388Y468025D01*
X411513Y468358D01*
X411555Y468650D01*
G01Y471750D02*
X411513Y472042D01*
X411388Y472375D01*
X411180Y472583D01*
X410888Y472667D01*
X410597Y472583D01*
X410347Y472333D01*
X410222Y471958D01*
Y471542D01*
X410138Y471292D01*
X409930Y471083D01*
X409638Y471000D01*
X409347Y471125D01*
X409138Y471417D01*
X409055Y471750D01*
X409138Y472083D01*
X409347Y472375D01*
X409638Y472500D01*
X409930Y472417D01*
X410138Y472208D01*
X410222Y471958D01*
Y471542D01*
X410347Y471167D01*
X410597Y470917D01*
X410888Y470833D01*
X411180Y470917D01*
X411388Y471125D01*
X411513Y471458D01*
X411555Y471750D01*
G01X399222Y455375D02*
X399430Y455708D01*
X399555Y456083D01*
Y456417D01*
X399430Y456750D01*
X399222Y457000D01*
X398930Y457125D01*
X398638Y457042D01*
X398388Y456833D01*
X398222Y456458D01*
X398138Y455958D01*
X397972Y455667D01*
X397680Y455542D01*
X397388Y455625D01*
X397180Y455833D01*
X397055Y456125D01*
Y456417D01*
X397138Y456708D01*
X397347Y456958D01*
G01X397263Y460267D02*
X397138Y460017D01*
X397055Y459725D01*
Y459392D01*
X397180Y459017D01*
X397388Y458725D01*
X397638Y458517D01*
X398055Y458350D01*
X398430Y458308D01*
X398805Y458392D01*
X399055Y458517D01*
X399305Y458767D01*
X399472Y459058D01*
X399555Y459350D01*
Y459642D01*
X399472Y459933D01*
X399347Y460183D01*
X399180Y460392D01*
G01X399555Y462450D02*
X397055D01*
X397555Y461950D01*
G01X399555D02*
Y462950D01*
G01X397055Y465550D02*
X397138Y465217D01*
X397347Y464967D01*
X397597Y464800D01*
X397930Y464675D01*
X398305Y464633D01*
X398680Y464675D01*
X399013Y464800D01*
X399263Y464967D01*
X399472Y465217D01*
X399555Y465550D01*
X399472Y465883D01*
X399263Y466133D01*
X399013Y466300D01*
X398680Y466425D01*
X398305Y466467D01*
X397930Y466425D01*
X397597Y466300D01*
X397347Y466133D01*
X397138Y465883D01*
X397055Y465550D01*
G01X399555Y468650D02*
X399513Y468942D01*
X399388Y469275D01*
X399180Y469483D01*
X398888Y469567D01*
X398597Y469483D01*
X398347Y469233D01*
X398222Y468858D01*
Y468442D01*
X398138Y468192D01*
X397930Y467983D01*
X397638Y467900D01*
X397347Y468025D01*
X397138Y468317D01*
X397055Y468650D01*
X397138Y468983D01*
X397347Y469275D01*
X397638Y469400D01*
X397930Y469317D01*
X398138Y469108D01*
X398222Y468858D01*
Y468442D01*
X398347Y468067D01*
X398597Y467817D01*
X398888Y467733D01*
X399180Y467817D01*
X399388Y468025D01*
X399513Y468358D01*
X399555Y468650D01*
G01X399263Y471042D02*
X399472Y471333D01*
X399555Y471667D01*
X399472Y472000D01*
X399222Y472292D01*
X398847Y472500D01*
X398472Y472583D01*
X398013D01*
X397638Y472500D01*
X397305Y472292D01*
X397138Y472042D01*
X397055Y471750D01*
X397138Y471417D01*
X397305Y471167D01*
X397555Y471000D01*
X397888Y470917D01*
X398180Y471000D01*
X398472Y471208D01*
X398638Y471458D01*
X398680Y471750D01*
X398597Y472083D01*
X398388Y472333D01*
X398013Y472583D01*
G01X403222Y455375D02*
X403430Y455708D01*
X403555Y456083D01*
Y456417D01*
X403430Y456750D01*
X403222Y457000D01*
X402930Y457125D01*
X402638Y457042D01*
X402388Y456833D01*
X402222Y456458D01*
X402138Y455958D01*
X401972Y455667D01*
X401680Y455542D01*
X401388Y455625D01*
X401180Y455833D01*
X401055Y456125D01*
Y456417D01*
X401138Y456708D01*
X401347Y456958D01*
G01X401263Y460267D02*
X401138Y460017D01*
X401055Y459725D01*
Y459392D01*
X401180Y459017D01*
X401388Y458725D01*
X401638Y458517D01*
X402055Y458350D01*
X402430Y458308D01*
X402805Y458392D01*
X403055Y458517D01*
X403305Y458767D01*
X403472Y459058D01*
X403555Y459350D01*
Y459642D01*
X403472Y459933D01*
X403347Y460183D01*
X403180Y460392D01*
G01X403555Y462450D02*
X401055D01*
X401555Y461950D01*
G01X403555D02*
Y462950D01*
G01X401055Y465550D02*
X401138Y465217D01*
X401347Y464967D01*
X401597Y464800D01*
X401930Y464675D01*
X402305Y464633D01*
X402680Y464675D01*
X403013Y464800D01*
X403263Y464967D01*
X403472Y465217D01*
X403555Y465550D01*
X403472Y465883D01*
X403263Y466133D01*
X403013Y466300D01*
X402680Y466425D01*
X402305Y466467D01*
X401930Y466425D01*
X401597Y466300D01*
X401347Y466133D01*
X401138Y465883D01*
X401055Y465550D01*
G01X403263Y467942D02*
X403472Y468233D01*
X403555Y468567D01*
X403472Y468900D01*
X403222Y469192D01*
X402847Y469400D01*
X402472Y469483D01*
X402013D01*
X401638Y469400D01*
X401305Y469192D01*
X401138Y468942D01*
X401055Y468650D01*
X401138Y468317D01*
X401305Y468067D01*
X401555Y467900D01*
X401888Y467817D01*
X402180Y467900D01*
X402472Y468108D01*
X402638Y468358D01*
X402680Y468650D01*
X402597Y468983D01*
X402388Y469233D01*
X402013Y469483D01*
G01X401055Y471750D02*
X401138Y471417D01*
X401347Y471167D01*
X401597Y471000D01*
X401930Y470875D01*
X402305Y470833D01*
X402680Y470875D01*
X403013Y471000D01*
X403263Y471167D01*
X403472Y471417D01*
X403555Y471750D01*
X403472Y472083D01*
X403263Y472333D01*
X403013Y472500D01*
X402680Y472625D01*
X402305Y472667D01*
X401930Y472625D01*
X401597Y472500D01*
X401347Y472333D01*
X401138Y472083D01*
X401055Y471750D01*
G01X403555Y477800D02*
X406055D01*
G01X403555Y476842D02*
Y478758D01*
G01X406055Y480067D02*
X403555D01*
Y481067D01*
X403680Y481400D01*
X403972Y481650D01*
X404305Y481733D01*
X404638Y481650D01*
X404888Y481442D01*
X405013Y481067D01*
Y480067D01*
G01X403972Y483208D02*
X403722Y483458D01*
X403597Y483750D01*
X403555Y484083D01*
X403638Y484500D01*
X403847Y484792D01*
X404097Y484875D01*
X404347Y484833D01*
X404555Y484667D01*
X404972Y483833D01*
X405263Y483458D01*
X405680Y483208D01*
X406055Y483125D01*
Y484875D01*
G01X405013Y486308D02*
X404722Y486600D01*
X404555Y486850D01*
X404472Y487183D01*
X404555Y487475D01*
X404722Y487683D01*
X404972Y487850D01*
X405263Y487892D01*
X405513Y487850D01*
X405763Y487683D01*
X405972Y487433D01*
X406055Y487142D01*
X405972Y486808D01*
X405722Y486517D01*
X405347Y486350D01*
X404930Y486308D01*
X404388Y486392D01*
X404097Y486517D01*
X403805Y486725D01*
X403597Y487017D01*
X403555Y487308D01*
X403638Y487600D01*
X403847Y487808D01*
G01X405555Y489283D02*
X405847Y489533D01*
X406013Y489867D01*
X406055Y490242D01*
X406013Y490575D01*
X405805Y490908D01*
X405555Y491117D01*
X405305Y491158D01*
X405013Y491075D01*
X404805Y490783D01*
X404722Y490492D01*
Y490117D01*
G01Y490492D02*
X404597Y490742D01*
X404388Y490950D01*
X404138Y491033D01*
X403888Y490950D01*
X403680Y490742D01*
X403555Y490367D01*
X403597Y489992D01*
X403763Y489617D01*
G01X398055Y477800D02*
X400555D01*
G01X398055Y476842D02*
Y478758D01*
G01X400555Y480067D02*
X398055D01*
Y481067D01*
X398180Y481400D01*
X398472Y481650D01*
X398805Y481733D01*
X399138Y481650D01*
X399388Y481442D01*
X399513Y481067D01*
Y480067D01*
G01X398472Y483208D02*
X398222Y483458D01*
X398097Y483750D01*
X398055Y484083D01*
X398138Y484500D01*
X398347Y484792D01*
X398597Y484875D01*
X398847Y484833D01*
X399055Y484667D01*
X399472Y483833D01*
X399763Y483458D01*
X400180Y483208D01*
X400555Y483125D01*
Y484875D01*
G01X399513Y486308D02*
X399222Y486600D01*
X399055Y486850D01*
X398972Y487183D01*
X399055Y487475D01*
X399222Y487683D01*
X399472Y487850D01*
X399763Y487892D01*
X400013Y487850D01*
X400263Y487683D01*
X400472Y487433D01*
X400555Y487142D01*
X400472Y486808D01*
X400222Y486517D01*
X399847Y486350D01*
X399430Y486308D01*
X398888Y486392D01*
X398597Y486517D01*
X398305Y486725D01*
X398097Y487017D01*
X398055Y487308D01*
X398138Y487600D01*
X398347Y487808D01*
G01X400180Y489283D02*
X400388Y489533D01*
X400513Y489825D01*
X400555Y490200D01*
X400472Y490575D01*
X400305Y490867D01*
X400013Y491075D01*
X399680Y491117D01*
X399347Y491033D01*
X399138Y490825D01*
X398972Y490533D01*
X398930Y490242D01*
X398972Y489950D01*
X399138Y489575D01*
X398055Y489700D01*
Y490825D01*
G01X403222Y493175D02*
X403430Y493508D01*
X403555Y493883D01*
Y494217D01*
X403430Y494550D01*
X403222Y494800D01*
X402930Y494925D01*
X402638Y494842D01*
X402388Y494633D01*
X402222Y494258D01*
X402138Y493758D01*
X401972Y493467D01*
X401680Y493342D01*
X401388Y493425D01*
X401180Y493633D01*
X401055Y493925D01*
Y494217D01*
X401138Y494508D01*
X401347Y494758D01*
G01X403555Y496317D02*
X401055D01*
Y497358D01*
X401180Y497692D01*
X401347Y497900D01*
X401680Y497983D01*
X402013Y497900D01*
X402222Y497650D01*
X402347Y497358D01*
Y496317D01*
G01Y497358D02*
X403555Y497983D01*
G01Y500167D02*
X403013Y500250D01*
X402555Y500375D01*
X402138Y500542D01*
X401680Y500750D01*
X401055Y501083D01*
Y499417D01*
G01X403555Y503850D02*
X401055D01*
X402847Y502308D01*
Y504392D01*
G01X403555Y506367D02*
X403013Y506450D01*
X402555Y506575D01*
X402138Y506742D01*
X401680Y506950D01*
X401055Y507283D01*
Y505617D01*
G01X399000Y854517D02*
X396500D01*
Y855558D01*
X396625Y855892D01*
X396792Y856100D01*
X397125Y856183D01*
X397458Y856100D01*
X397667Y855850D01*
X397792Y855558D01*
Y854517D01*
G01Y855558D02*
X399000Y856183D01*
G01X397958Y857658D02*
X397667Y857950D01*
X397500Y858200D01*
X397417Y858533D01*
X397500Y858825D01*
X397667Y859033D01*
X397917Y859200D01*
X398208Y859242D01*
X398458Y859200D01*
X398708Y859033D01*
X398917Y858783D01*
X399000Y858492D01*
X398917Y858158D01*
X398667Y857867D01*
X398292Y857700D01*
X397875Y857658D01*
X397333Y857742D01*
X397042Y857867D01*
X396750Y858075D01*
X396542Y858367D01*
X396500Y858658D01*
X396583Y858950D01*
X396792Y859158D01*
G01X399000Y862050D02*
X396500D01*
X398292Y860508D01*
Y862592D01*
G01X399000Y864650D02*
X396500D01*
X397000Y864150D01*
G01X399000D02*
Y865150D01*
G01X400000Y875700D02*
X396000D01*
Y868300D01*
G01X398000Y891933D02*
X399792D01*
X400167Y892100D01*
X400417Y892433D01*
X400500Y892850D01*
X400417Y893267D01*
X400167Y893600D01*
X399792Y893767D01*
X398000D01*
G01X400500Y895950D02*
X398000D01*
X398500Y895450D01*
G01X400500D02*
Y896450D01*
G01Y899050D02*
X400458Y899342D01*
X400333Y899675D01*
X400125Y899883D01*
X399833Y899967D01*
X399542Y899883D01*
X399292Y899633D01*
X399167Y899258D01*
Y898842D01*
X399083Y898592D01*
X398875Y898383D01*
X398583Y898300D01*
X398292Y898425D01*
X398083Y898717D01*
X398000Y899050D01*
X398083Y899383D01*
X398292Y899675D01*
X398583Y899800D01*
X398875Y899717D01*
X399083Y899508D01*
X399167Y899258D01*
Y898842D01*
X399292Y898467D01*
X399542Y898217D01*
X399833Y898133D01*
X400125Y898217D01*
X400333Y898425D01*
X400458Y898758D01*
X400500Y899050D01*
G01Y902150D02*
X400458Y902442D01*
X400333Y902775D01*
X400125Y902983D01*
X399833Y903067D01*
X399542Y902983D01*
X399292Y902733D01*
X399167Y902358D01*
Y901942D01*
X399083Y901692D01*
X398875Y901483D01*
X398583Y901400D01*
X398292Y901525D01*
X398083Y901817D01*
X398000Y902150D01*
X398083Y902483D01*
X398292Y902775D01*
X398583Y902900D01*
X398875Y902817D01*
X399083Y902608D01*
X399167Y902358D01*
Y901942D01*
X399292Y901567D01*
X399542Y901317D01*
X399833Y901233D01*
X400125Y901317D01*
X400333Y901525D01*
X400458Y901858D01*
X400500Y902150D01*
G01X411017Y879000D02*
Y881500D01*
X412058D01*
X412392Y881375D01*
X412600Y881208D01*
X412683Y880875D01*
X412600Y880542D01*
X412350Y880333D01*
X412058Y880208D01*
X411017D01*
G01X412058D02*
X412683Y879000D01*
G01X414158Y880042D02*
X414450Y880333D01*
X414700Y880500D01*
X415033Y880583D01*
X415325Y880500D01*
X415533Y880333D01*
X415700Y880083D01*
X415742Y879792D01*
X415700Y879542D01*
X415533Y879292D01*
X415283Y879083D01*
X414992Y879000D01*
X414658Y879083D01*
X414367Y879333D01*
X414200Y879708D01*
X414158Y880125D01*
X414242Y880667D01*
X414367Y880958D01*
X414575Y881250D01*
X414867Y881458D01*
X415158Y881500D01*
X415450Y881417D01*
X415658Y881208D01*
G01X418550Y879000D02*
Y881500D01*
X417008Y879708D01*
X419092D01*
G01X421650Y879000D02*
Y881500D01*
X420108Y879708D01*
X422192D01*
G01X407700Y878500D02*
Y882500D01*
X400300D01*
G01X411017Y883500D02*
Y886000D01*
X412058D01*
X412392Y885875D01*
X412600Y885708D01*
X412683Y885375D01*
X412600Y885042D01*
X412350Y884833D01*
X412058Y884708D01*
X411017D01*
G01X412058D02*
X412683Y883500D01*
G01X414158Y884542D02*
X414450Y884833D01*
X414700Y885000D01*
X415033Y885083D01*
X415325Y885000D01*
X415533Y884833D01*
X415700Y884583D01*
X415742Y884292D01*
X415700Y884042D01*
X415533Y883792D01*
X415283Y883583D01*
X414992Y883500D01*
X414658Y883583D01*
X414367Y883833D01*
X414200Y884208D01*
X414158Y884625D01*
X414242Y885167D01*
X414367Y885458D01*
X414575Y885750D01*
X414867Y885958D01*
X415158Y886000D01*
X415450Y885917D01*
X415658Y885708D01*
G01X418550Y883500D02*
Y886000D01*
X417008Y884208D01*
X419092D01*
G01X420233Y883875D02*
X420483Y883667D01*
X420775Y883542D01*
X421150Y883500D01*
X421525Y883583D01*
X421817Y883750D01*
X422025Y884042D01*
X422067Y884375D01*
X421983Y884708D01*
X421775Y884917D01*
X421483Y885083D01*
X421192Y885125D01*
X420900Y885083D01*
X420525Y884917D01*
X420650Y886000D01*
X421775D01*
G01X400300Y887000D02*
Y883000D01*
X407700D01*
G01X405300Y913500D02*
Y909500D01*
X412700D01*
G01X405300Y917500D02*
Y913500D01*
X412700D01*
G01X403975Y948833D02*
X404308Y948625D01*
X404683Y948500D01*
X405017D01*
X405350Y948625D01*
X405600Y948833D01*
X405725Y949125D01*
X405642Y949417D01*
X405433Y949667D01*
X405058Y949833D01*
X404558Y949917D01*
X404267Y950083D01*
X404142Y950375D01*
X404225Y950667D01*
X404433Y950875D01*
X404725Y951000D01*
X405017D01*
X405308Y950917D01*
X405558Y950708D01*
G01X407033Y951000D02*
Y949208D01*
X407200Y948833D01*
X407533Y948583D01*
X407950Y948500D01*
X408367Y948583D01*
X408700Y948833D01*
X408867Y949208D01*
Y951000D01*
G01X411050Y948500D02*
Y951000D01*
X410550Y950500D01*
G01Y948500D02*
X411550D01*
G01X414150D02*
X414442Y948542D01*
X414775Y948667D01*
X414983Y948875D01*
X415067Y949167D01*
X414983Y949458D01*
X414733Y949708D01*
X414358Y949833D01*
X413942D01*
X413692Y949917D01*
X413483Y950125D01*
X413400Y950417D01*
X413525Y950708D01*
X413817Y950917D01*
X414150Y951000D01*
X414483Y950917D01*
X414775Y950708D01*
X414900Y950417D01*
X414817Y950125D01*
X414608Y949917D01*
X414358Y949833D01*
X413942D01*
X413567Y949708D01*
X413317Y949458D01*
X413233Y949167D01*
X413317Y948875D01*
X413525Y948667D01*
X413858Y948542D01*
X414150Y948500D01*
G01X417873Y4692D02*
X422148D01*
G01X417873Y11292D02*
Y4692D01*
G01X422148D02*
G03X432498I5175J1348D01*
G01X436773Y11292D02*
X417873D01*
G01X415500Y39467D02*
X413000D01*
Y40467D01*
X413125Y40800D01*
X413417Y41050D01*
X413750Y41133D01*
X414083Y41050D01*
X414333Y40842D01*
X414458Y40467D01*
Y39467D01*
G01X413208Y44317D02*
X413083Y44067D01*
X413000Y43775D01*
Y43442D01*
X413125Y43067D01*
X413333Y42775D01*
X413583Y42567D01*
X414000Y42400D01*
X414375Y42358D01*
X414750Y42442D01*
X415000Y42567D01*
X415250Y42817D01*
X415417Y43108D01*
X415500Y43400D01*
Y43692D01*
X415417Y43983D01*
X415292Y44233D01*
X415125Y44442D01*
G01X415500Y46500D02*
X413000D01*
X413500Y46000D01*
G01X415500D02*
Y47000D01*
G01X415208Y48892D02*
X415417Y49183D01*
X415500Y49517D01*
X415417Y49850D01*
X415167Y50142D01*
X414792Y50350D01*
X414417Y50433D01*
X413958D01*
X413583Y50350D01*
X413250Y50142D01*
X413083Y49892D01*
X413000Y49600D01*
X413083Y49267D01*
X413250Y49017D01*
X413500Y48850D01*
X413833Y48767D01*
X414125Y48850D01*
X414417Y49058D01*
X414583Y49308D01*
X414625Y49600D01*
X414542Y49933D01*
X414333Y50183D01*
X413958Y50433D01*
G01X415208Y51992D02*
X415417Y52283D01*
X415500Y52617D01*
X415417Y52950D01*
X415167Y53242D01*
X414792Y53450D01*
X414417Y53533D01*
X413958D01*
X413583Y53450D01*
X413250Y53242D01*
X413083Y52992D01*
X413000Y52700D01*
X413083Y52367D01*
X413250Y52117D01*
X413500Y51950D01*
X413833Y51867D01*
X414125Y51950D01*
X414417Y52158D01*
X414583Y52408D01*
X414625Y52700D01*
X414542Y53033D01*
X414333Y53283D01*
X413958Y53533D01*
G01X420167Y39375D02*
X420375Y39708D01*
X420500Y40083D01*
Y40417D01*
X420375Y40750D01*
X420167Y41000D01*
X419875Y41125D01*
X419583Y41042D01*
X419333Y40833D01*
X419167Y40458D01*
X419083Y39958D01*
X418917Y39667D01*
X418625Y39542D01*
X418333Y39625D01*
X418125Y39833D01*
X418000Y40125D01*
Y40417D01*
X418083Y40708D01*
X418292Y40958D01*
G01X418208Y44267D02*
X418083Y44017D01*
X418000Y43725D01*
Y43392D01*
X418125Y43017D01*
X418333Y42725D01*
X418583Y42517D01*
X419000Y42350D01*
X419375Y42308D01*
X419750Y42392D01*
X420000Y42517D01*
X420250Y42767D01*
X420417Y43058D01*
X420500Y43350D01*
Y43642D01*
X420417Y43933D01*
X420292Y44183D01*
X420125Y44392D01*
G01X420500Y46450D02*
X418000D01*
X418500Y45950D01*
G01X420500D02*
Y46950D01*
G01X418000Y49550D02*
X418083Y49217D01*
X418292Y48967D01*
X418542Y48800D01*
X418875Y48675D01*
X419250Y48633D01*
X419625Y48675D01*
X419958Y48800D01*
X420208Y48967D01*
X420417Y49217D01*
X420500Y49550D01*
X420417Y49883D01*
X420208Y50133D01*
X419958Y50300D01*
X419625Y50425D01*
X419250Y50467D01*
X418875Y50425D01*
X418542Y50300D01*
X418292Y50133D01*
X418083Y49883D01*
X418000Y49550D01*
G01X420500Y53150D02*
X418000D01*
X419792Y51608D01*
Y53692D01*
G01X420125Y54833D02*
X420333Y55083D01*
X420458Y55375D01*
X420500Y55750D01*
X420417Y56125D01*
X420250Y56417D01*
X419958Y56625D01*
X419625Y56667D01*
X419292Y56583D01*
X419083Y56375D01*
X418917Y56083D01*
X418875Y55792D01*
X418917Y55500D01*
X419083Y55125D01*
X418000Y55250D01*
Y56375D01*
G01X424167Y39375D02*
X424375Y39708D01*
X424500Y40083D01*
Y40417D01*
X424375Y40750D01*
X424167Y41000D01*
X423875Y41125D01*
X423583Y41042D01*
X423333Y40833D01*
X423167Y40458D01*
X423083Y39958D01*
X422917Y39667D01*
X422625Y39542D01*
X422333Y39625D01*
X422125Y39833D01*
X422000Y40125D01*
Y40417D01*
X422083Y40708D01*
X422292Y40958D01*
G01X422208Y44267D02*
X422083Y44017D01*
X422000Y43725D01*
Y43392D01*
X422125Y43017D01*
X422333Y42725D01*
X422583Y42517D01*
X423000Y42350D01*
X423375Y42308D01*
X423750Y42392D01*
X424000Y42517D01*
X424250Y42767D01*
X424417Y43058D01*
X424500Y43350D01*
Y43642D01*
X424417Y43933D01*
X424292Y44183D01*
X424125Y44392D01*
G01X424500Y46450D02*
X422000D01*
X422500Y45950D01*
G01X424500D02*
Y46950D01*
G01X422000Y49550D02*
X422083Y49217D01*
X422292Y48967D01*
X422542Y48800D01*
X422875Y48675D01*
X423250Y48633D01*
X423625Y48675D01*
X423958Y48800D01*
X424208Y48967D01*
X424417Y49217D01*
X424500Y49550D01*
X424417Y49883D01*
X424208Y50133D01*
X423958Y50300D01*
X423625Y50425D01*
X423250Y50467D01*
X422875Y50425D01*
X422542Y50300D01*
X422292Y50133D01*
X422083Y49883D01*
X422000Y49550D01*
G01X424500Y53150D02*
X422000D01*
X423792Y51608D01*
Y53692D01*
G01X423458Y54958D02*
X423167Y55250D01*
X423000Y55500D01*
X422917Y55833D01*
X423000Y56125D01*
X423167Y56333D01*
X423417Y56500D01*
X423708Y56542D01*
X423958Y56500D01*
X424208Y56333D01*
X424417Y56083D01*
X424500Y55792D01*
X424417Y55458D01*
X424167Y55167D01*
X423792Y55000D01*
X423375Y54958D01*
X422833Y55042D01*
X422542Y55167D01*
X422250Y55375D01*
X422042Y55667D01*
X422000Y55958D01*
X422083Y56250D01*
X422292Y56458D01*
G01X428167Y39375D02*
X428375Y39708D01*
X428500Y40083D01*
Y40417D01*
X428375Y40750D01*
X428167Y41000D01*
X427875Y41125D01*
X427583Y41042D01*
X427333Y40833D01*
X427167Y40458D01*
X427083Y39958D01*
X426917Y39667D01*
X426625Y39542D01*
X426333Y39625D01*
X426125Y39833D01*
X426000Y40125D01*
Y40417D01*
X426083Y40708D01*
X426292Y40958D01*
G01X426208Y44267D02*
X426083Y44017D01*
X426000Y43725D01*
Y43392D01*
X426125Y43017D01*
X426333Y42725D01*
X426583Y42517D01*
X427000Y42350D01*
X427375Y42308D01*
X427750Y42392D01*
X428000Y42517D01*
X428250Y42767D01*
X428417Y43058D01*
X428500Y43350D01*
Y43642D01*
X428417Y43933D01*
X428292Y44183D01*
X428125Y44392D01*
G01X428500Y46450D02*
X426000D01*
X426500Y45950D01*
G01X428500D02*
Y46950D01*
G01X426000Y49550D02*
X426083Y49217D01*
X426292Y48967D01*
X426542Y48800D01*
X426875Y48675D01*
X427250Y48633D01*
X427625Y48675D01*
X427958Y48800D01*
X428208Y48967D01*
X428417Y49217D01*
X428500Y49550D01*
X428417Y49883D01*
X428208Y50133D01*
X427958Y50300D01*
X427625Y50425D01*
X427250Y50467D01*
X426875Y50425D01*
X426542Y50300D01*
X426292Y50133D01*
X426083Y49883D01*
X426000Y49550D01*
G01X428500Y53150D02*
X426000D01*
X427792Y51608D01*
Y53692D01*
G01X428500Y55667D02*
X427958Y55750D01*
X427500Y55875D01*
X427083Y56042D01*
X426625Y56250D01*
X426000Y56583D01*
Y54917D01*
G01X419965Y99833D02*
X420298Y99625D01*
X420673Y99500D01*
X421007D01*
X421340Y99625D01*
X421590Y99833D01*
X421715Y100125D01*
X421632Y100417D01*
X421423Y100667D01*
X421048Y100833D01*
X420548Y100917D01*
X420257Y101083D01*
X420132Y101375D01*
X420215Y101667D01*
X420423Y101875D01*
X420715Y102000D01*
X421007D01*
X421298Y101917D01*
X421548Y101708D01*
G01X423107Y99500D02*
Y102000D01*
X424148D01*
X424482Y101875D01*
X424690Y101708D01*
X424773Y101375D01*
X424690Y101042D01*
X424440Y100833D01*
X424148Y100708D01*
X423107D01*
G01X424148D02*
X424773Y99500D01*
G01X426248Y100542D02*
X426540Y100833D01*
X426790Y101000D01*
X427123Y101083D01*
X427415Y101000D01*
X427623Y100833D01*
X427790Y100583D01*
X427832Y100292D01*
X427790Y100042D01*
X427623Y99792D01*
X427373Y99583D01*
X427082Y99500D01*
X426748Y99583D01*
X426457Y99833D01*
X426290Y100208D01*
X426248Y100625D01*
X426332Y101167D01*
X426457Y101458D01*
X426665Y101750D01*
X426957Y101958D01*
X427248Y102000D01*
X427540Y101917D01*
X427748Y101708D01*
G01X430140Y99500D02*
X430432Y99542D01*
X430765Y99667D01*
X430973Y99875D01*
X431057Y100167D01*
X430973Y100458D01*
X430723Y100708D01*
X430348Y100833D01*
X429932D01*
X429682Y100917D01*
X429473Y101125D01*
X429390Y101417D01*
X429515Y101708D01*
X429807Y101917D01*
X430140Y102000D01*
X430473Y101917D01*
X430765Y101708D01*
X430890Y101417D01*
X430807Y101125D01*
X430598Y100917D01*
X430348Y100833D01*
X429932D01*
X429557Y100708D01*
X429307Y100458D01*
X429223Y100167D01*
X429307Y99875D01*
X429515Y99667D01*
X429848Y99542D01*
X430140Y99500D01*
G01X432323Y100000D02*
X432573Y99708D01*
X432907Y99542D01*
X433282Y99500D01*
X433615Y99542D01*
X433948Y99750D01*
X434157Y100000D01*
X434198Y100250D01*
X434115Y100542D01*
X433823Y100750D01*
X433532Y100833D01*
X433157D01*
G01X433532D02*
X433782Y100958D01*
X433990Y101167D01*
X434073Y101417D01*
X433990Y101667D01*
X433782Y101875D01*
X433407Y102000D01*
X433032Y101958D01*
X432657Y101792D01*
G01X419854Y94833D02*
X420187Y94625D01*
X420562Y94500D01*
X420896D01*
X421229Y94625D01*
X421479Y94833D01*
X421604Y95125D01*
X421521Y95417D01*
X421312Y95667D01*
X420937Y95833D01*
X420437Y95917D01*
X420146Y96083D01*
X420021Y96375D01*
X420104Y96667D01*
X420312Y96875D01*
X420604Y97000D01*
X420896D01*
X421187Y96917D01*
X421437Y96708D01*
G01X422996Y94500D02*
Y97000D01*
X424037D01*
X424371Y96875D01*
X424579Y96708D01*
X424662Y96375D01*
X424579Y96042D01*
X424329Y95833D01*
X424037Y95708D01*
X422996D01*
G01X424037D02*
X424662Y94500D01*
G01X426137Y95542D02*
X426429Y95833D01*
X426679Y96000D01*
X427012Y96083D01*
X427304Y96000D01*
X427512Y95833D01*
X427679Y95583D01*
X427721Y95292D01*
X427679Y95042D01*
X427512Y94792D01*
X427262Y94583D01*
X426971Y94500D01*
X426637Y94583D01*
X426346Y94833D01*
X426179Y95208D01*
X426137Y95625D01*
X426221Y96167D01*
X426346Y96458D01*
X426554Y96750D01*
X426846Y96958D01*
X427137Y97000D01*
X427429Y96917D01*
X427637Y96708D01*
G01X430029Y94500D02*
X430321Y94542D01*
X430654Y94667D01*
X430862Y94875D01*
X430946Y95167D01*
X430862Y95458D01*
X430612Y95708D01*
X430237Y95833D01*
X429821D01*
X429571Y95917D01*
X429362Y96125D01*
X429279Y96417D01*
X429404Y96708D01*
X429696Y96917D01*
X430029Y97000D01*
X430362Y96917D01*
X430654Y96708D01*
X430779Y96417D01*
X430696Y96125D01*
X430487Y95917D01*
X430237Y95833D01*
X429821D01*
X429446Y95708D01*
X429196Y95458D01*
X429112Y95167D01*
X429196Y94875D01*
X429404Y94667D01*
X429737Y94542D01*
X430029Y94500D01*
G01X432212Y94875D02*
X432462Y94667D01*
X432754Y94542D01*
X433129Y94500D01*
X433504Y94583D01*
X433796Y94750D01*
X434004Y95042D01*
X434046Y95375D01*
X433962Y95708D01*
X433754Y95917D01*
X433462Y96083D01*
X433171Y96125D01*
X432879Y96083D01*
X432504Y95917D01*
X432629Y97000D01*
X433754D01*
G01X417596Y93425D02*
X417804Y93758D01*
X417929Y94133D01*
Y94467D01*
X417804Y94800D01*
X417596Y95050D01*
X417304Y95175D01*
X417012Y95092D01*
X416762Y94883D01*
X416596Y94508D01*
X416512Y94008D01*
X416346Y93717D01*
X416054Y93592D01*
X415762Y93675D01*
X415554Y93883D01*
X415429Y94175D01*
Y94467D01*
X415512Y94758D01*
X415721Y95008D01*
G01X417929Y96567D02*
X415429D01*
Y97608D01*
X415554Y97942D01*
X415721Y98150D01*
X416054Y98233D01*
X416387Y98150D01*
X416596Y97900D01*
X416721Y97608D01*
Y96567D01*
G01Y97608D02*
X417929Y98233D01*
G01X416887Y99708D02*
X416596Y100000D01*
X416429Y100250D01*
X416346Y100583D01*
X416429Y100875D01*
X416596Y101083D01*
X416846Y101250D01*
X417137Y101292D01*
X417387Y101250D01*
X417637Y101083D01*
X417846Y100833D01*
X417929Y100542D01*
X417846Y100208D01*
X417596Y99917D01*
X417221Y99750D01*
X416804Y99708D01*
X416262Y99792D01*
X415971Y99917D01*
X415679Y100125D01*
X415471Y100417D01*
X415429Y100708D01*
X415512Y101000D01*
X415721Y101208D01*
G01X417929Y103600D02*
X417887Y103892D01*
X417762Y104225D01*
X417554Y104433D01*
X417262Y104517D01*
X416971Y104433D01*
X416721Y104183D01*
X416596Y103808D01*
Y103392D01*
X416512Y103142D01*
X416304Y102933D01*
X416012Y102850D01*
X415721Y102975D01*
X415512Y103267D01*
X415429Y103600D01*
X415512Y103933D01*
X415721Y104225D01*
X416012Y104350D01*
X416304Y104267D01*
X416512Y104058D01*
X416596Y103808D01*
Y103392D01*
X416721Y103017D01*
X416971Y102767D01*
X417262Y102683D01*
X417554Y102767D01*
X417762Y102975D01*
X417887Y103308D01*
X417929Y103600D01*
G01Y106617D02*
X417387Y106700D01*
X416929Y106825D01*
X416512Y106992D01*
X416054Y107200D01*
X415429Y107533D01*
Y105867D01*
G01X423800Y238500D02*
Y234500D01*
X431200D01*
G01X426929Y255100D02*
X422929D01*
Y247700D01*
G01X422429Y255100D02*
X418429D01*
Y247700D01*
G01X427429Y255700D02*
X431429D01*
Y263100D01*
G01X426700Y266000D02*
Y270000D01*
X419300D01*
G01X418429Y255700D02*
X422429D01*
Y263100D01*
G01X426929D02*
X422929D01*
Y255700D01*
G01X428455Y285200D02*
Y289200D01*
X421055D01*
G01X428455Y273200D02*
Y277200D01*
X421055D01*
G01Y285200D02*
Y281200D01*
X428455D01*
G01X421055D02*
Y277200D01*
X428455D01*
G01X425055Y299200D02*
X421055D01*
Y291800D01*
G01X425555Y289800D02*
X429555D01*
Y297200D01*
G01X420555Y304700D02*
X416555D01*
Y297300D01*
G01X427222Y455375D02*
X427430Y455708D01*
X427555Y456083D01*
Y456417D01*
X427430Y456750D01*
X427222Y457000D01*
X426930Y457125D01*
X426638Y457042D01*
X426388Y456833D01*
X426222Y456458D01*
X426138Y455958D01*
X425972Y455667D01*
X425680Y455542D01*
X425388Y455625D01*
X425180Y455833D01*
X425055Y456125D01*
Y456417D01*
X425138Y456708D01*
X425347Y456958D01*
G01X425263Y460267D02*
X425138Y460017D01*
X425055Y459725D01*
Y459392D01*
X425180Y459017D01*
X425388Y458725D01*
X425638Y458517D01*
X426055Y458350D01*
X426430Y458308D01*
X426805Y458392D01*
X427055Y458517D01*
X427305Y458767D01*
X427472Y459058D01*
X427555Y459350D01*
Y459642D01*
X427472Y459933D01*
X427347Y460183D01*
X427180Y460392D01*
G01X427555Y462450D02*
X425055D01*
X425555Y461950D01*
G01X427555D02*
Y462950D01*
G01X425055Y465550D02*
X425138Y465217D01*
X425347Y464967D01*
X425597Y464800D01*
X425930Y464675D01*
X426305Y464633D01*
X426680Y464675D01*
X427013Y464800D01*
X427263Y464967D01*
X427472Y465217D01*
X427555Y465550D01*
X427472Y465883D01*
X427263Y466133D01*
X427013Y466300D01*
X426680Y466425D01*
X426305Y466467D01*
X425930Y466425D01*
X425597Y466300D01*
X425347Y466133D01*
X425138Y465883D01*
X425055Y465550D01*
G01X427555Y468650D02*
X427513Y468942D01*
X427388Y469275D01*
X427180Y469483D01*
X426888Y469567D01*
X426597Y469483D01*
X426347Y469233D01*
X426222Y468858D01*
Y468442D01*
X426138Y468192D01*
X425930Y467983D01*
X425638Y467900D01*
X425347Y468025D01*
X425138Y468317D01*
X425055Y468650D01*
X425138Y468983D01*
X425347Y469275D01*
X425638Y469400D01*
X425930Y469317D01*
X426138Y469108D01*
X426222Y468858D01*
Y468442D01*
X426347Y468067D01*
X426597Y467817D01*
X426888Y467733D01*
X427180Y467817D01*
X427388Y468025D01*
X427513Y468358D01*
X427555Y468650D01*
G01X427055Y470833D02*
X427347Y471083D01*
X427513Y471417D01*
X427555Y471792D01*
X427513Y472125D01*
X427305Y472458D01*
X427055Y472667D01*
X426805Y472708D01*
X426513Y472625D01*
X426305Y472333D01*
X426222Y472042D01*
Y471667D01*
G01Y472042D02*
X426097Y472292D01*
X425888Y472500D01*
X425638Y472583D01*
X425388Y472500D01*
X425180Y472292D01*
X425055Y471917D01*
X425097Y471542D01*
X425263Y471167D01*
G01X423222Y455375D02*
X423430Y455708D01*
X423555Y456083D01*
Y456417D01*
X423430Y456750D01*
X423222Y457000D01*
X422930Y457125D01*
X422638Y457042D01*
X422388Y456833D01*
X422222Y456458D01*
X422138Y455958D01*
X421972Y455667D01*
X421680Y455542D01*
X421388Y455625D01*
X421180Y455833D01*
X421055Y456125D01*
Y456417D01*
X421138Y456708D01*
X421347Y456958D01*
G01X421263Y460267D02*
X421138Y460017D01*
X421055Y459725D01*
Y459392D01*
X421180Y459017D01*
X421388Y458725D01*
X421638Y458517D01*
X422055Y458350D01*
X422430Y458308D01*
X422805Y458392D01*
X423055Y458517D01*
X423305Y458767D01*
X423472Y459058D01*
X423555Y459350D01*
Y459642D01*
X423472Y459933D01*
X423347Y460183D01*
X423180Y460392D01*
G01X423555Y462450D02*
X421055D01*
X421555Y461950D01*
G01X423555D02*
Y462950D01*
G01X421055Y465550D02*
X421138Y465217D01*
X421347Y464967D01*
X421597Y464800D01*
X421930Y464675D01*
X422305Y464633D01*
X422680Y464675D01*
X423013Y464800D01*
X423263Y464967D01*
X423472Y465217D01*
X423555Y465550D01*
X423472Y465883D01*
X423263Y466133D01*
X423013Y466300D01*
X422680Y466425D01*
X422305Y466467D01*
X421930Y466425D01*
X421597Y466300D01*
X421347Y466133D01*
X421138Y465883D01*
X421055Y465550D01*
G01X423555Y468650D02*
X423513Y468942D01*
X423388Y469275D01*
X423180Y469483D01*
X422888Y469567D01*
X422597Y469483D01*
X422347Y469233D01*
X422222Y468858D01*
Y468442D01*
X422138Y468192D01*
X421930Y467983D01*
X421638Y467900D01*
X421347Y468025D01*
X421138Y468317D01*
X421055Y468650D01*
X421138Y468983D01*
X421347Y469275D01*
X421638Y469400D01*
X421930Y469317D01*
X422138Y469108D01*
X422222Y468858D01*
Y468442D01*
X422347Y468067D01*
X422597Y467817D01*
X422888Y467733D01*
X423180Y467817D01*
X423388Y468025D01*
X423513Y468358D01*
X423555Y468650D01*
G01Y472250D02*
X421055D01*
X422847Y470708D01*
Y472792D01*
G01X419222Y455375D02*
X419430Y455708D01*
X419555Y456083D01*
Y456417D01*
X419430Y456750D01*
X419222Y457000D01*
X418930Y457125D01*
X418638Y457042D01*
X418388Y456833D01*
X418222Y456458D01*
X418138Y455958D01*
X417972Y455667D01*
X417680Y455542D01*
X417388Y455625D01*
X417180Y455833D01*
X417055Y456125D01*
Y456417D01*
X417138Y456708D01*
X417347Y456958D01*
G01X417263Y460267D02*
X417138Y460017D01*
X417055Y459725D01*
Y459392D01*
X417180Y459017D01*
X417388Y458725D01*
X417638Y458517D01*
X418055Y458350D01*
X418430Y458308D01*
X418805Y458392D01*
X419055Y458517D01*
X419305Y458767D01*
X419472Y459058D01*
X419555Y459350D01*
Y459642D01*
X419472Y459933D01*
X419347Y460183D01*
X419180Y460392D01*
G01X419555Y462450D02*
X417055D01*
X417555Y461950D01*
G01X419555D02*
Y462950D01*
G01X417055Y465550D02*
X417138Y465217D01*
X417347Y464967D01*
X417597Y464800D01*
X417930Y464675D01*
X418305Y464633D01*
X418680Y464675D01*
X419013Y464800D01*
X419263Y464967D01*
X419472Y465217D01*
X419555Y465550D01*
X419472Y465883D01*
X419263Y466133D01*
X419013Y466300D01*
X418680Y466425D01*
X418305Y466467D01*
X417930Y466425D01*
X417597Y466300D01*
X417347Y466133D01*
X417138Y465883D01*
X417055Y465550D01*
G01X419555Y468650D02*
X419513Y468942D01*
X419388Y469275D01*
X419180Y469483D01*
X418888Y469567D01*
X418597Y469483D01*
X418347Y469233D01*
X418222Y468858D01*
Y468442D01*
X418138Y468192D01*
X417930Y467983D01*
X417638Y467900D01*
X417347Y468025D01*
X417138Y468317D01*
X417055Y468650D01*
X417138Y468983D01*
X417347Y469275D01*
X417638Y469400D01*
X417930Y469317D01*
X418138Y469108D01*
X418222Y468858D01*
Y468442D01*
X418347Y468067D01*
X418597Y467817D01*
X418888Y467733D01*
X419180Y467817D01*
X419388Y468025D01*
X419513Y468358D01*
X419555Y468650D01*
G01X419180Y470833D02*
X419388Y471083D01*
X419513Y471375D01*
X419555Y471750D01*
X419472Y472125D01*
X419305Y472417D01*
X419013Y472625D01*
X418680Y472667D01*
X418347Y472583D01*
X418138Y472375D01*
X417972Y472083D01*
X417930Y471792D01*
X417972Y471500D01*
X418138Y471125D01*
X417055Y471250D01*
Y472375D01*
G01X415222Y455375D02*
X415430Y455708D01*
X415555Y456083D01*
Y456417D01*
X415430Y456750D01*
X415222Y457000D01*
X414930Y457125D01*
X414638Y457042D01*
X414388Y456833D01*
X414222Y456458D01*
X414138Y455958D01*
X413972Y455667D01*
X413680Y455542D01*
X413388Y455625D01*
X413180Y455833D01*
X413055Y456125D01*
Y456417D01*
X413138Y456708D01*
X413347Y456958D01*
G01X413263Y460267D02*
X413138Y460017D01*
X413055Y459725D01*
Y459392D01*
X413180Y459017D01*
X413388Y458725D01*
X413638Y458517D01*
X414055Y458350D01*
X414430Y458308D01*
X414805Y458392D01*
X415055Y458517D01*
X415305Y458767D01*
X415472Y459058D01*
X415555Y459350D01*
Y459642D01*
X415472Y459933D01*
X415347Y460183D01*
X415180Y460392D01*
G01X415555Y462450D02*
X413055D01*
X413555Y461950D01*
G01X415555D02*
Y462950D01*
G01X413055Y465550D02*
X413138Y465217D01*
X413347Y464967D01*
X413597Y464800D01*
X413930Y464675D01*
X414305Y464633D01*
X414680Y464675D01*
X415013Y464800D01*
X415263Y464967D01*
X415472Y465217D01*
X415555Y465550D01*
X415472Y465883D01*
X415263Y466133D01*
X415013Y466300D01*
X414680Y466425D01*
X414305Y466467D01*
X413930Y466425D01*
X413597Y466300D01*
X413347Y466133D01*
X413138Y465883D01*
X413055Y465550D01*
G01X415555Y468650D02*
X415513Y468942D01*
X415388Y469275D01*
X415180Y469483D01*
X414888Y469567D01*
X414597Y469483D01*
X414347Y469233D01*
X414222Y468858D01*
Y468442D01*
X414138Y468192D01*
X413930Y467983D01*
X413638Y467900D01*
X413347Y468025D01*
X413138Y468317D01*
X413055Y468650D01*
X413138Y468983D01*
X413347Y469275D01*
X413638Y469400D01*
X413930Y469317D01*
X414138Y469108D01*
X414222Y468858D01*
Y468442D01*
X414347Y468067D01*
X414597Y467817D01*
X414888Y467733D01*
X415180Y467817D01*
X415388Y468025D01*
X415513Y468358D01*
X415555Y468650D01*
G01X414513Y470958D02*
X414222Y471250D01*
X414055Y471500D01*
X413972Y471833D01*
X414055Y472125D01*
X414222Y472333D01*
X414472Y472500D01*
X414763Y472542D01*
X415013Y472500D01*
X415263Y472333D01*
X415472Y472083D01*
X415555Y471792D01*
X415472Y471458D01*
X415222Y471167D01*
X414847Y471000D01*
X414430Y470958D01*
X413888Y471042D01*
X413597Y471167D01*
X413305Y471375D01*
X413097Y471667D01*
X413055Y471958D01*
X413138Y472250D01*
X413347Y472458D01*
G01X416517Y910000D02*
Y912500D01*
X417558D01*
X417892Y912375D01*
X418100Y912208D01*
X418183Y911875D01*
X418100Y911542D01*
X417850Y911333D01*
X417558Y911208D01*
X416517D01*
G01X417558D02*
X418183Y910000D01*
G01X419658Y911042D02*
X419950Y911333D01*
X420200Y911500D01*
X420533Y911583D01*
X420825Y911500D01*
X421033Y911333D01*
X421200Y911083D01*
X421242Y910792D01*
X421200Y910542D01*
X421033Y910292D01*
X420783Y910083D01*
X420492Y910000D01*
X420158Y910083D01*
X419867Y910333D01*
X419700Y910708D01*
X419658Y911125D01*
X419742Y911667D01*
X419867Y911958D01*
X420075Y912250D01*
X420367Y912458D01*
X420658Y912500D01*
X420950Y912417D01*
X421158Y912208D01*
G01X422758Y912083D02*
X423008Y912333D01*
X423300Y912458D01*
X423633Y912500D01*
X424050Y912417D01*
X424342Y912208D01*
X424425Y911958D01*
X424383Y911708D01*
X424217Y911500D01*
X423383Y911083D01*
X423008Y910792D01*
X422758Y910375D01*
X422675Y910000D01*
X424425D01*
G01X426650D02*
X426942Y910042D01*
X427275Y910167D01*
X427483Y910375D01*
X427567Y910667D01*
X427483Y910958D01*
X427233Y911208D01*
X426858Y911333D01*
X426442D01*
X426192Y911417D01*
X425983Y911625D01*
X425900Y911917D01*
X426025Y912208D01*
X426317Y912417D01*
X426650Y912500D01*
X426983Y912417D01*
X427275Y912208D01*
X427400Y911917D01*
X427317Y911625D01*
X427108Y911417D01*
X426858Y911333D01*
X426442D01*
X426067Y911208D01*
X425817Y910958D01*
X425733Y910667D01*
X425817Y910375D01*
X426025Y910167D01*
X426358Y910042D01*
X426650Y910000D01*
G01X421100Y926300D02*
Y938700D01*
G01D02*
Y926300D01*
G01X416517Y914000D02*
Y916500D01*
X417558D01*
X417892Y916375D01*
X418100Y916208D01*
X418183Y915875D01*
X418100Y915542D01*
X417850Y915333D01*
X417558Y915208D01*
X416517D01*
G01X417558D02*
X418183Y914000D01*
G01X419533Y914375D02*
X419783Y914167D01*
X420075Y914042D01*
X420450Y914000D01*
X420825Y914083D01*
X421117Y914250D01*
X421325Y914542D01*
X421367Y914875D01*
X421283Y915208D01*
X421075Y915417D01*
X420783Y915583D01*
X420492Y915625D01*
X420200Y915583D01*
X419825Y915417D01*
X419950Y916500D01*
X421075D01*
G01X422842Y914292D02*
X423133Y914083D01*
X423467Y914000D01*
X423800Y914083D01*
X424092Y914333D01*
X424300Y914708D01*
X424383Y915083D01*
Y915542D01*
X424300Y915917D01*
X424092Y916250D01*
X423842Y916417D01*
X423550Y916500D01*
X423217Y916417D01*
X422967Y916250D01*
X422800Y916000D01*
X422717Y915667D01*
X422800Y915375D01*
X423008Y915083D01*
X423258Y914917D01*
X423550Y914875D01*
X423883Y914958D01*
X424133Y915167D01*
X424383Y915542D01*
G01X425733Y914375D02*
X425983Y914167D01*
X426275Y914042D01*
X426650Y914000D01*
X427025Y914083D01*
X427317Y914250D01*
X427525Y914542D01*
X427567Y914875D01*
X427483Y915208D01*
X427275Y915417D01*
X426983Y915583D01*
X426692Y915625D01*
X426400Y915583D01*
X426025Y915417D01*
X426150Y916500D01*
X427275D01*
G01X425300Y943500D02*
Y939500D01*
X432700D01*
G01X421925Y949833D02*
X422258Y949625D01*
X422633Y949500D01*
X422967D01*
X423300Y949625D01*
X423550Y949833D01*
X423675Y950125D01*
X423592Y950417D01*
X423383Y950667D01*
X423008Y950833D01*
X422508Y950917D01*
X422217Y951083D01*
X422092Y951375D01*
X422175Y951667D01*
X422383Y951875D01*
X422675Y952000D01*
X422967D01*
X423258Y951917D01*
X423508Y951708D01*
G01X425067Y949500D02*
Y952000D01*
X426108D01*
X426442Y951875D01*
X426650Y951708D01*
X426733Y951375D01*
X426650Y951042D01*
X426400Y950833D01*
X426108Y950708D01*
X425067D01*
G01X426108D02*
X426733Y949500D01*
G01X428292Y949792D02*
X428583Y949583D01*
X428917Y949500D01*
X429250Y949583D01*
X429542Y949833D01*
X429750Y950208D01*
X429833Y950583D01*
Y951042D01*
X429750Y951417D01*
X429542Y951750D01*
X429292Y951917D01*
X429000Y952000D01*
X428667Y951917D01*
X428417Y951750D01*
X428250Y951500D01*
X428167Y951167D01*
X428250Y950875D01*
X428458Y950583D01*
X428708Y950417D01*
X429000Y950375D01*
X429333Y950458D01*
X429583Y950667D01*
X429833Y951042D01*
G01X432600Y949500D02*
Y952000D01*
X431058Y950208D01*
X433142D01*
G01X435200Y949500D02*
X435492Y949542D01*
X435825Y949667D01*
X436033Y949875D01*
X436117Y950167D01*
X436033Y950458D01*
X435783Y950708D01*
X435408Y950833D01*
X434992D01*
X434742Y950917D01*
X434533Y951125D01*
X434450Y951417D01*
X434575Y951708D01*
X434867Y951917D01*
X435200Y952000D01*
X435533Y951917D01*
X435825Y951708D01*
X435950Y951417D01*
X435867Y951125D01*
X435658Y950917D01*
X435408Y950833D01*
X434992D01*
X434617Y950708D01*
X434367Y950458D01*
X434283Y950167D01*
X434367Y949875D01*
X434575Y949667D01*
X434908Y949542D01*
X435200Y949500D01*
G01X421925Y953833D02*
X422258Y953625D01*
X422633Y953500D01*
X422967D01*
X423300Y953625D01*
X423550Y953833D01*
X423675Y954125D01*
X423592Y954417D01*
X423383Y954667D01*
X423008Y954833D01*
X422508Y954917D01*
X422217Y955083D01*
X422092Y955375D01*
X422175Y955667D01*
X422383Y955875D01*
X422675Y956000D01*
X422967D01*
X423258Y955917D01*
X423508Y955708D01*
G01X425067Y953500D02*
Y956000D01*
X426108D01*
X426442Y955875D01*
X426650Y955708D01*
X426733Y955375D01*
X426650Y955042D01*
X426400Y954833D01*
X426108Y954708D01*
X425067D01*
G01X426108D02*
X426733Y953500D01*
G01X428292Y953792D02*
X428583Y953583D01*
X428917Y953500D01*
X429250Y953583D01*
X429542Y953833D01*
X429750Y954208D01*
X429833Y954583D01*
Y955042D01*
X429750Y955417D01*
X429542Y955750D01*
X429292Y955917D01*
X429000Y956000D01*
X428667Y955917D01*
X428417Y955750D01*
X428250Y955500D01*
X428167Y955167D01*
X428250Y954875D01*
X428458Y954583D01*
X428708Y954417D01*
X429000Y954375D01*
X429333Y954458D01*
X429583Y954667D01*
X429833Y955042D01*
G01X432600Y953500D02*
Y956000D01*
X431058Y954208D01*
X433142D01*
G01X434492Y953792D02*
X434783Y953583D01*
X435117Y953500D01*
X435450Y953583D01*
X435742Y953833D01*
X435950Y954208D01*
X436033Y954583D01*
Y955042D01*
X435950Y955417D01*
X435742Y955750D01*
X435492Y955917D01*
X435200Y956000D01*
X434867Y955917D01*
X434617Y955750D01*
X434450Y955500D01*
X434367Y955167D01*
X434450Y954875D01*
X434658Y954583D01*
X434908Y954417D01*
X435200Y954375D01*
X435533Y954458D01*
X435783Y954667D01*
X436033Y955042D01*
G01X425300Y947500D02*
Y943500D01*
X432700D01*
G01X443517Y9000D02*
Y6500D01*
X445183D01*
G01X448283D02*
X446617D01*
Y9000D01*
X448283D01*
G01X447617Y7792D02*
X446617D01*
G01X449633Y6500D02*
Y9000D01*
X450467D01*
X450800Y8875D01*
X451050Y8708D01*
X451258Y8458D01*
X451425Y8167D01*
X451467Y7750D01*
X451425Y7333D01*
X451258Y7042D01*
X451050Y6792D01*
X450800Y6625D01*
X450467Y6500D01*
X449633D01*
G01X454150D02*
Y9000D01*
X452608Y7208D01*
X454692D01*
G01X436773Y4692D02*
Y11292D01*
G01X432498Y4692D02*
X436773D01*
G01X434950Y21500D02*
X434617Y21542D01*
X434325Y21708D01*
X434075Y21958D01*
X433908Y22250D01*
X433825Y22583D01*
Y22917D01*
X433908Y23250D01*
X434075Y23542D01*
X434325Y23792D01*
X434617Y23958D01*
X434950Y24000D01*
X435283Y23958D01*
X435575Y23792D01*
X435825Y23542D01*
X435992Y23250D01*
X436075Y22917D01*
Y22583D01*
X435992Y22250D01*
X435825Y21958D01*
X435575Y21708D01*
X435283Y21542D01*
X434950Y21500D01*
G01X435283Y22167D02*
X435783Y21500D01*
G01X438550D02*
Y24000D01*
X437008Y22208D01*
X439092D01*
G01X444240Y104000D02*
Y108000D01*
X436840D01*
G01X436540Y111700D02*
X432540D01*
Y104300D01*
G01X451700Y108000D02*
Y112000D01*
X444300D01*
G01X451700Y104000D02*
Y108000D01*
X444300D01*
G01X444240D02*
Y112000D01*
X436840D01*
G01X437240Y115500D02*
Y119500D01*
X429840D01*
G01X451700Y112500D02*
Y116500D01*
X444300D01*
G01X445748Y127952D02*
G02I-1850J0D01*
G01Y226378D02*
G02I-1850J0D01*
G01X442000Y241700D02*
X438000D01*
Y234300D01*
G01X431500D02*
X435500D01*
Y241700D01*
G01X430500Y271000D02*
X440000D01*
Y250500D01*
X436000D01*
Y246500D01*
G01X444200Y242000D02*
Y246000D01*
X436800D01*
G01X440000Y267500D02*
X453500D01*
Y266000D01*
X497500D01*
Y293000D01*
X517000D01*
Y287000D01*
X527000D01*
G01X435929Y263100D02*
X431929D01*
Y255700D01*
G01X440000Y271000D02*
X455500D01*
Y273000D01*
G01X445855Y284150D02*
X437855D01*
Y272200D01*
X445855D01*
Y284150D01*
G01X439705Y272200D02*
X441705Y274200D01*
X443705Y272200D01*
G01X440455Y288000D02*
X429655D01*
Y293200D01*
X440455D01*
Y288000D01*
G01X443222Y455375D02*
X443430Y455708D01*
X443555Y456083D01*
Y456417D01*
X443430Y456750D01*
X443222Y457000D01*
X442930Y457125D01*
X442638Y457042D01*
X442388Y456833D01*
X442222Y456458D01*
X442138Y455958D01*
X441972Y455667D01*
X441680Y455542D01*
X441388Y455625D01*
X441180Y455833D01*
X441055Y456125D01*
Y456417D01*
X441138Y456708D01*
X441347Y456958D01*
G01X441263Y460267D02*
X441138Y460017D01*
X441055Y459725D01*
Y459392D01*
X441180Y459017D01*
X441388Y458725D01*
X441638Y458517D01*
X442055Y458350D01*
X442430Y458308D01*
X442805Y458392D01*
X443055Y458517D01*
X443305Y458767D01*
X443472Y459058D01*
X443555Y459350D01*
Y459642D01*
X443472Y459933D01*
X443347Y460183D01*
X443180Y460392D01*
G01X443555Y462450D02*
X441055D01*
X441555Y461950D01*
G01X443555D02*
Y462950D01*
G01X441055Y465550D02*
X441138Y465217D01*
X441347Y464967D01*
X441597Y464800D01*
X441930Y464675D01*
X442305Y464633D01*
X442680Y464675D01*
X443013Y464800D01*
X443263Y464967D01*
X443472Y465217D01*
X443555Y465550D01*
X443472Y465883D01*
X443263Y466133D01*
X443013Y466300D01*
X442680Y466425D01*
X442305Y466467D01*
X441930Y466425D01*
X441597Y466300D01*
X441347Y466133D01*
X441138Y465883D01*
X441055Y465550D01*
G01X443555Y468567D02*
X443013Y468650D01*
X442555Y468775D01*
X442138Y468942D01*
X441680Y469150D01*
X441055Y469483D01*
Y467817D01*
G01X443263Y471042D02*
X443472Y471333D01*
X443555Y471667D01*
X443472Y472000D01*
X443222Y472292D01*
X442847Y472500D01*
X442472Y472583D01*
X442013D01*
X441638Y472500D01*
X441305Y472292D01*
X441138Y472042D01*
X441055Y471750D01*
X441138Y471417D01*
X441305Y471167D01*
X441555Y471000D01*
X441888Y470917D01*
X442180Y471000D01*
X442472Y471208D01*
X442638Y471458D01*
X442680Y471750D01*
X442597Y472083D01*
X442388Y472333D01*
X442013Y472583D01*
G01X439222Y455375D02*
X439430Y455708D01*
X439555Y456083D01*
Y456417D01*
X439430Y456750D01*
X439222Y457000D01*
X438930Y457125D01*
X438638Y457042D01*
X438388Y456833D01*
X438222Y456458D01*
X438138Y455958D01*
X437972Y455667D01*
X437680Y455542D01*
X437388Y455625D01*
X437180Y455833D01*
X437055Y456125D01*
Y456417D01*
X437138Y456708D01*
X437347Y456958D01*
G01X437263Y460267D02*
X437138Y460017D01*
X437055Y459725D01*
Y459392D01*
X437180Y459017D01*
X437388Y458725D01*
X437638Y458517D01*
X438055Y458350D01*
X438430Y458308D01*
X438805Y458392D01*
X439055Y458517D01*
X439305Y458767D01*
X439472Y459058D01*
X439555Y459350D01*
Y459642D01*
X439472Y459933D01*
X439347Y460183D01*
X439180Y460392D01*
G01X439555Y462450D02*
X437055D01*
X437555Y461950D01*
G01X439555D02*
Y462950D01*
G01X437055Y465550D02*
X437138Y465217D01*
X437347Y464967D01*
X437597Y464800D01*
X437930Y464675D01*
X438305Y464633D01*
X438680Y464675D01*
X439013Y464800D01*
X439263Y464967D01*
X439472Y465217D01*
X439555Y465550D01*
X439472Y465883D01*
X439263Y466133D01*
X439013Y466300D01*
X438680Y466425D01*
X438305Y466467D01*
X437930Y466425D01*
X437597Y466300D01*
X437347Y466133D01*
X437138Y465883D01*
X437055Y465550D01*
G01X439555Y468650D02*
X439513Y468942D01*
X439388Y469275D01*
X439180Y469483D01*
X438888Y469567D01*
X438597Y469483D01*
X438347Y469233D01*
X438222Y468858D01*
Y468442D01*
X438138Y468192D01*
X437930Y467983D01*
X437638Y467900D01*
X437347Y468025D01*
X437138Y468317D01*
X437055Y468650D01*
X437138Y468983D01*
X437347Y469275D01*
X437638Y469400D01*
X437930Y469317D01*
X438138Y469108D01*
X438222Y468858D01*
Y468442D01*
X438347Y468067D01*
X438597Y467817D01*
X438888Y467733D01*
X439180Y467817D01*
X439388Y468025D01*
X439513Y468358D01*
X439555Y468650D01*
G01X437055Y471750D02*
X437138Y471417D01*
X437347Y471167D01*
X437597Y471000D01*
X437930Y470875D01*
X438305Y470833D01*
X438680Y470875D01*
X439013Y471000D01*
X439263Y471167D01*
X439472Y471417D01*
X439555Y471750D01*
X439472Y472083D01*
X439263Y472333D01*
X439013Y472500D01*
X438680Y472625D01*
X438305Y472667D01*
X437930Y472625D01*
X437597Y472500D01*
X437347Y472333D01*
X437138Y472083D01*
X437055Y471750D01*
G01X435222Y455375D02*
X435430Y455708D01*
X435555Y456083D01*
Y456417D01*
X435430Y456750D01*
X435222Y457000D01*
X434930Y457125D01*
X434638Y457042D01*
X434388Y456833D01*
X434222Y456458D01*
X434138Y455958D01*
X433972Y455667D01*
X433680Y455542D01*
X433388Y455625D01*
X433180Y455833D01*
X433055Y456125D01*
Y456417D01*
X433138Y456708D01*
X433347Y456958D01*
G01X433263Y460267D02*
X433138Y460017D01*
X433055Y459725D01*
Y459392D01*
X433180Y459017D01*
X433388Y458725D01*
X433638Y458517D01*
X434055Y458350D01*
X434430Y458308D01*
X434805Y458392D01*
X435055Y458517D01*
X435305Y458767D01*
X435472Y459058D01*
X435555Y459350D01*
Y459642D01*
X435472Y459933D01*
X435347Y460183D01*
X435180Y460392D01*
G01X435555Y462450D02*
X433055D01*
X433555Y461950D01*
G01X435555D02*
Y462950D01*
G01X433055Y465550D02*
X433138Y465217D01*
X433347Y464967D01*
X433597Y464800D01*
X433930Y464675D01*
X434305Y464633D01*
X434680Y464675D01*
X435013Y464800D01*
X435263Y464967D01*
X435472Y465217D01*
X435555Y465550D01*
X435472Y465883D01*
X435263Y466133D01*
X435013Y466300D01*
X434680Y466425D01*
X434305Y466467D01*
X433930Y466425D01*
X433597Y466300D01*
X433347Y466133D01*
X433138Y465883D01*
X433055Y465550D01*
G01X435555Y468650D02*
X435513Y468942D01*
X435388Y469275D01*
X435180Y469483D01*
X434888Y469567D01*
X434597Y469483D01*
X434347Y469233D01*
X434222Y468858D01*
Y468442D01*
X434138Y468192D01*
X433930Y467983D01*
X433638Y467900D01*
X433347Y468025D01*
X433138Y468317D01*
X433055Y468650D01*
X433138Y468983D01*
X433347Y469275D01*
X433638Y469400D01*
X433930Y469317D01*
X434138Y469108D01*
X434222Y468858D01*
Y468442D01*
X434347Y468067D01*
X434597Y467817D01*
X434888Y467733D01*
X435180Y467817D01*
X435388Y468025D01*
X435513Y468358D01*
X435555Y468650D01*
G01Y471750D02*
X433055D01*
X433555Y471250D01*
G01X435555D02*
Y472250D01*
G01X431222Y455375D02*
X431430Y455708D01*
X431555Y456083D01*
Y456417D01*
X431430Y456750D01*
X431222Y457000D01*
X430930Y457125D01*
X430638Y457042D01*
X430388Y456833D01*
X430222Y456458D01*
X430138Y455958D01*
X429972Y455667D01*
X429680Y455542D01*
X429388Y455625D01*
X429180Y455833D01*
X429055Y456125D01*
Y456417D01*
X429138Y456708D01*
X429347Y456958D01*
G01X429263Y460267D02*
X429138Y460017D01*
X429055Y459725D01*
Y459392D01*
X429180Y459017D01*
X429388Y458725D01*
X429638Y458517D01*
X430055Y458350D01*
X430430Y458308D01*
X430805Y458392D01*
X431055Y458517D01*
X431305Y458767D01*
X431472Y459058D01*
X431555Y459350D01*
Y459642D01*
X431472Y459933D01*
X431347Y460183D01*
X431180Y460392D01*
G01X431555Y462450D02*
X429055D01*
X429555Y461950D01*
G01X431555D02*
Y462950D01*
G01X429055Y465550D02*
X429138Y465217D01*
X429347Y464967D01*
X429597Y464800D01*
X429930Y464675D01*
X430305Y464633D01*
X430680Y464675D01*
X431013Y464800D01*
X431263Y464967D01*
X431472Y465217D01*
X431555Y465550D01*
X431472Y465883D01*
X431263Y466133D01*
X431013Y466300D01*
X430680Y466425D01*
X430305Y466467D01*
X429930Y466425D01*
X429597Y466300D01*
X429347Y466133D01*
X429138Y465883D01*
X429055Y465550D01*
G01X431555Y468650D02*
X431513Y468942D01*
X431388Y469275D01*
X431180Y469483D01*
X430888Y469567D01*
X430597Y469483D01*
X430347Y469233D01*
X430222Y468858D01*
Y468442D01*
X430138Y468192D01*
X429930Y467983D01*
X429638Y467900D01*
X429347Y468025D01*
X429138Y468317D01*
X429055Y468650D01*
X429138Y468983D01*
X429347Y469275D01*
X429638Y469400D01*
X429930Y469317D01*
X430138Y469108D01*
X430222Y468858D01*
Y468442D01*
X430347Y468067D01*
X430597Y467817D01*
X430888Y467733D01*
X431180Y467817D01*
X431388Y468025D01*
X431513Y468358D01*
X431555Y468650D01*
G01X429472Y470958D02*
X429222Y471208D01*
X429097Y471500D01*
X429055Y471833D01*
X429138Y472250D01*
X429347Y472542D01*
X429597Y472625D01*
X429847Y472583D01*
X430055Y472417D01*
X430472Y471583D01*
X430763Y471208D01*
X431180Y470958D01*
X431555Y470875D01*
Y472625D01*
G01X445445Y787425D02*
X445653Y787758D01*
X445778Y788133D01*
Y788467D01*
X445653Y788800D01*
X445445Y789050D01*
X445153Y789175D01*
X444861Y789092D01*
X444611Y788883D01*
X444445Y788508D01*
X444361Y788008D01*
X444195Y787717D01*
X443903Y787592D01*
X443611Y787675D01*
X443403Y787883D01*
X443278Y788175D01*
Y788467D01*
X443361Y788758D01*
X443570Y789008D01*
G01X445778Y790567D02*
X443278D01*
Y791608D01*
X443403Y791942D01*
X443570Y792150D01*
X443903Y792233D01*
X444236Y792150D01*
X444445Y791900D01*
X444570Y791608D01*
Y790567D01*
G01Y791608D02*
X445778Y792233D01*
G01Y794500D02*
X445736Y794792D01*
X445611Y795125D01*
X445403Y795333D01*
X445111Y795417D01*
X444820Y795333D01*
X444570Y795083D01*
X444445Y794708D01*
Y794292D01*
X444361Y794042D01*
X444153Y793833D01*
X443861Y793750D01*
X443570Y793875D01*
X443361Y794167D01*
X443278Y794500D01*
X443361Y794833D01*
X443570Y795125D01*
X443861Y795250D01*
X444153Y795167D01*
X444361Y794958D01*
X444445Y794708D01*
Y794292D01*
X444570Y793917D01*
X444820Y793667D01*
X445111Y793583D01*
X445403Y793667D01*
X445611Y793875D01*
X445736Y794208D01*
X445778Y794500D01*
G01Y797517D02*
X445236Y797600D01*
X444778Y797725D01*
X444361Y797892D01*
X443903Y798100D01*
X443278Y798433D01*
Y796767D01*
G01X445778Y800617D02*
X445236Y800700D01*
X444778Y800825D01*
X444361Y800992D01*
X443903Y801200D01*
X443278Y801533D01*
Y799867D01*
G01X438945Y787425D02*
X439153Y787758D01*
X439278Y788133D01*
Y788467D01*
X439153Y788800D01*
X438945Y789050D01*
X438653Y789175D01*
X438361Y789092D01*
X438111Y788883D01*
X437945Y788508D01*
X437861Y788008D01*
X437695Y787717D01*
X437403Y787592D01*
X437111Y787675D01*
X436903Y787883D01*
X436778Y788175D01*
Y788467D01*
X436861Y788758D01*
X437070Y789008D01*
G01X439278Y790567D02*
X436778D01*
Y791608D01*
X436903Y791942D01*
X437070Y792150D01*
X437403Y792233D01*
X437736Y792150D01*
X437945Y791900D01*
X438070Y791608D01*
Y790567D01*
G01Y791608D02*
X439278Y792233D01*
G01Y794500D02*
X439236Y794792D01*
X439111Y795125D01*
X438903Y795333D01*
X438611Y795417D01*
X438320Y795333D01*
X438070Y795083D01*
X437945Y794708D01*
Y794292D01*
X437861Y794042D01*
X437653Y793833D01*
X437361Y793750D01*
X437070Y793875D01*
X436861Y794167D01*
X436778Y794500D01*
X436861Y794833D01*
X437070Y795125D01*
X437361Y795250D01*
X437653Y795167D01*
X437861Y794958D01*
X437945Y794708D01*
Y794292D01*
X438070Y793917D01*
X438320Y793667D01*
X438611Y793583D01*
X438903Y793667D01*
X439111Y793875D01*
X439236Y794208D01*
X439278Y794500D01*
G01Y797600D02*
X439236Y797892D01*
X439111Y798225D01*
X438903Y798433D01*
X438611Y798517D01*
X438320Y798433D01*
X438070Y798183D01*
X437945Y797808D01*
Y797392D01*
X437861Y797142D01*
X437653Y796933D01*
X437361Y796850D01*
X437070Y796975D01*
X436861Y797267D01*
X436778Y797600D01*
X436861Y797933D01*
X437070Y798225D01*
X437361Y798350D01*
X437653Y798267D01*
X437861Y798058D01*
X437945Y797808D01*
Y797392D01*
X438070Y797017D01*
X438320Y796767D01*
X438611Y796683D01*
X438903Y796767D01*
X439111Y796975D01*
X439236Y797308D01*
X439278Y797600D01*
G01Y800700D02*
X436778D01*
X437278Y800200D01*
G01X439278D02*
Y801200D01*
G01X446778Y810700D02*
X442778D01*
Y803300D01*
G01Y806800D02*
X446778D01*
Y814200D01*
G01X440278Y810700D02*
X436278D01*
Y803300D01*
G01Y806800D02*
X440278D01*
Y814200D01*
G01X444945Y815925D02*
X445153Y816258D01*
X445278Y816633D01*
Y816967D01*
X445153Y817300D01*
X444945Y817550D01*
X444653Y817675D01*
X444361Y817592D01*
X444111Y817383D01*
X443945Y817008D01*
X443861Y816508D01*
X443695Y816217D01*
X443403Y816092D01*
X443111Y816175D01*
X442903Y816383D01*
X442778Y816675D01*
Y816967D01*
X442861Y817258D01*
X443070Y817508D01*
G01X445278Y819067D02*
X442778D01*
Y820108D01*
X442903Y820442D01*
X443070Y820650D01*
X443403Y820733D01*
X443736Y820650D01*
X443945Y820400D01*
X444070Y820108D01*
Y819067D01*
G01Y820108D02*
X445278Y820733D01*
G01Y823000D02*
X445236Y823292D01*
X445111Y823625D01*
X444903Y823833D01*
X444611Y823917D01*
X444320Y823833D01*
X444070Y823583D01*
X443945Y823208D01*
Y822792D01*
X443861Y822542D01*
X443653Y822333D01*
X443361Y822250D01*
X443070Y822375D01*
X442861Y822667D01*
X442778Y823000D01*
X442861Y823333D01*
X443070Y823625D01*
X443361Y823750D01*
X443653Y823667D01*
X443861Y823458D01*
X443945Y823208D01*
Y822792D01*
X444070Y822417D01*
X444320Y822167D01*
X444611Y822083D01*
X444903Y822167D01*
X445111Y822375D01*
X445236Y822708D01*
X445278Y823000D01*
G01Y826017D02*
X444736Y826100D01*
X444278Y826225D01*
X443861Y826392D01*
X443403Y826600D01*
X442778Y826933D01*
Y825267D01*
G01X444986Y828492D02*
X445195Y828783D01*
X445278Y829117D01*
X445195Y829450D01*
X444945Y829742D01*
X444570Y829950D01*
X444195Y830033D01*
X443736D01*
X443361Y829950D01*
X443028Y829742D01*
X442861Y829492D01*
X442778Y829200D01*
X442861Y828867D01*
X443028Y828617D01*
X443278Y828450D01*
X443611Y828367D01*
X443903Y828450D01*
X444195Y828658D01*
X444361Y828908D01*
X444403Y829200D01*
X444320Y829533D01*
X444111Y829783D01*
X443736Y830033D01*
G01X438445Y815925D02*
X438653Y816258D01*
X438778Y816633D01*
Y816967D01*
X438653Y817300D01*
X438445Y817550D01*
X438153Y817675D01*
X437861Y817592D01*
X437611Y817383D01*
X437445Y817008D01*
X437361Y816508D01*
X437195Y816217D01*
X436903Y816092D01*
X436611Y816175D01*
X436403Y816383D01*
X436278Y816675D01*
Y816967D01*
X436361Y817258D01*
X436570Y817508D01*
G01X438778Y819067D02*
X436278D01*
Y820108D01*
X436403Y820442D01*
X436570Y820650D01*
X436903Y820733D01*
X437236Y820650D01*
X437445Y820400D01*
X437570Y820108D01*
Y819067D01*
G01Y820108D02*
X438778Y820733D01*
G01Y823000D02*
X438736Y823292D01*
X438611Y823625D01*
X438403Y823833D01*
X438111Y823917D01*
X437820Y823833D01*
X437570Y823583D01*
X437445Y823208D01*
Y822792D01*
X437361Y822542D01*
X437153Y822333D01*
X436861Y822250D01*
X436570Y822375D01*
X436361Y822667D01*
X436278Y823000D01*
X436361Y823333D01*
X436570Y823625D01*
X436861Y823750D01*
X437153Y823667D01*
X437361Y823458D01*
X437445Y823208D01*
Y822792D01*
X437570Y822417D01*
X437820Y822167D01*
X438111Y822083D01*
X438403Y822167D01*
X438611Y822375D01*
X438736Y822708D01*
X438778Y823000D01*
G01Y826100D02*
X438736Y826392D01*
X438611Y826725D01*
X438403Y826933D01*
X438111Y827017D01*
X437820Y826933D01*
X437570Y826683D01*
X437445Y826308D01*
Y825892D01*
X437361Y825642D01*
X437153Y825433D01*
X436861Y825350D01*
X436570Y825475D01*
X436361Y825767D01*
X436278Y826100D01*
X436361Y826433D01*
X436570Y826725D01*
X436861Y826850D01*
X437153Y826767D01*
X437361Y826558D01*
X437445Y826308D01*
Y825892D01*
X437570Y825517D01*
X437820Y825267D01*
X438111Y825183D01*
X438403Y825267D01*
X438611Y825475D01*
X438736Y825808D01*
X438778Y826100D01*
G01X438278Y828283D02*
X438570Y828533D01*
X438736Y828867D01*
X438778Y829242D01*
X438736Y829575D01*
X438528Y829908D01*
X438278Y830117D01*
X438028Y830158D01*
X437736Y830075D01*
X437528Y829783D01*
X437445Y829492D01*
Y829117D01*
G01Y829492D02*
X437320Y829742D01*
X437111Y829950D01*
X436861Y830033D01*
X436611Y829950D01*
X436403Y829742D01*
X436278Y829367D01*
X436320Y828992D01*
X436486Y828617D01*
G01X444945Y853925D02*
X445153Y854258D01*
X445278Y854633D01*
Y854967D01*
X445153Y855300D01*
X444945Y855550D01*
X444653Y855675D01*
X444361Y855592D01*
X444111Y855383D01*
X443945Y855008D01*
X443861Y854508D01*
X443695Y854217D01*
X443403Y854092D01*
X443111Y854175D01*
X442903Y854383D01*
X442778Y854675D01*
Y854967D01*
X442861Y855258D01*
X443070Y855508D01*
G01X445278Y857067D02*
X442778D01*
Y858108D01*
X442903Y858442D01*
X443070Y858650D01*
X443403Y858733D01*
X443736Y858650D01*
X443945Y858400D01*
X444070Y858108D01*
Y857067D01*
G01Y858108D02*
X445278Y858733D01*
G01Y861000D02*
X445236Y861292D01*
X445111Y861625D01*
X444903Y861833D01*
X444611Y861917D01*
X444320Y861833D01*
X444070Y861583D01*
X443945Y861208D01*
Y860792D01*
X443861Y860542D01*
X443653Y860333D01*
X443361Y860250D01*
X443070Y860375D01*
X442861Y860667D01*
X442778Y861000D01*
X442861Y861333D01*
X443070Y861625D01*
X443361Y861750D01*
X443653Y861667D01*
X443861Y861458D01*
X443945Y861208D01*
Y860792D01*
X444070Y860417D01*
X444320Y860167D01*
X444611Y860083D01*
X444903Y860167D01*
X445111Y860375D01*
X445236Y860708D01*
X445278Y861000D01*
G01Y864100D02*
X445236Y864392D01*
X445111Y864725D01*
X444903Y864933D01*
X444611Y865017D01*
X444320Y864933D01*
X444070Y864683D01*
X443945Y864308D01*
Y863892D01*
X443861Y863642D01*
X443653Y863433D01*
X443361Y863350D01*
X443070Y863475D01*
X442861Y863767D01*
X442778Y864100D01*
X442861Y864433D01*
X443070Y864725D01*
X443361Y864850D01*
X443653Y864767D01*
X443861Y864558D01*
X443945Y864308D01*
Y863892D01*
X444070Y863517D01*
X444320Y863267D01*
X444611Y863183D01*
X444903Y863267D01*
X445111Y863475D01*
X445236Y863808D01*
X445278Y864100D01*
G01Y867700D02*
X442778D01*
X444570Y866158D01*
Y868242D01*
G01X446278Y881200D02*
X442278D01*
Y873800D01*
G01Y870300D02*
X446278D01*
Y877700D01*
G01X444945Y883425D02*
X445153Y883758D01*
X445278Y884133D01*
Y884467D01*
X445153Y884800D01*
X444945Y885050D01*
X444653Y885175D01*
X444361Y885092D01*
X444111Y884883D01*
X443945Y884508D01*
X443861Y884008D01*
X443695Y883717D01*
X443403Y883592D01*
X443111Y883675D01*
X442903Y883883D01*
X442778Y884175D01*
Y884467D01*
X442861Y884758D01*
X443070Y885008D01*
G01X445278Y886567D02*
X442778D01*
Y887608D01*
X442903Y887942D01*
X443070Y888150D01*
X443403Y888233D01*
X443736Y888150D01*
X443945Y887900D01*
X444070Y887608D01*
Y886567D01*
G01Y887608D02*
X445278Y888233D01*
G01Y890500D02*
X445236Y890792D01*
X445111Y891125D01*
X444903Y891333D01*
X444611Y891417D01*
X444320Y891333D01*
X444070Y891083D01*
X443945Y890708D01*
Y890292D01*
X443861Y890042D01*
X443653Y889833D01*
X443361Y889750D01*
X443070Y889875D01*
X442861Y890167D01*
X442778Y890500D01*
X442861Y890833D01*
X443070Y891125D01*
X443361Y891250D01*
X443653Y891167D01*
X443861Y890958D01*
X443945Y890708D01*
Y890292D01*
X444070Y889917D01*
X444320Y889667D01*
X444611Y889583D01*
X444903Y889667D01*
X445111Y889875D01*
X445236Y890208D01*
X445278Y890500D01*
G01Y893600D02*
X445236Y893892D01*
X445111Y894225D01*
X444903Y894433D01*
X444611Y894517D01*
X444320Y894433D01*
X444070Y894183D01*
X443945Y893808D01*
Y893392D01*
X443861Y893142D01*
X443653Y892933D01*
X443361Y892850D01*
X443070Y892975D01*
X442861Y893267D01*
X442778Y893600D01*
X442861Y893933D01*
X443070Y894225D01*
X443361Y894350D01*
X443653Y894267D01*
X443861Y894058D01*
X443945Y893808D01*
Y893392D01*
X444070Y893017D01*
X444320Y892767D01*
X444611Y892683D01*
X444903Y892767D01*
X445111Y892975D01*
X445236Y893308D01*
X445278Y893600D01*
G01X443195Y895908D02*
X442945Y896158D01*
X442820Y896450D01*
X442778Y896783D01*
X442861Y897200D01*
X443070Y897492D01*
X443320Y897575D01*
X443570Y897533D01*
X443778Y897367D01*
X444195Y896533D01*
X444486Y896158D01*
X444903Y895908D01*
X445278Y895825D01*
Y897575D01*
G01X454596Y79875D02*
X454804Y80208D01*
X454929Y80583D01*
Y80917D01*
X454804Y81250D01*
X454596Y81500D01*
X454304Y81625D01*
X454012Y81542D01*
X453762Y81333D01*
X453596Y80958D01*
X453512Y80458D01*
X453346Y80167D01*
X453054Y80042D01*
X452762Y80125D01*
X452554Y80333D01*
X452429Y80625D01*
Y80917D01*
X452512Y81208D01*
X452721Y81458D01*
G01X452429Y83017D02*
X454929D01*
Y84683D01*
G01Y87783D02*
Y86117D01*
X452429D01*
Y87783D01*
G01X453637Y87117D02*
Y86117D01*
G01X454929Y89133D02*
X452429D01*
Y89967D01*
X452554Y90300D01*
X452721Y90550D01*
X452971Y90758D01*
X453262Y90925D01*
X453679Y90967D01*
X454096Y90925D01*
X454387Y90758D01*
X454637Y90550D01*
X454804Y90300D01*
X454929Y89967D01*
Y89133D01*
G01X452846Y92358D02*
X452596Y92608D01*
X452471Y92900D01*
X452429Y93233D01*
X452512Y93650D01*
X452721Y93942D01*
X452971Y94025D01*
X453221Y93983D01*
X453429Y93817D01*
X453846Y92983D01*
X454137Y92608D01*
X454554Y92358D01*
X454929Y92275D01*
Y94025D01*
G01X453887Y95458D02*
X453596Y95750D01*
X453429Y96000D01*
X453346Y96333D01*
X453429Y96625D01*
X453596Y96833D01*
X453846Y97000D01*
X454137Y97042D01*
X454387Y97000D01*
X454637Y96833D01*
X454846Y96583D01*
X454929Y96292D01*
X454846Y95958D01*
X454596Y95667D01*
X454221Y95500D01*
X453804Y95458D01*
X453262Y95542D01*
X452971Y95667D01*
X452679Y95875D01*
X452471Y96167D01*
X452429Y96458D01*
X452512Y96750D01*
X452721Y96958D01*
G01X450029Y104100D02*
X460829D01*
Y98900D01*
X450029D01*
Y104100D01*
G01X453000Y107800D02*
X457000D01*
Y115200D01*
G01X452800Y119500D02*
Y115500D01*
X460200D01*
G01X457500Y107800D02*
X461500D01*
Y115200D01*
G01X452166Y129802D02*
Y134370D01*
G01Y216260D02*
Y138070D01*
G01X450316Y127952D02*
X445748D01*
G01X454016D02*
G02I-1850J0D01*
G01Y136220D02*
G02I-1850J0D01*
G01X468129Y163500D02*
Y167500D01*
X460729D01*
G01X468129Y170500D02*
Y174500D01*
X460729D01*
G01X460300Y187000D02*
Y183000D01*
X467700D01*
G01X468129Y178500D02*
Y182500D01*
X460729D01*
G01X467700Y195000D02*
Y199000D01*
X460300D01*
G01X467629Y187500D02*
Y191500D01*
X460229D01*
G01X452166Y224528D02*
Y219960D01*
G01X454016Y218110D02*
G02I-1850J0D01*
G01X450316Y226378D02*
X445748D01*
G01X454016D02*
G02I-1850J0D01*
G01X445425Y237833D02*
X445758Y237625D01*
X446133Y237500D01*
X446467D01*
X446800Y237625D01*
X447050Y237833D01*
X447175Y238125D01*
X447092Y238417D01*
X446883Y238667D01*
X446508Y238833D01*
X446008Y238917D01*
X445717Y239083D01*
X445592Y239375D01*
X445675Y239667D01*
X445883Y239875D01*
X446175Y240000D01*
X446467D01*
X446758Y239917D01*
X447008Y239708D01*
G01X448567Y237500D02*
Y240000D01*
X449608D01*
X449942Y239875D01*
X450150Y239708D01*
X450233Y239375D01*
X450150Y239042D01*
X449900Y238833D01*
X449608Y238708D01*
X448567D01*
G01X449608D02*
X450233Y237500D01*
G01X452417D02*
X452500Y238042D01*
X452625Y238500D01*
X452792Y238917D01*
X453000Y239375D01*
X453333Y240000D01*
X451667D01*
G01X455600D02*
X455267Y239917D01*
X455017Y239708D01*
X454850Y239458D01*
X454725Y239125D01*
X454683Y238750D01*
X454725Y238375D01*
X454850Y238042D01*
X455017Y237792D01*
X455267Y237583D01*
X455600Y237500D01*
X455933Y237583D01*
X456183Y237792D01*
X456350Y238042D01*
X456475Y238375D01*
X456517Y238750D01*
X456475Y239125D01*
X456350Y239458D01*
X456183Y239708D01*
X455933Y239917D01*
X455600Y240000D01*
G01X457908Y238542D02*
X458200Y238833D01*
X458450Y239000D01*
X458783Y239083D01*
X459075Y239000D01*
X459283Y238833D01*
X459450Y238583D01*
X459492Y238292D01*
X459450Y238042D01*
X459283Y237792D01*
X459033Y237583D01*
X458742Y237500D01*
X458408Y237583D01*
X458117Y237833D01*
X457950Y238208D01*
X457908Y238625D01*
X457992Y239167D01*
X458117Y239458D01*
X458325Y239750D01*
X458617Y239958D01*
X458908Y240000D01*
X459200Y239917D01*
X459408Y239708D01*
G01X455500Y287500D02*
Y284500D01*
G01X463200Y275500D02*
Y279500D01*
X455800D01*
G01X463200Y271000D02*
Y275000D01*
X455800D01*
G01X465200Y280000D02*
Y284000D01*
X457800D01*
G01X447577Y301700D02*
X449577D01*
G01X447577Y288300D02*
Y301700D01*
G01X449577Y288300D02*
X447577D01*
G01X449577Y301700D02*
Y288300D01*
G01X467700Y284500D02*
Y288500D01*
X460300D01*
G01X460555Y298700D02*
X456555D01*
Y291300D01*
G01X460500Y304500D02*
Y309000D01*
X468500D01*
Y315500D01*
X467000D01*
G01X446980Y438733D02*
X447313Y438525D01*
X447688Y438400D01*
X448022D01*
X448355Y438525D01*
X448605Y438733D01*
X448730Y439025D01*
X448647Y439317D01*
X448438Y439567D01*
X448063Y439733D01*
X447563Y439817D01*
X447272Y439983D01*
X447147Y440275D01*
X447230Y440567D01*
X447438Y440775D01*
X447730Y440900D01*
X448022D01*
X448313Y440817D01*
X448563Y440608D01*
G01X450038Y440900D02*
Y439108D01*
X450205Y438733D01*
X450538Y438483D01*
X450955Y438400D01*
X451372Y438483D01*
X451705Y438733D01*
X451872Y439108D01*
Y440900D01*
G01X454055Y438400D02*
Y440900D01*
X453555Y440400D01*
G01Y438400D02*
X454555D01*
G01X463222Y455375D02*
X463430Y455708D01*
X463555Y456083D01*
Y456417D01*
X463430Y456750D01*
X463222Y457000D01*
X462930Y457125D01*
X462638Y457042D01*
X462388Y456833D01*
X462222Y456458D01*
X462138Y455958D01*
X461972Y455667D01*
X461680Y455542D01*
X461388Y455625D01*
X461180Y455833D01*
X461055Y456125D01*
Y456417D01*
X461138Y456708D01*
X461347Y456958D01*
G01X461263Y460267D02*
X461138Y460017D01*
X461055Y459725D01*
Y459392D01*
X461180Y459017D01*
X461388Y458725D01*
X461638Y458517D01*
X462055Y458350D01*
X462430Y458308D01*
X462805Y458392D01*
X463055Y458517D01*
X463305Y458767D01*
X463472Y459058D01*
X463555Y459350D01*
Y459642D01*
X463472Y459933D01*
X463347Y460183D01*
X463180Y460392D01*
G01X463555Y462450D02*
X461055D01*
X461555Y461950D01*
G01X463555D02*
Y462950D01*
G01X461055Y465550D02*
X461138Y465217D01*
X461347Y464967D01*
X461597Y464800D01*
X461930Y464675D01*
X462305Y464633D01*
X462680Y464675D01*
X463013Y464800D01*
X463263Y464967D01*
X463472Y465217D01*
X463555Y465550D01*
X463472Y465883D01*
X463263Y466133D01*
X463013Y466300D01*
X462680Y466425D01*
X462305Y466467D01*
X461930Y466425D01*
X461597Y466300D01*
X461347Y466133D01*
X461138Y465883D01*
X461055Y465550D01*
G01X463555Y468567D02*
X463013Y468650D01*
X462555Y468775D01*
X462138Y468942D01*
X461680Y469150D01*
X461055Y469483D01*
Y467817D01*
G01X463555Y472250D02*
X461055D01*
X462847Y470708D01*
Y472792D01*
G01X459222Y455375D02*
X459430Y455708D01*
X459555Y456083D01*
Y456417D01*
X459430Y456750D01*
X459222Y457000D01*
X458930Y457125D01*
X458638Y457042D01*
X458388Y456833D01*
X458222Y456458D01*
X458138Y455958D01*
X457972Y455667D01*
X457680Y455542D01*
X457388Y455625D01*
X457180Y455833D01*
X457055Y456125D01*
Y456417D01*
X457138Y456708D01*
X457347Y456958D01*
G01X457263Y460267D02*
X457138Y460017D01*
X457055Y459725D01*
Y459392D01*
X457180Y459017D01*
X457388Y458725D01*
X457638Y458517D01*
X458055Y458350D01*
X458430Y458308D01*
X458805Y458392D01*
X459055Y458517D01*
X459305Y458767D01*
X459472Y459058D01*
X459555Y459350D01*
Y459642D01*
X459472Y459933D01*
X459347Y460183D01*
X459180Y460392D01*
G01X459555Y462450D02*
X457055D01*
X457555Y461950D01*
G01X459555D02*
Y462950D01*
G01X457055Y465550D02*
X457138Y465217D01*
X457347Y464967D01*
X457597Y464800D01*
X457930Y464675D01*
X458305Y464633D01*
X458680Y464675D01*
X459013Y464800D01*
X459263Y464967D01*
X459472Y465217D01*
X459555Y465550D01*
X459472Y465883D01*
X459263Y466133D01*
X459013Y466300D01*
X458680Y466425D01*
X458305Y466467D01*
X457930Y466425D01*
X457597Y466300D01*
X457347Y466133D01*
X457138Y465883D01*
X457055Y465550D01*
G01X459555Y468567D02*
X459013Y468650D01*
X458555Y468775D01*
X458138Y468942D01*
X457680Y469150D01*
X457055Y469483D01*
Y467817D01*
G01X459180Y470833D02*
X459388Y471083D01*
X459513Y471375D01*
X459555Y471750D01*
X459472Y472125D01*
X459305Y472417D01*
X459013Y472625D01*
X458680Y472667D01*
X458347Y472583D01*
X458138Y472375D01*
X457972Y472083D01*
X457930Y471792D01*
X457972Y471500D01*
X458138Y471125D01*
X457055Y471250D01*
Y472375D01*
G01X455222Y455375D02*
X455430Y455708D01*
X455555Y456083D01*
Y456417D01*
X455430Y456750D01*
X455222Y457000D01*
X454930Y457125D01*
X454638Y457042D01*
X454388Y456833D01*
X454222Y456458D01*
X454138Y455958D01*
X453972Y455667D01*
X453680Y455542D01*
X453388Y455625D01*
X453180Y455833D01*
X453055Y456125D01*
Y456417D01*
X453138Y456708D01*
X453347Y456958D01*
G01X453263Y460267D02*
X453138Y460017D01*
X453055Y459725D01*
Y459392D01*
X453180Y459017D01*
X453388Y458725D01*
X453638Y458517D01*
X454055Y458350D01*
X454430Y458308D01*
X454805Y458392D01*
X455055Y458517D01*
X455305Y458767D01*
X455472Y459058D01*
X455555Y459350D01*
Y459642D01*
X455472Y459933D01*
X455347Y460183D01*
X455180Y460392D01*
G01X455555Y462450D02*
X453055D01*
X453555Y461950D01*
G01X455555D02*
Y462950D01*
G01X453055Y465550D02*
X453138Y465217D01*
X453347Y464967D01*
X453597Y464800D01*
X453930Y464675D01*
X454305Y464633D01*
X454680Y464675D01*
X455013Y464800D01*
X455263Y464967D01*
X455472Y465217D01*
X455555Y465550D01*
X455472Y465883D01*
X455263Y466133D01*
X455013Y466300D01*
X454680Y466425D01*
X454305Y466467D01*
X453930Y466425D01*
X453597Y466300D01*
X453347Y466133D01*
X453138Y465883D01*
X453055Y465550D01*
G01X455555Y468567D02*
X455013Y468650D01*
X454555Y468775D01*
X454138Y468942D01*
X453680Y469150D01*
X453055Y469483D01*
Y467817D01*
G01X454513Y470958D02*
X454222Y471250D01*
X454055Y471500D01*
X453972Y471833D01*
X454055Y472125D01*
X454222Y472333D01*
X454472Y472500D01*
X454763Y472542D01*
X455013Y472500D01*
X455263Y472333D01*
X455472Y472083D01*
X455555Y471792D01*
X455472Y471458D01*
X455222Y471167D01*
X454847Y471000D01*
X454430Y470958D01*
X453888Y471042D01*
X453597Y471167D01*
X453305Y471375D01*
X453097Y471667D01*
X453055Y471958D01*
X453138Y472250D01*
X453347Y472458D01*
G01X451222Y455375D02*
X451430Y455708D01*
X451555Y456083D01*
Y456417D01*
X451430Y456750D01*
X451222Y457000D01*
X450930Y457125D01*
X450638Y457042D01*
X450388Y456833D01*
X450222Y456458D01*
X450138Y455958D01*
X449972Y455667D01*
X449680Y455542D01*
X449388Y455625D01*
X449180Y455833D01*
X449055Y456125D01*
Y456417D01*
X449138Y456708D01*
X449347Y456958D01*
G01X449263Y460267D02*
X449138Y460017D01*
X449055Y459725D01*
Y459392D01*
X449180Y459017D01*
X449388Y458725D01*
X449638Y458517D01*
X450055Y458350D01*
X450430Y458308D01*
X450805Y458392D01*
X451055Y458517D01*
X451305Y458767D01*
X451472Y459058D01*
X451555Y459350D01*
Y459642D01*
X451472Y459933D01*
X451347Y460183D01*
X451180Y460392D01*
G01X451555Y462450D02*
X449055D01*
X449555Y461950D01*
G01X451555D02*
Y462950D01*
G01X449055Y465550D02*
X449138Y465217D01*
X449347Y464967D01*
X449597Y464800D01*
X449930Y464675D01*
X450305Y464633D01*
X450680Y464675D01*
X451013Y464800D01*
X451263Y464967D01*
X451472Y465217D01*
X451555Y465550D01*
X451472Y465883D01*
X451263Y466133D01*
X451013Y466300D01*
X450680Y466425D01*
X450305Y466467D01*
X449930Y466425D01*
X449597Y466300D01*
X449347Y466133D01*
X449138Y465883D01*
X449055Y465550D01*
G01X451555Y468567D02*
X451013Y468650D01*
X450555Y468775D01*
X450138Y468942D01*
X449680Y469150D01*
X449055Y469483D01*
Y467817D01*
G01X451555Y471667D02*
X451013Y471750D01*
X450555Y471875D01*
X450138Y472042D01*
X449680Y472250D01*
X449055Y472583D01*
Y470917D01*
G01X447222Y455375D02*
X447430Y455708D01*
X447555Y456083D01*
Y456417D01*
X447430Y456750D01*
X447222Y457000D01*
X446930Y457125D01*
X446638Y457042D01*
X446388Y456833D01*
X446222Y456458D01*
X446138Y455958D01*
X445972Y455667D01*
X445680Y455542D01*
X445388Y455625D01*
X445180Y455833D01*
X445055Y456125D01*
Y456417D01*
X445138Y456708D01*
X445347Y456958D01*
G01X445263Y460267D02*
X445138Y460017D01*
X445055Y459725D01*
Y459392D01*
X445180Y459017D01*
X445388Y458725D01*
X445638Y458517D01*
X446055Y458350D01*
X446430Y458308D01*
X446805Y458392D01*
X447055Y458517D01*
X447305Y458767D01*
X447472Y459058D01*
X447555Y459350D01*
Y459642D01*
X447472Y459933D01*
X447347Y460183D01*
X447180Y460392D01*
G01X447555Y462450D02*
X445055D01*
X445555Y461950D01*
G01X447555D02*
Y462950D01*
G01X445055Y465550D02*
X445138Y465217D01*
X445347Y464967D01*
X445597Y464800D01*
X445930Y464675D01*
X446305Y464633D01*
X446680Y464675D01*
X447013Y464800D01*
X447263Y464967D01*
X447472Y465217D01*
X447555Y465550D01*
X447472Y465883D01*
X447263Y466133D01*
X447013Y466300D01*
X446680Y466425D01*
X446305Y466467D01*
X445930Y466425D01*
X445597Y466300D01*
X445347Y466133D01*
X445138Y465883D01*
X445055Y465550D01*
G01X447555Y468567D02*
X447013Y468650D01*
X446555Y468775D01*
X446138Y468942D01*
X445680Y469150D01*
X445055Y469483D01*
Y467817D01*
G01X447555Y471750D02*
X447513Y472042D01*
X447388Y472375D01*
X447180Y472583D01*
X446888Y472667D01*
X446597Y472583D01*
X446347Y472333D01*
X446222Y471958D01*
Y471542D01*
X446138Y471292D01*
X445930Y471083D01*
X445638Y471000D01*
X445347Y471125D01*
X445138Y471417D01*
X445055Y471750D01*
X445138Y472083D01*
X445347Y472375D01*
X445638Y472500D01*
X445930Y472417D01*
X446138Y472208D01*
X446222Y471958D01*
Y471542D01*
X446347Y471167D01*
X446597Y470917D01*
X446888Y470833D01*
X447180Y470917D01*
X447388Y471125D01*
X447513Y471458D01*
X447555Y471750D01*
G01X451445Y853925D02*
X451653Y854258D01*
X451778Y854633D01*
Y854967D01*
X451653Y855300D01*
X451445Y855550D01*
X451153Y855675D01*
X450861Y855592D01*
X450611Y855383D01*
X450445Y855008D01*
X450361Y854508D01*
X450195Y854217D01*
X449903Y854092D01*
X449611Y854175D01*
X449403Y854383D01*
X449278Y854675D01*
Y854967D01*
X449361Y855258D01*
X449570Y855508D01*
G01X451778Y857067D02*
X449278D01*
Y858108D01*
X449403Y858442D01*
X449570Y858650D01*
X449903Y858733D01*
X450236Y858650D01*
X450445Y858400D01*
X450570Y858108D01*
Y857067D01*
G01Y858108D02*
X451778Y858733D01*
G01Y861000D02*
X451736Y861292D01*
X451611Y861625D01*
X451403Y861833D01*
X451111Y861917D01*
X450820Y861833D01*
X450570Y861583D01*
X450445Y861208D01*
Y860792D01*
X450361Y860542D01*
X450153Y860333D01*
X449861Y860250D01*
X449570Y860375D01*
X449361Y860667D01*
X449278Y861000D01*
X449361Y861333D01*
X449570Y861625D01*
X449861Y861750D01*
X450153Y861667D01*
X450361Y861458D01*
X450445Y861208D01*
Y860792D01*
X450570Y860417D01*
X450820Y860167D01*
X451111Y860083D01*
X451403Y860167D01*
X451611Y860375D01*
X451736Y860708D01*
X451778Y861000D01*
G01Y864100D02*
X451736Y864392D01*
X451611Y864725D01*
X451403Y864933D01*
X451111Y865017D01*
X450820Y864933D01*
X450570Y864683D01*
X450445Y864308D01*
Y863892D01*
X450361Y863642D01*
X450153Y863433D01*
X449861Y863350D01*
X449570Y863475D01*
X449361Y863767D01*
X449278Y864100D01*
X449361Y864433D01*
X449570Y864725D01*
X449861Y864850D01*
X450153Y864767D01*
X450361Y864558D01*
X450445Y864308D01*
Y863892D01*
X450570Y863517D01*
X450820Y863267D01*
X451111Y863183D01*
X451403Y863267D01*
X451611Y863475D01*
X451736Y863808D01*
X451778Y864100D01*
G01X449278Y867200D02*
X449361Y866867D01*
X449570Y866617D01*
X449820Y866450D01*
X450153Y866325D01*
X450528Y866283D01*
X450903Y866325D01*
X451236Y866450D01*
X451486Y866617D01*
X451695Y866867D01*
X451778Y867200D01*
X451695Y867533D01*
X451486Y867783D01*
X451236Y867950D01*
X450903Y868075D01*
X450528Y868117D01*
X450153Y868075D01*
X449820Y867950D01*
X449570Y867783D01*
X449361Y867533D01*
X449278Y867200D01*
G01X452778Y881200D02*
X448778D01*
Y873800D01*
G01Y870300D02*
X452778D01*
Y877700D01*
G01X451445Y883425D02*
X451653Y883758D01*
X451778Y884133D01*
Y884467D01*
X451653Y884800D01*
X451445Y885050D01*
X451153Y885175D01*
X450861Y885092D01*
X450611Y884883D01*
X450445Y884508D01*
X450361Y884008D01*
X450195Y883717D01*
X449903Y883592D01*
X449611Y883675D01*
X449403Y883883D01*
X449278Y884175D01*
Y884467D01*
X449361Y884758D01*
X449570Y885008D01*
G01X451778Y886567D02*
X449278D01*
Y887608D01*
X449403Y887942D01*
X449570Y888150D01*
X449903Y888233D01*
X450236Y888150D01*
X450445Y887900D01*
X450570Y887608D01*
Y886567D01*
G01Y887608D02*
X451778Y888233D01*
G01Y890500D02*
X451736Y890792D01*
X451611Y891125D01*
X451403Y891333D01*
X451111Y891417D01*
X450820Y891333D01*
X450570Y891083D01*
X450445Y890708D01*
Y890292D01*
X450361Y890042D01*
X450153Y889833D01*
X449861Y889750D01*
X449570Y889875D01*
X449361Y890167D01*
X449278Y890500D01*
X449361Y890833D01*
X449570Y891125D01*
X449861Y891250D01*
X450153Y891167D01*
X450361Y890958D01*
X450445Y890708D01*
Y890292D01*
X450570Y889917D01*
X450820Y889667D01*
X451111Y889583D01*
X451403Y889667D01*
X451611Y889875D01*
X451736Y890208D01*
X451778Y890500D01*
G01Y893517D02*
X451236Y893600D01*
X450778Y893725D01*
X450361Y893892D01*
X449903Y894100D01*
X449278Y894433D01*
Y892767D01*
G01X451778Y896700D02*
X451736Y896992D01*
X451611Y897325D01*
X451403Y897533D01*
X451111Y897617D01*
X450820Y897533D01*
X450570Y897283D01*
X450445Y896908D01*
Y896492D01*
X450361Y896242D01*
X450153Y896033D01*
X449861Y895950D01*
X449570Y896075D01*
X449361Y896367D01*
X449278Y896700D01*
X449361Y897033D01*
X449570Y897325D01*
X449861Y897450D01*
X450153Y897367D01*
X450361Y897158D01*
X450445Y896908D01*
Y896492D01*
X450570Y896117D01*
X450820Y895867D01*
X451111Y895783D01*
X451403Y895867D01*
X451611Y896075D01*
X451736Y896408D01*
X451778Y896700D01*
G01X463425Y101333D02*
X463758Y101125D01*
X464133Y101000D01*
X464467D01*
X464800Y101125D01*
X465050Y101333D01*
X465175Y101625D01*
X465092Y101917D01*
X464883Y102167D01*
X464508Y102333D01*
X464008Y102417D01*
X463717Y102583D01*
X463592Y102875D01*
X463675Y103167D01*
X463883Y103375D01*
X464175Y103500D01*
X464467D01*
X464758Y103417D01*
X465008Y103208D01*
G01X466567Y101000D02*
Y103500D01*
X467608D01*
X467942Y103375D01*
X468150Y103208D01*
X468233Y102875D01*
X468150Y102542D01*
X467900Y102333D01*
X467608Y102208D01*
X466567D01*
G01X467608D02*
X468233Y101000D01*
G01X469708Y102042D02*
X470000Y102333D01*
X470250Y102500D01*
X470583Y102583D01*
X470875Y102500D01*
X471083Y102333D01*
X471250Y102083D01*
X471292Y101792D01*
X471250Y101542D01*
X471083Y101292D01*
X470833Y101083D01*
X470542Y101000D01*
X470208Y101083D01*
X469917Y101333D01*
X469750Y101708D01*
X469708Y102125D01*
X469792Y102667D01*
X469917Y102958D01*
X470125Y103250D01*
X470417Y103458D01*
X470708Y103500D01*
X471000Y103417D01*
X471208Y103208D01*
G01X472808Y102042D02*
X473100Y102333D01*
X473350Y102500D01*
X473683Y102583D01*
X473975Y102500D01*
X474183Y102333D01*
X474350Y102083D01*
X474392Y101792D01*
X474350Y101542D01*
X474183Y101292D01*
X473933Y101083D01*
X473642Y101000D01*
X473308Y101083D01*
X473017Y101333D01*
X472850Y101708D01*
X472808Y102125D01*
X472892Y102667D01*
X473017Y102958D01*
X473225Y103250D01*
X473517Y103458D01*
X473808Y103500D01*
X474100Y103417D01*
X474308Y103208D01*
G01X475908Y103083D02*
X476158Y103333D01*
X476450Y103458D01*
X476783Y103500D01*
X477200Y103417D01*
X477492Y103208D01*
X477575Y102958D01*
X477533Y102708D01*
X477367Y102500D01*
X476533Y102083D01*
X476158Y101792D01*
X475908Y101375D01*
X475825Y101000D01*
X477575D01*
G01X463425Y97333D02*
X463758Y97125D01*
X464133Y97000D01*
X464467D01*
X464800Y97125D01*
X465050Y97333D01*
X465175Y97625D01*
X465092Y97917D01*
X464883Y98167D01*
X464508Y98333D01*
X464008Y98417D01*
X463717Y98583D01*
X463592Y98875D01*
X463675Y99167D01*
X463883Y99375D01*
X464175Y99500D01*
X464467D01*
X464758Y99417D01*
X465008Y99208D01*
G01X466567Y97000D02*
Y99500D01*
X467608D01*
X467942Y99375D01*
X468150Y99208D01*
X468233Y98875D01*
X468150Y98542D01*
X467900Y98333D01*
X467608Y98208D01*
X466567D01*
G01X467608D02*
X468233Y97000D01*
G01X469708Y98042D02*
X470000Y98333D01*
X470250Y98500D01*
X470583Y98583D01*
X470875Y98500D01*
X471083Y98333D01*
X471250Y98083D01*
X471292Y97792D01*
X471250Y97542D01*
X471083Y97292D01*
X470833Y97083D01*
X470542Y97000D01*
X470208Y97083D01*
X469917Y97333D01*
X469750Y97708D01*
X469708Y98125D01*
X469792Y98667D01*
X469917Y98958D01*
X470125Y99250D01*
X470417Y99458D01*
X470708Y99500D01*
X471000Y99417D01*
X471208Y99208D01*
G01X472808Y98042D02*
X473100Y98333D01*
X473350Y98500D01*
X473683Y98583D01*
X473975Y98500D01*
X474183Y98333D01*
X474350Y98083D01*
X474392Y97792D01*
X474350Y97542D01*
X474183Y97292D01*
X473933Y97083D01*
X473642Y97000D01*
X473308Y97083D01*
X473017Y97333D01*
X472850Y97708D01*
X472808Y98125D01*
X472892Y98667D01*
X473017Y98958D01*
X473225Y99250D01*
X473517Y99458D01*
X473808Y99500D01*
X474100Y99417D01*
X474308Y99208D01*
G01X477200Y97000D02*
Y99500D01*
X475658Y97708D01*
X477742D01*
G01X463425Y105833D02*
X463758Y105625D01*
X464133Y105500D01*
X464467D01*
X464800Y105625D01*
X465050Y105833D01*
X465175Y106125D01*
X465092Y106417D01*
X464883Y106667D01*
X464508Y106833D01*
X464008Y106917D01*
X463717Y107083D01*
X463592Y107375D01*
X463675Y107667D01*
X463883Y107875D01*
X464175Y108000D01*
X464467D01*
X464758Y107917D01*
X465008Y107708D01*
G01X466567Y105500D02*
Y108000D01*
X467608D01*
X467942Y107875D01*
X468150Y107708D01*
X468233Y107375D01*
X468150Y107042D01*
X467900Y106833D01*
X467608Y106708D01*
X466567D01*
G01X467608D02*
X468233Y105500D01*
G01X469708Y106542D02*
X470000Y106833D01*
X470250Y107000D01*
X470583Y107083D01*
X470875Y107000D01*
X471083Y106833D01*
X471250Y106583D01*
X471292Y106292D01*
X471250Y106042D01*
X471083Y105792D01*
X470833Y105583D01*
X470542Y105500D01*
X470208Y105583D01*
X469917Y105833D01*
X469750Y106208D01*
X469708Y106625D01*
X469792Y107167D01*
X469917Y107458D01*
X470125Y107750D01*
X470417Y107958D01*
X470708Y108000D01*
X471000Y107917D01*
X471208Y107708D01*
G01X473517Y105500D02*
X473600Y106042D01*
X473725Y106500D01*
X473892Y106917D01*
X474100Y107375D01*
X474433Y108000D01*
X472767D01*
G01X476700D02*
X476367Y107917D01*
X476117Y107708D01*
X475950Y107458D01*
X475825Y107125D01*
X475783Y106750D01*
X475825Y106375D01*
X475950Y106042D01*
X476117Y105792D01*
X476367Y105583D01*
X476700Y105500D01*
X477033Y105583D01*
X477283Y105792D01*
X477450Y106042D01*
X477575Y106375D01*
X477617Y106750D01*
X477575Y107125D01*
X477450Y107458D01*
X477283Y107708D01*
X477033Y107917D01*
X476700Y108000D01*
G01X475814Y116333D02*
X476147Y116125D01*
X476522Y116000D01*
X476856D01*
X477189Y116125D01*
X477439Y116333D01*
X477564Y116625D01*
X477481Y116917D01*
X477272Y117167D01*
X476897Y117333D01*
X476397Y117417D01*
X476106Y117583D01*
X475981Y117875D01*
X476064Y118167D01*
X476272Y118375D01*
X476564Y118500D01*
X476856D01*
X477147Y118417D01*
X477397Y118208D01*
G01X479789Y118500D02*
Y116000D01*
G01X478831Y118500D02*
X480747D01*
G01X482056Y116000D02*
Y118500D01*
X483056D01*
X483389Y118375D01*
X483639Y118083D01*
X483722Y117750D01*
X483639Y117417D01*
X483431Y117167D01*
X483056Y117042D01*
X482056D01*
G01X486489Y116000D02*
Y118500D01*
X484947Y116708D01*
X487031D01*
G01X489089Y116000D02*
Y118500D01*
X488589Y118000D01*
G01Y116000D02*
X489589D01*
G01X473425Y109833D02*
X473758Y109625D01*
X474133Y109500D01*
X474467D01*
X474800Y109625D01*
X475050Y109833D01*
X475175Y110125D01*
X475092Y110417D01*
X474883Y110667D01*
X474508Y110833D01*
X474008Y110917D01*
X473717Y111083D01*
X473592Y111375D01*
X473675Y111667D01*
X473883Y111875D01*
X474175Y112000D01*
X474467D01*
X474758Y111917D01*
X475008Y111708D01*
G01X476567Y109500D02*
Y112000D01*
X477608D01*
X477942Y111875D01*
X478150Y111708D01*
X478233Y111375D01*
X478150Y111042D01*
X477900Y110833D01*
X477608Y110708D01*
X476567D01*
G01X477608D02*
X478233Y109500D01*
G01X479708Y110542D02*
X480000Y110833D01*
X480250Y111000D01*
X480583Y111083D01*
X480875Y111000D01*
X481083Y110833D01*
X481250Y110583D01*
X481292Y110292D01*
X481250Y110042D01*
X481083Y109792D01*
X480833Y109583D01*
X480542Y109500D01*
X480208Y109583D01*
X479917Y109833D01*
X479750Y110208D01*
X479708Y110625D01*
X479792Y111167D01*
X479917Y111458D01*
X480125Y111750D01*
X480417Y111958D01*
X480708Y112000D01*
X481000Y111917D01*
X481208Y111708D01*
G01X483600Y109500D02*
X483892Y109542D01*
X484225Y109667D01*
X484433Y109875D01*
X484517Y110167D01*
X484433Y110458D01*
X484183Y110708D01*
X483808Y110833D01*
X483392D01*
X483142Y110917D01*
X482933Y111125D01*
X482850Y111417D01*
X482975Y111708D01*
X483267Y111917D01*
X483600Y112000D01*
X483933Y111917D01*
X484225Y111708D01*
X484350Y111417D01*
X484267Y111125D01*
X484058Y110917D01*
X483808Y110833D01*
X483392D01*
X483017Y110708D01*
X482767Y110458D01*
X482683Y110167D01*
X482767Y109875D01*
X482975Y109667D01*
X483308Y109542D01*
X483600Y109500D01*
G01X487200D02*
Y112000D01*
X485658Y110208D01*
X487742D01*
G01X472354Y132333D02*
X472687Y132125D01*
X473062Y132000D01*
X473396D01*
X473729Y132125D01*
X473979Y132333D01*
X474104Y132625D01*
X474021Y132917D01*
X473812Y133167D01*
X473437Y133333D01*
X472937Y133417D01*
X472646Y133583D01*
X472521Y133875D01*
X472604Y134167D01*
X472812Y134375D01*
X473104Y134500D01*
X473396D01*
X473687Y134417D01*
X473937Y134208D01*
G01X476329Y134500D02*
Y132000D01*
G01X475371Y134500D02*
X477287D01*
G01X478596Y132000D02*
Y134500D01*
X479596D01*
X479929Y134375D01*
X480179Y134083D01*
X480262Y133750D01*
X480179Y133417D01*
X479971Y133167D01*
X479596Y133042D01*
X478596D01*
G01X481737Y134083D02*
X481987Y134333D01*
X482279Y134458D01*
X482612Y134500D01*
X483029Y134417D01*
X483321Y134208D01*
X483404Y133958D01*
X483362Y133708D01*
X483196Y133500D01*
X482362Y133083D01*
X481987Y132792D01*
X481737Y132375D01*
X481654Y132000D01*
X483404D01*
G01X484712Y132375D02*
X484962Y132167D01*
X485254Y132042D01*
X485629Y132000D01*
X486004Y132083D01*
X486296Y132250D01*
X486504Y132542D01*
X486546Y132875D01*
X486462Y133208D01*
X486254Y133417D01*
X485962Y133583D01*
X485671Y133625D01*
X485379Y133583D01*
X485004Y133417D01*
X485129Y134500D01*
X486254D01*
G01X474875Y126833D02*
X475208Y126625D01*
X475583Y126500D01*
X475917D01*
X476250Y126625D01*
X476500Y126833D01*
X476625Y127125D01*
X476542Y127417D01*
X476333Y127667D01*
X475958Y127833D01*
X475458Y127917D01*
X475167Y128083D01*
X475042Y128375D01*
X475125Y128667D01*
X475333Y128875D01*
X475625Y129000D01*
X475917D01*
X476208Y128917D01*
X476458Y128708D01*
G01X478850Y129000D02*
Y126500D01*
G01X477892Y129000D02*
X479808D01*
G01X481117Y126500D02*
Y129000D01*
X482117D01*
X482450Y128875D01*
X482700Y128583D01*
X482783Y128250D01*
X482700Y127917D01*
X482492Y127667D01*
X482117Y127542D01*
X481117D01*
G01X485050Y126500D02*
Y129000D01*
X484550Y128500D01*
G01Y126500D02*
X485550D01*
G01X488650D02*
Y129000D01*
X487108Y127208D01*
X489192D01*
G01X491250Y126500D02*
Y129000D01*
X490750Y128500D01*
G01Y126500D02*
X491750D01*
G01X468375Y141333D02*
X468708Y141125D01*
X469083Y141000D01*
X469417D01*
X469750Y141125D01*
X470000Y141333D01*
X470125Y141625D01*
X470042Y141917D01*
X469833Y142167D01*
X469458Y142333D01*
X468958Y142417D01*
X468667Y142583D01*
X468542Y142875D01*
X468625Y143167D01*
X468833Y143375D01*
X469125Y143500D01*
X469417D01*
X469708Y143417D01*
X469958Y143208D01*
G01X472350Y143500D02*
Y141000D01*
G01X471392Y143500D02*
X473308D01*
G01X474617Y141000D02*
Y143500D01*
X475617D01*
X475950Y143375D01*
X476200Y143083D01*
X476283Y142750D01*
X476200Y142417D01*
X475992Y142167D01*
X475617Y142042D01*
X474617D01*
G01X478550Y141000D02*
Y143500D01*
X478050Y143000D01*
G01Y141000D02*
X479050D01*
G01X480733Y141500D02*
X480983Y141208D01*
X481317Y141042D01*
X481692Y141000D01*
X482025Y141042D01*
X482358Y141250D01*
X482567Y141500D01*
X482608Y141750D01*
X482525Y142042D01*
X482233Y142250D01*
X481942Y142333D01*
X481567D01*
G01X481942D02*
X482192Y142458D01*
X482400Y142667D01*
X482483Y142917D01*
X482400Y143167D01*
X482192Y143375D01*
X481817Y143500D01*
X481442Y143458D01*
X481067Y143292D01*
G01X483833Y141500D02*
X484083Y141208D01*
X484417Y141042D01*
X484792Y141000D01*
X485125Y141042D01*
X485458Y141250D01*
X485667Y141500D01*
X485708Y141750D01*
X485625Y142042D01*
X485333Y142250D01*
X485042Y142333D01*
X484667D01*
G01X485042D02*
X485292Y142458D01*
X485500Y142667D01*
X485583Y142917D01*
X485500Y143167D01*
X485292Y143375D01*
X484917Y143500D01*
X484542Y143458D01*
X484167Y143292D01*
G01X470425Y171833D02*
X470758Y171625D01*
X471133Y171500D01*
X471467D01*
X471800Y171625D01*
X472050Y171833D01*
X472175Y172125D01*
X472092Y172417D01*
X471883Y172667D01*
X471508Y172833D01*
X471008Y172917D01*
X470717Y173083D01*
X470592Y173375D01*
X470675Y173667D01*
X470883Y173875D01*
X471175Y174000D01*
X471467D01*
X471758Y173917D01*
X472008Y173708D01*
G01X473567Y171500D02*
Y174000D01*
X474608D01*
X474942Y173875D01*
X475150Y173708D01*
X475233Y173375D01*
X475150Y173042D01*
X474900Y172833D01*
X474608Y172708D01*
X473567D01*
G01X474608D02*
X475233Y171500D01*
G01X476708Y172542D02*
X477000Y172833D01*
X477250Y173000D01*
X477583Y173083D01*
X477875Y173000D01*
X478083Y172833D01*
X478250Y172583D01*
X478292Y172292D01*
X478250Y172042D01*
X478083Y171792D01*
X477833Y171583D01*
X477542Y171500D01*
X477208Y171583D01*
X476917Y171833D01*
X476750Y172208D01*
X476708Y172625D01*
X476792Y173167D01*
X476917Y173458D01*
X477125Y173750D01*
X477417Y173958D01*
X477708Y174000D01*
X478000Y173917D01*
X478208Y173708D01*
G01X480600Y171500D02*
Y174000D01*
X480100Y173500D01*
G01Y171500D02*
X481100D01*
G01X484200D02*
Y174000D01*
X482658Y172208D01*
X484742D01*
G01X470425Y164833D02*
X470758Y164625D01*
X471133Y164500D01*
X471467D01*
X471800Y164625D01*
X472050Y164833D01*
X472175Y165125D01*
X472092Y165417D01*
X471883Y165667D01*
X471508Y165833D01*
X471008Y165917D01*
X470717Y166083D01*
X470592Y166375D01*
X470675Y166667D01*
X470883Y166875D01*
X471175Y167000D01*
X471467D01*
X471758Y166917D01*
X472008Y166708D01*
G01X473567Y164500D02*
Y167000D01*
X474608D01*
X474942Y166875D01*
X475150Y166708D01*
X475233Y166375D01*
X475150Y166042D01*
X474900Y165833D01*
X474608Y165708D01*
X473567D01*
G01X474608D02*
X475233Y164500D01*
G01X476708Y165542D02*
X477000Y165833D01*
X477250Y166000D01*
X477583Y166083D01*
X477875Y166000D01*
X478083Y165833D01*
X478250Y165583D01*
X478292Y165292D01*
X478250Y165042D01*
X478083Y164792D01*
X477833Y164583D01*
X477542Y164500D01*
X477208Y164583D01*
X476917Y164833D01*
X476750Y165208D01*
X476708Y165625D01*
X476792Y166167D01*
X476917Y166458D01*
X477125Y166750D01*
X477417Y166958D01*
X477708Y167000D01*
X478000Y166917D01*
X478208Y166708D01*
G01X479808Y165542D02*
X480100Y165833D01*
X480350Y166000D01*
X480683Y166083D01*
X480975Y166000D01*
X481183Y165833D01*
X481350Y165583D01*
X481392Y165292D01*
X481350Y165042D01*
X481183Y164792D01*
X480933Y164583D01*
X480642Y164500D01*
X480308Y164583D01*
X480017Y164833D01*
X479850Y165208D01*
X479808Y165625D01*
X479892Y166167D01*
X480017Y166458D01*
X480225Y166750D01*
X480517Y166958D01*
X480808Y167000D01*
X481100Y166917D01*
X481308Y166708D01*
G01X482908Y165542D02*
X483200Y165833D01*
X483450Y166000D01*
X483783Y166083D01*
X484075Y166000D01*
X484283Y165833D01*
X484450Y165583D01*
X484492Y165292D01*
X484450Y165042D01*
X484283Y164792D01*
X484033Y164583D01*
X483742Y164500D01*
X483408Y164583D01*
X483117Y164833D01*
X482950Y165208D01*
X482908Y165625D01*
X482992Y166167D01*
X483117Y166458D01*
X483325Y166750D01*
X483617Y166958D01*
X483908Y167000D01*
X484200Y166917D01*
X484408Y166708D01*
G01X470425Y183833D02*
X470758Y183625D01*
X471133Y183500D01*
X471467D01*
X471800Y183625D01*
X472050Y183833D01*
X472175Y184125D01*
X472092Y184417D01*
X471883Y184667D01*
X471508Y184833D01*
X471008Y184917D01*
X470717Y185083D01*
X470592Y185375D01*
X470675Y185667D01*
X470883Y185875D01*
X471175Y186000D01*
X471467D01*
X471758Y185917D01*
X472008Y185708D01*
G01X473567Y183500D02*
Y186000D01*
X474608D01*
X474942Y185875D01*
X475150Y185708D01*
X475233Y185375D01*
X475150Y185042D01*
X474900Y184833D01*
X474608Y184708D01*
X473567D01*
G01X474608D02*
X475233Y183500D01*
G01X476792Y183792D02*
X477083Y183583D01*
X477417Y183500D01*
X477750Y183583D01*
X478042Y183833D01*
X478250Y184208D01*
X478333Y184583D01*
Y185042D01*
X478250Y185417D01*
X478042Y185750D01*
X477792Y185917D01*
X477500Y186000D01*
X477167Y185917D01*
X476917Y185750D01*
X476750Y185500D01*
X476667Y185167D01*
X476750Y184875D01*
X476958Y184583D01*
X477208Y184417D01*
X477500Y184375D01*
X477833Y184458D01*
X478083Y184667D01*
X478333Y185042D01*
G01X479808Y185583D02*
X480058Y185833D01*
X480350Y185958D01*
X480683Y186000D01*
X481100Y185917D01*
X481392Y185708D01*
X481475Y185458D01*
X481433Y185208D01*
X481267Y185000D01*
X480433Y184583D01*
X480058Y184292D01*
X479808Y183875D01*
X479725Y183500D01*
X481475D01*
G01X483700D02*
Y186000D01*
X483200Y185500D01*
G01Y183500D02*
X484200D01*
G01X470354Y188833D02*
X470687Y188625D01*
X471062Y188500D01*
X471396D01*
X471729Y188625D01*
X471979Y188833D01*
X472104Y189125D01*
X472021Y189417D01*
X471812Y189667D01*
X471437Y189833D01*
X470937Y189917D01*
X470646Y190083D01*
X470521Y190375D01*
X470604Y190667D01*
X470812Y190875D01*
X471104Y191000D01*
X471396D01*
X471687Y190917D01*
X471937Y190708D01*
G01X473496Y188500D02*
Y191000D01*
X474537D01*
X474871Y190875D01*
X475079Y190708D01*
X475162Y190375D01*
X475079Y190042D01*
X474829Y189833D01*
X474537Y189708D01*
X473496D01*
G01X474537D02*
X475162Y188500D01*
G01X476637Y189542D02*
X476929Y189833D01*
X477179Y190000D01*
X477512Y190083D01*
X477804Y190000D01*
X478012Y189833D01*
X478179Y189583D01*
X478221Y189292D01*
X478179Y189042D01*
X478012Y188792D01*
X477762Y188583D01*
X477471Y188500D01*
X477137Y188583D01*
X476846Y188833D01*
X476679Y189208D01*
X476637Y189625D01*
X476721Y190167D01*
X476846Y190458D01*
X477054Y190750D01*
X477346Y190958D01*
X477637Y191000D01*
X477929Y190917D01*
X478137Y190708D01*
G01X481029Y188500D02*
Y191000D01*
X479487Y189208D01*
X481571D01*
G01X482921Y188792D02*
X483212Y188583D01*
X483546Y188500D01*
X483879Y188583D01*
X484171Y188833D01*
X484379Y189208D01*
X484462Y189583D01*
Y190042D01*
X484379Y190417D01*
X484171Y190750D01*
X483921Y190917D01*
X483629Y191000D01*
X483296Y190917D01*
X483046Y190750D01*
X482879Y190500D01*
X482796Y190167D01*
X482879Y189875D01*
X483087Y189583D01*
X483337Y189417D01*
X483629Y189375D01*
X483962Y189458D01*
X484212Y189667D01*
X484462Y190042D01*
G01X470425Y179333D02*
X470758Y179125D01*
X471133Y179000D01*
X471467D01*
X471800Y179125D01*
X472050Y179333D01*
X472175Y179625D01*
X472092Y179917D01*
X471883Y180167D01*
X471508Y180333D01*
X471008Y180417D01*
X470717Y180583D01*
X470592Y180875D01*
X470675Y181167D01*
X470883Y181375D01*
X471175Y181500D01*
X471467D01*
X471758Y181417D01*
X472008Y181208D01*
G01X473567Y179000D02*
Y181500D01*
X474608D01*
X474942Y181375D01*
X475150Y181208D01*
X475233Y180875D01*
X475150Y180542D01*
X474900Y180333D01*
X474608Y180208D01*
X473567D01*
G01X474608D02*
X475233Y179000D01*
G01X476708Y180042D02*
X477000Y180333D01*
X477250Y180500D01*
X477583Y180583D01*
X477875Y180500D01*
X478083Y180333D01*
X478250Y180083D01*
X478292Y179792D01*
X478250Y179542D01*
X478083Y179292D01*
X477833Y179083D01*
X477542Y179000D01*
X477208Y179083D01*
X476917Y179333D01*
X476750Y179708D01*
X476708Y180125D01*
X476792Y180667D01*
X476917Y180958D01*
X477125Y181250D01*
X477417Y181458D01*
X477708Y181500D01*
X478000Y181417D01*
X478208Y181208D01*
G01X479808Y180042D02*
X480100Y180333D01*
X480350Y180500D01*
X480683Y180583D01*
X480975Y180500D01*
X481183Y180333D01*
X481350Y180083D01*
X481392Y179792D01*
X481350Y179542D01*
X481183Y179292D01*
X480933Y179083D01*
X480642Y179000D01*
X480308Y179083D01*
X480017Y179333D01*
X479850Y179708D01*
X479808Y180125D01*
X479892Y180667D01*
X480017Y180958D01*
X480225Y181250D01*
X480517Y181458D01*
X480808Y181500D01*
X481100Y181417D01*
X481308Y181208D01*
G01X483700Y179000D02*
X483992Y179042D01*
X484325Y179167D01*
X484533Y179375D01*
X484617Y179667D01*
X484533Y179958D01*
X484283Y180208D01*
X483908Y180333D01*
X483492D01*
X483242Y180417D01*
X483033Y180625D01*
X482950Y180917D01*
X483075Y181208D01*
X483367Y181417D01*
X483700Y181500D01*
X484033Y181417D01*
X484325Y181208D01*
X484450Y180917D01*
X484367Y180625D01*
X484158Y180417D01*
X483908Y180333D01*
X483492D01*
X483117Y180208D01*
X482867Y179958D01*
X482783Y179667D01*
X482867Y179375D01*
X483075Y179167D01*
X483408Y179042D01*
X483700Y179000D01*
G01X470425Y195833D02*
X470758Y195625D01*
X471133Y195500D01*
X471467D01*
X471800Y195625D01*
X472050Y195833D01*
X472175Y196125D01*
X472092Y196417D01*
X471883Y196667D01*
X471508Y196833D01*
X471008Y196917D01*
X470717Y197083D01*
X470592Y197375D01*
X470675Y197667D01*
X470883Y197875D01*
X471175Y198000D01*
X471467D01*
X471758Y197917D01*
X472008Y197708D01*
G01X473567Y195500D02*
Y198000D01*
X474608D01*
X474942Y197875D01*
X475150Y197708D01*
X475233Y197375D01*
X475150Y197042D01*
X474900Y196833D01*
X474608Y196708D01*
X473567D01*
G01X474608D02*
X475233Y195500D01*
G01X476708Y196542D02*
X477000Y196833D01*
X477250Y197000D01*
X477583Y197083D01*
X477875Y197000D01*
X478083Y196833D01*
X478250Y196583D01*
X478292Y196292D01*
X478250Y196042D01*
X478083Y195792D01*
X477833Y195583D01*
X477542Y195500D01*
X477208Y195583D01*
X476917Y195833D01*
X476750Y196208D01*
X476708Y196625D01*
X476792Y197167D01*
X476917Y197458D01*
X477125Y197750D01*
X477417Y197958D01*
X477708Y198000D01*
X478000Y197917D01*
X478208Y197708D01*
G01X480600Y195500D02*
Y198000D01*
X480100Y197500D01*
G01Y195500D02*
X481100D01*
G01X482783Y195875D02*
X483033Y195667D01*
X483325Y195542D01*
X483700Y195500D01*
X484075Y195583D01*
X484367Y195750D01*
X484575Y196042D01*
X484617Y196375D01*
X484533Y196708D01*
X484325Y196917D01*
X484033Y197083D01*
X483742Y197125D01*
X483450Y197083D01*
X483075Y196917D01*
X483200Y198000D01*
X484325D01*
G01X467167Y217925D02*
X467375Y218258D01*
X467500Y218633D01*
Y218967D01*
X467375Y219300D01*
X467167Y219550D01*
X466875Y219675D01*
X466583Y219592D01*
X466333Y219383D01*
X466167Y219008D01*
X466083Y218508D01*
X465917Y218217D01*
X465625Y218092D01*
X465333Y218175D01*
X465125Y218383D01*
X465000Y218675D01*
Y218967D01*
X465083Y219258D01*
X465292Y219508D01*
G01X465000Y221900D02*
X467500D01*
G01X465000Y220942D02*
Y222858D01*
G01X467500Y224167D02*
X465000D01*
Y225167D01*
X465125Y225500D01*
X465417Y225750D01*
X465750Y225833D01*
X466083Y225750D01*
X466333Y225542D01*
X466458Y225167D01*
Y224167D01*
G01X467000Y227183D02*
X467292Y227433D01*
X467458Y227767D01*
X467500Y228142D01*
X467458Y228475D01*
X467250Y228808D01*
X467000Y229017D01*
X466750Y229058D01*
X466458Y228975D01*
X466250Y228683D01*
X466167Y228392D01*
Y228017D01*
G01Y228392D02*
X466042Y228642D01*
X465833Y228850D01*
X465583Y228933D01*
X465333Y228850D01*
X465125Y228642D01*
X465000Y228267D01*
X465042Y227892D01*
X465208Y227517D01*
G01X467500Y231200D02*
X465000D01*
X465500Y230700D01*
G01X467500D02*
Y231700D01*
G01X476096Y217925D02*
X476304Y218258D01*
X476429Y218633D01*
Y218967D01*
X476304Y219300D01*
X476096Y219550D01*
X475804Y219675D01*
X475512Y219592D01*
X475262Y219383D01*
X475096Y219008D01*
X475012Y218508D01*
X474846Y218217D01*
X474554Y218092D01*
X474262Y218175D01*
X474054Y218383D01*
X473929Y218675D01*
Y218967D01*
X474012Y219258D01*
X474221Y219508D01*
G01X473929Y221900D02*
X476429D01*
G01X473929Y220942D02*
Y222858D01*
G01X476429Y224167D02*
X473929D01*
Y225167D01*
X474054Y225500D01*
X474346Y225750D01*
X474679Y225833D01*
X475012Y225750D01*
X475262Y225542D01*
X475387Y225167D01*
Y224167D01*
G01X475929Y227183D02*
X476221Y227433D01*
X476387Y227767D01*
X476429Y228142D01*
X476387Y228475D01*
X476179Y228808D01*
X475929Y229017D01*
X475679Y229058D01*
X475387Y228975D01*
X475179Y228683D01*
X475096Y228392D01*
Y228017D01*
G01Y228392D02*
X474971Y228642D01*
X474762Y228850D01*
X474512Y228933D01*
X474262Y228850D01*
X474054Y228642D01*
X473929Y228267D01*
X473971Y227892D01*
X474137Y227517D01*
G01X475387Y230408D02*
X475096Y230700D01*
X474929Y230950D01*
X474846Y231283D01*
X474929Y231575D01*
X475096Y231783D01*
X475346Y231950D01*
X475637Y231992D01*
X475887Y231950D01*
X476137Y231783D01*
X476346Y231533D01*
X476429Y231242D01*
X476346Y230908D01*
X476096Y230617D01*
X475721Y230450D01*
X475304Y230408D01*
X474762Y230492D01*
X474471Y230617D01*
X474179Y230825D01*
X473971Y231117D01*
X473929Y231408D01*
X474012Y231700D01*
X474221Y231908D01*
G01X471667Y214925D02*
X471875Y215258D01*
X472000Y215633D01*
Y215967D01*
X471875Y216300D01*
X471667Y216550D01*
X471375Y216675D01*
X471083Y216592D01*
X470833Y216383D01*
X470667Y216008D01*
X470583Y215508D01*
X470417Y215217D01*
X470125Y215092D01*
X469833Y215175D01*
X469625Y215383D01*
X469500Y215675D01*
Y215967D01*
X469583Y216258D01*
X469792Y216508D01*
G01X469500Y218900D02*
X472000D01*
G01X469500Y217942D02*
Y219858D01*
G01X472000Y221167D02*
X469500D01*
Y222167D01*
X469625Y222500D01*
X469917Y222750D01*
X470250Y222833D01*
X470583Y222750D01*
X470833Y222542D01*
X470958Y222167D01*
Y221167D01*
G01X471500Y224183D02*
X471792Y224433D01*
X471958Y224767D01*
X472000Y225142D01*
X471958Y225475D01*
X471750Y225808D01*
X471500Y226017D01*
X471250Y226058D01*
X470958Y225975D01*
X470750Y225683D01*
X470667Y225392D01*
Y225017D01*
G01Y225392D02*
X470542Y225642D01*
X470333Y225850D01*
X470083Y225933D01*
X469833Y225850D01*
X469625Y225642D01*
X469500Y225267D01*
X469542Y224892D01*
X469708Y224517D01*
G01X471708Y227492D02*
X471917Y227783D01*
X472000Y228117D01*
X471917Y228450D01*
X471667Y228742D01*
X471292Y228950D01*
X470917Y229033D01*
X470458D01*
X470083Y228950D01*
X469750Y228742D01*
X469583Y228492D01*
X469500Y228200D01*
X469583Y227867D01*
X469750Y227617D01*
X470000Y227450D01*
X470333Y227367D01*
X470625Y227450D01*
X470917Y227658D01*
X471083Y227908D01*
X471125Y228200D01*
X471042Y228533D01*
X470833Y228783D01*
X470458Y229033D01*
G01X466925Y237333D02*
X467258Y237125D01*
X467633Y237000D01*
X467967D01*
X468300Y237125D01*
X468550Y237333D01*
X468675Y237625D01*
X468592Y237917D01*
X468383Y238167D01*
X468008Y238333D01*
X467508Y238417D01*
X467217Y238583D01*
X467092Y238875D01*
X467175Y239167D01*
X467383Y239375D01*
X467675Y239500D01*
X467967D01*
X468258Y239417D01*
X468508Y239208D01*
G01X470067Y237000D02*
Y239500D01*
X471108D01*
X471442Y239375D01*
X471650Y239208D01*
X471733Y238875D01*
X471650Y238542D01*
X471400Y238333D01*
X471108Y238208D01*
X470067D01*
G01X471108D02*
X471733Y237000D01*
G01X473208Y238042D02*
X473500Y238333D01*
X473750Y238500D01*
X474083Y238583D01*
X474375Y238500D01*
X474583Y238333D01*
X474750Y238083D01*
X474792Y237792D01*
X474750Y237542D01*
X474583Y237292D01*
X474333Y237083D01*
X474042Y237000D01*
X473708Y237083D01*
X473417Y237333D01*
X473250Y237708D01*
X473208Y238125D01*
X473292Y238667D01*
X473417Y238958D01*
X473625Y239250D01*
X473917Y239458D01*
X474208Y239500D01*
X474500Y239417D01*
X474708Y239208D01*
G01X477100Y237000D02*
X477392Y237042D01*
X477725Y237167D01*
X477933Y237375D01*
X478017Y237667D01*
X477933Y237958D01*
X477683Y238208D01*
X477308Y238333D01*
X476892D01*
X476642Y238417D01*
X476433Y238625D01*
X476350Y238917D01*
X476475Y239208D01*
X476767Y239417D01*
X477100Y239500D01*
X477433Y239417D01*
X477725Y239208D01*
X477850Y238917D01*
X477767Y238625D01*
X477558Y238417D01*
X477308Y238333D01*
X476892D01*
X476517Y238208D01*
X476267Y237958D01*
X476183Y237667D01*
X476267Y237375D01*
X476475Y237167D01*
X476808Y237042D01*
X477100Y237000D01*
G01X479492Y237292D02*
X479783Y237083D01*
X480117Y237000D01*
X480450Y237083D01*
X480742Y237333D01*
X480950Y237708D01*
X481033Y238083D01*
Y238542D01*
X480950Y238917D01*
X480742Y239250D01*
X480492Y239417D01*
X480200Y239500D01*
X479867Y239417D01*
X479617Y239250D01*
X479450Y239000D01*
X479367Y238667D01*
X479450Y238375D01*
X479658Y238083D01*
X479908Y237917D01*
X480200Y237875D01*
X480533Y237958D01*
X480783Y238167D01*
X481033Y238542D01*
G01X464167Y234925D02*
X464375Y235258D01*
X464500Y235633D01*
Y235967D01*
X464375Y236300D01*
X464167Y236550D01*
X463875Y236675D01*
X463583Y236592D01*
X463333Y236383D01*
X463167Y236008D01*
X463083Y235508D01*
X462917Y235217D01*
X462625Y235092D01*
X462333Y235175D01*
X462125Y235383D01*
X462000Y235675D01*
Y235967D01*
X462083Y236258D01*
X462292Y236508D01*
G01X464500Y238067D02*
X462000D01*
Y239108D01*
X462125Y239442D01*
X462292Y239650D01*
X462625Y239733D01*
X462958Y239650D01*
X463167Y239400D01*
X463292Y239108D01*
Y238067D01*
G01Y239108D02*
X464500Y239733D01*
G01X463458Y241208D02*
X463167Y241500D01*
X463000Y241750D01*
X462917Y242083D01*
X463000Y242375D01*
X463167Y242583D01*
X463417Y242750D01*
X463708Y242792D01*
X463958Y242750D01*
X464208Y242583D01*
X464417Y242333D01*
X464500Y242042D01*
X464417Y241708D01*
X464167Y241417D01*
X463792Y241250D01*
X463375Y241208D01*
X462833Y241292D01*
X462542Y241417D01*
X462250Y241625D01*
X462042Y241917D01*
X462000Y242208D01*
X462083Y242500D01*
X462292Y242708D01*
G01X464208Y244392D02*
X464417Y244683D01*
X464500Y245017D01*
X464417Y245350D01*
X464167Y245642D01*
X463792Y245850D01*
X463417Y245933D01*
X462958D01*
X462583Y245850D01*
X462250Y245642D01*
X462083Y245392D01*
X462000Y245100D01*
X462083Y244767D01*
X462250Y244517D01*
X462500Y244350D01*
X462833Y244267D01*
X463125Y244350D01*
X463417Y244558D01*
X463583Y244808D01*
X463625Y245100D01*
X463542Y245433D01*
X463333Y245683D01*
X462958Y245933D01*
G01X464125Y247283D02*
X464333Y247533D01*
X464458Y247825D01*
X464500Y248200D01*
X464417Y248575D01*
X464250Y248867D01*
X463958Y249075D01*
X463625Y249117D01*
X463292Y249033D01*
X463083Y248825D01*
X462917Y248533D01*
X462875Y248242D01*
X462917Y247950D01*
X463083Y247575D01*
X462000Y247700D01*
Y248825D01*
G01X466925Y243833D02*
X467258Y243625D01*
X467633Y243500D01*
X467967D01*
X468300Y243625D01*
X468550Y243833D01*
X468675Y244125D01*
X468592Y244417D01*
X468383Y244667D01*
X468008Y244833D01*
X467508Y244917D01*
X467217Y245083D01*
X467092Y245375D01*
X467175Y245667D01*
X467383Y245875D01*
X467675Y246000D01*
X467967D01*
X468258Y245917D01*
X468508Y245708D01*
G01X470067Y243500D02*
Y246000D01*
X471108D01*
X471442Y245875D01*
X471650Y245708D01*
X471733Y245375D01*
X471650Y245042D01*
X471400Y244833D01*
X471108Y244708D01*
X470067D01*
G01X471108D02*
X471733Y243500D01*
G01X473917D02*
X474000Y244042D01*
X474125Y244500D01*
X474292Y244917D01*
X474500Y245375D01*
X474833Y246000D01*
X473167D01*
G01X476183Y244000D02*
X476433Y243708D01*
X476767Y243542D01*
X477142Y243500D01*
X477475Y243542D01*
X477808Y243750D01*
X478017Y244000D01*
X478058Y244250D01*
X477975Y244542D01*
X477683Y244750D01*
X477392Y244833D01*
X477017D01*
G01X477392D02*
X477642Y244958D01*
X477850Y245167D01*
X477933Y245417D01*
X477850Y245667D01*
X477642Y245875D01*
X477267Y246000D01*
X476892Y245958D01*
X476517Y245792D01*
G01X479408Y245583D02*
X479658Y245833D01*
X479950Y245958D01*
X480283Y246000D01*
X480700Y245917D01*
X480992Y245708D01*
X481075Y245458D01*
X481033Y245208D01*
X480867Y245000D01*
X480033Y244583D01*
X479658Y244292D01*
X479408Y243875D01*
X479325Y243500D01*
X481075D01*
G01X473967Y268000D02*
Y270500D01*
X475008D01*
X475342Y270375D01*
X475550Y270208D01*
X475633Y269875D01*
X475550Y269542D01*
X475300Y269333D01*
X475008Y269208D01*
X473967D01*
G01X475008D02*
X475633Y268000D01*
G01X476983Y268375D02*
X477233Y268167D01*
X477525Y268042D01*
X477900Y268000D01*
X478275Y268083D01*
X478567Y268250D01*
X478775Y268542D01*
X478817Y268875D01*
X478733Y269208D01*
X478525Y269417D01*
X478233Y269583D01*
X477942Y269625D01*
X477650Y269583D01*
X477275Y269417D01*
X477400Y270500D01*
X478525D01*
G01X480083Y268500D02*
X480333Y268208D01*
X480667Y268042D01*
X481042Y268000D01*
X481375Y268042D01*
X481708Y268250D01*
X481917Y268500D01*
X481958Y268750D01*
X481875Y269042D01*
X481583Y269250D01*
X481292Y269333D01*
X480917D01*
G01X481292D02*
X481542Y269458D01*
X481750Y269667D01*
X481833Y269917D01*
X481750Y270167D01*
X481542Y270375D01*
X481167Y270500D01*
X480792Y270458D01*
X480417Y270292D01*
G01X484100Y268000D02*
Y270500D01*
X483600Y270000D01*
G01Y268000D02*
X484600D01*
G01X486408Y270083D02*
X486658Y270333D01*
X486950Y270458D01*
X487283Y270500D01*
X487700Y270417D01*
X487992Y270208D01*
X488075Y269958D01*
X488033Y269708D01*
X487867Y269500D01*
X487033Y269083D01*
X486658Y268792D01*
X486408Y268375D01*
X486325Y268000D01*
X488075D01*
G01X469517Y262000D02*
Y264500D01*
X470558D01*
X470892Y264375D01*
X471100Y264208D01*
X471183Y263875D01*
X471100Y263542D01*
X470850Y263333D01*
X470558Y263208D01*
X469517D01*
G01X470558D02*
X471183Y262000D01*
G01X472533Y262375D02*
X472783Y262167D01*
X473075Y262042D01*
X473450Y262000D01*
X473825Y262083D01*
X474117Y262250D01*
X474325Y262542D01*
X474367Y262875D01*
X474283Y263208D01*
X474075Y263417D01*
X473783Y263583D01*
X473492Y263625D01*
X473200Y263583D01*
X472825Y263417D01*
X472950Y264500D01*
X474075D01*
G01X476550Y262000D02*
X476842Y262042D01*
X477175Y262167D01*
X477383Y262375D01*
X477467Y262667D01*
X477383Y262958D01*
X477133Y263208D01*
X476758Y263333D01*
X476342D01*
X476092Y263417D01*
X475883Y263625D01*
X475800Y263917D01*
X475925Y264208D01*
X476217Y264417D01*
X476550Y264500D01*
X476883Y264417D01*
X477175Y264208D01*
X477300Y263917D01*
X477217Y263625D01*
X477008Y263417D01*
X476758Y263333D01*
X476342D01*
X475967Y263208D01*
X475717Y262958D01*
X475633Y262667D01*
X475717Y262375D01*
X475925Y262167D01*
X476258Y262042D01*
X476550Y262000D01*
G01X479567D02*
X479650Y262542D01*
X479775Y263000D01*
X479942Y263417D01*
X480150Y263875D01*
X480483Y264500D01*
X478817D01*
G01X470000Y275800D02*
X472500D01*
G01X470000Y274842D02*
Y276758D01*
G01X472500Y278067D02*
X470000D01*
Y279067D01*
X470125Y279400D01*
X470417Y279650D01*
X470750Y279733D01*
X471083Y279650D01*
X471333Y279442D01*
X471458Y279067D01*
Y278067D01*
G01X472500Y282000D02*
X470000D01*
X470500Y281500D01*
G01X472500D02*
Y282500D01*
G01Y285017D02*
X471958Y285100D01*
X471500Y285225D01*
X471083Y285392D01*
X470625Y285600D01*
X470000Y285933D01*
Y284267D01*
G01X472500Y288200D02*
X470000D01*
X470500Y287700D01*
G01X472500D02*
Y288700D01*
G01X475967Y276500D02*
Y279000D01*
X477008D01*
X477342Y278875D01*
X477550Y278708D01*
X477633Y278375D01*
X477550Y278042D01*
X477300Y277833D01*
X477008Y277708D01*
X475967D01*
G01X477008D02*
X477633Y276500D01*
G01X478983Y276875D02*
X479233Y276667D01*
X479525Y276542D01*
X479900Y276500D01*
X480275Y276583D01*
X480567Y276750D01*
X480775Y277042D01*
X480817Y277375D01*
X480733Y277708D01*
X480525Y277917D01*
X480233Y278083D01*
X479942Y278125D01*
X479650Y278083D01*
X479275Y277917D01*
X479400Y279000D01*
X480525D01*
G01X482083Y277000D02*
X482333Y276708D01*
X482667Y276542D01*
X483042Y276500D01*
X483375Y276542D01*
X483708Y276750D01*
X483917Y277000D01*
X483958Y277250D01*
X483875Y277542D01*
X483583Y277750D01*
X483292Y277833D01*
X482917D01*
G01X483292D02*
X483542Y277958D01*
X483750Y278167D01*
X483833Y278417D01*
X483750Y278667D01*
X483542Y278875D01*
X483167Y279000D01*
X482792Y278958D01*
X482417Y278792D01*
G01X486100Y276500D02*
Y279000D01*
X485600Y278500D01*
G01Y276500D02*
X486600D01*
G01X488283Y277000D02*
X488533Y276708D01*
X488867Y276542D01*
X489242Y276500D01*
X489575Y276542D01*
X489908Y276750D01*
X490117Y277000D01*
X490158Y277250D01*
X490075Y277542D01*
X489783Y277750D01*
X489492Y277833D01*
X489117D01*
G01X489492D02*
X489742Y277958D01*
X489950Y278167D01*
X490033Y278417D01*
X489950Y278667D01*
X489742Y278875D01*
X489367Y279000D01*
X488992Y278958D01*
X488617Y278792D01*
G01X475017Y272000D02*
Y274500D01*
X476058D01*
X476392Y274375D01*
X476600Y274208D01*
X476683Y273875D01*
X476600Y273542D01*
X476350Y273333D01*
X476058Y273208D01*
X475017D01*
G01X476058D02*
X476683Y272000D01*
G01X478033Y272375D02*
X478283Y272167D01*
X478575Y272042D01*
X478950Y272000D01*
X479325Y272083D01*
X479617Y272250D01*
X479825Y272542D01*
X479867Y272875D01*
X479783Y273208D01*
X479575Y273417D01*
X479283Y273583D01*
X478992Y273625D01*
X478700Y273583D01*
X478325Y273417D01*
X478450Y274500D01*
X479575D01*
G01X482050Y272000D02*
X482342Y272042D01*
X482675Y272167D01*
X482883Y272375D01*
X482967Y272667D01*
X482883Y272958D01*
X482633Y273208D01*
X482258Y273333D01*
X481842D01*
X481592Y273417D01*
X481383Y273625D01*
X481300Y273917D01*
X481425Y274208D01*
X481717Y274417D01*
X482050Y274500D01*
X482383Y274417D01*
X482675Y274208D01*
X482800Y273917D01*
X482717Y273625D01*
X482508Y273417D01*
X482258Y273333D01*
X481842D01*
X481467Y273208D01*
X481217Y272958D01*
X481133Y272667D01*
X481217Y272375D01*
X481425Y272167D01*
X481758Y272042D01*
X482050Y272000D01*
G01X485150D02*
X485442Y272042D01*
X485775Y272167D01*
X485983Y272375D01*
X486067Y272667D01*
X485983Y272958D01*
X485733Y273208D01*
X485358Y273333D01*
X484942D01*
X484692Y273417D01*
X484483Y273625D01*
X484400Y273917D01*
X484525Y274208D01*
X484817Y274417D01*
X485150Y274500D01*
X485483Y274417D01*
X485775Y274208D01*
X485900Y273917D01*
X485817Y273625D01*
X485608Y273417D01*
X485358Y273333D01*
X484942D01*
X484567Y273208D01*
X484317Y272958D01*
X484233Y272667D01*
X484317Y272375D01*
X484525Y272167D01*
X484858Y272042D01*
X485150Y272000D01*
G01X475425Y281333D02*
X475758Y281125D01*
X476133Y281000D01*
X476467D01*
X476800Y281125D01*
X477050Y281333D01*
X477175Y281625D01*
X477092Y281917D01*
X476883Y282167D01*
X476508Y282333D01*
X476008Y282417D01*
X475717Y282583D01*
X475592Y282875D01*
X475675Y283167D01*
X475883Y283375D01*
X476175Y283500D01*
X476467D01*
X476758Y283417D01*
X477008Y283208D01*
G01X478567Y281000D02*
Y283500D01*
X479608D01*
X479942Y283375D01*
X480150Y283208D01*
X480233Y282875D01*
X480150Y282542D01*
X479900Y282333D01*
X479608Y282208D01*
X478567D01*
G01X479608D02*
X480233Y281000D01*
G01X481583Y281375D02*
X481833Y281167D01*
X482125Y281042D01*
X482500Y281000D01*
X482875Y281083D01*
X483167Y281250D01*
X483375Y281542D01*
X483417Y281875D01*
X483333Y282208D01*
X483125Y282417D01*
X482833Y282583D01*
X482542Y282625D01*
X482250Y282583D01*
X481875Y282417D01*
X482000Y283500D01*
X483125D01*
G01X484892Y281292D02*
X485183Y281083D01*
X485517Y281000D01*
X485850Y281083D01*
X486142Y281333D01*
X486350Y281708D01*
X486433Y282083D01*
Y282542D01*
X486350Y282917D01*
X486142Y283250D01*
X485892Y283417D01*
X485600Y283500D01*
X485267Y283417D01*
X485017Y283250D01*
X484850Y283000D01*
X484767Y282667D01*
X484850Y282375D01*
X485058Y282083D01*
X485308Y281917D01*
X485600Y281875D01*
X485933Y281958D01*
X486183Y282167D01*
X486433Y282542D01*
G01X488617Y281000D02*
X488700Y281542D01*
X488825Y282000D01*
X488992Y282417D01*
X489200Y282875D01*
X489533Y283500D01*
X487867D01*
G01X476375Y285833D02*
X476708Y285625D01*
X477083Y285500D01*
X477417D01*
X477750Y285625D01*
X478000Y285833D01*
X478125Y286125D01*
X478042Y286417D01*
X477833Y286667D01*
X477458Y286833D01*
X476958Y286917D01*
X476667Y287083D01*
X476542Y287375D01*
X476625Y287667D01*
X476833Y287875D01*
X477125Y288000D01*
X477417D01*
X477708Y287917D01*
X477958Y287708D01*
G01X481267Y287792D02*
X481017Y287917D01*
X480725Y288000D01*
X480392D01*
X480017Y287875D01*
X479725Y287667D01*
X479517Y287417D01*
X479350Y287000D01*
X479308Y286625D01*
X479392Y286250D01*
X479517Y286000D01*
X479767Y285750D01*
X480058Y285583D01*
X480350Y285500D01*
X480642D01*
X480933Y285583D01*
X481183Y285708D01*
X481392Y285875D01*
G01X483450Y285500D02*
Y288000D01*
X482950Y287500D01*
G01Y285500D02*
X483950D01*
G01X486550D02*
Y288000D01*
X486050Y287500D01*
G01Y285500D02*
X487050D01*
G01X488858Y287583D02*
X489108Y287833D01*
X489400Y287958D01*
X489733Y288000D01*
X490150Y287917D01*
X490442Y287708D01*
X490525Y287458D01*
X490483Y287208D01*
X490317Y287000D01*
X489483Y286583D01*
X489108Y286292D01*
X488858Y285875D01*
X488775Y285500D01*
X490525D01*
G01X491833Y285875D02*
X492083Y285667D01*
X492375Y285542D01*
X492750Y285500D01*
X493125Y285583D01*
X493417Y285750D01*
X493625Y286042D01*
X493667Y286375D01*
X493583Y286708D01*
X493375Y286917D01*
X493083Y287083D01*
X492792Y287125D01*
X492500Y287083D01*
X492125Y286917D01*
X492250Y288000D01*
X493375D01*
G01X475773Y295083D02*
Y310483D01*
G01X498273Y295083D02*
X475773D01*
G01X474755Y291800D02*
Y295800D01*
X467355D01*
G01X464722Y293425D02*
X464930Y293758D01*
X465055Y294133D01*
Y294467D01*
X464930Y294800D01*
X464722Y295050D01*
X464430Y295175D01*
X464138Y295092D01*
X463888Y294883D01*
X463722Y294508D01*
X463638Y294008D01*
X463472Y293717D01*
X463180Y293592D01*
X462888Y293675D01*
X462680Y293883D01*
X462555Y294175D01*
Y294467D01*
X462638Y294758D01*
X462847Y295008D01*
G01X465055Y296567D02*
X462555D01*
Y297608D01*
X462680Y297942D01*
X462847Y298150D01*
X463180Y298233D01*
X463513Y298150D01*
X463722Y297900D01*
X463847Y297608D01*
Y296567D01*
G01Y297608D02*
X465055Y298233D01*
G01Y300500D02*
X465013Y300792D01*
X464888Y301125D01*
X464680Y301333D01*
X464388Y301417D01*
X464097Y301333D01*
X463847Y301083D01*
X463722Y300708D01*
Y300292D01*
X463638Y300042D01*
X463430Y299833D01*
X463138Y299750D01*
X462847Y299875D01*
X462638Y300167D01*
X462555Y300500D01*
X462638Y300833D01*
X462847Y301125D01*
X463138Y301250D01*
X463430Y301167D01*
X463638Y300958D01*
X463722Y300708D01*
Y300292D01*
X463847Y299917D01*
X464097Y299667D01*
X464388Y299583D01*
X464680Y299667D01*
X464888Y299875D01*
X465013Y300208D01*
X465055Y300500D01*
G01X462555Y303600D02*
X462638Y303267D01*
X462847Y303017D01*
X463097Y302850D01*
X463430Y302725D01*
X463805Y302683D01*
X464180Y302725D01*
X464513Y302850D01*
X464763Y303017D01*
X464972Y303267D01*
X465055Y303600D01*
X464972Y303933D01*
X464763Y304183D01*
X464513Y304350D01*
X464180Y304475D01*
X463805Y304517D01*
X463430Y304475D01*
X463097Y304350D01*
X462847Y304183D01*
X462638Y303933D01*
X462555Y303600D01*
G01X465055Y306700D02*
X462555D01*
X463055Y306200D01*
G01X465055D02*
Y307200D01*
G01X476375Y289833D02*
X476708Y289625D01*
X477083Y289500D01*
X477417D01*
X477750Y289625D01*
X478000Y289833D01*
X478125Y290125D01*
X478042Y290417D01*
X477833Y290667D01*
X477458Y290833D01*
X476958Y290917D01*
X476667Y291083D01*
X476542Y291375D01*
X476625Y291667D01*
X476833Y291875D01*
X477125Y292000D01*
X477417D01*
X477708Y291917D01*
X477958Y291708D01*
G01X481267Y291792D02*
X481017Y291917D01*
X480725Y292000D01*
X480392D01*
X480017Y291875D01*
X479725Y291667D01*
X479517Y291417D01*
X479350Y291000D01*
X479308Y290625D01*
X479392Y290250D01*
X479517Y290000D01*
X479767Y289750D01*
X480058Y289583D01*
X480350Y289500D01*
X480642D01*
X480933Y289583D01*
X481183Y289708D01*
X481392Y289875D01*
G01X483450Y289500D02*
Y292000D01*
X482950Y291500D01*
G01Y289500D02*
X483950D01*
G01X486550D02*
Y292000D01*
X486050Y291500D01*
G01Y289500D02*
X487050D01*
G01X488858Y291583D02*
X489108Y291833D01*
X489400Y291958D01*
X489733Y292000D01*
X490150Y291917D01*
X490442Y291708D01*
X490525Y291458D01*
X490483Y291208D01*
X490317Y291000D01*
X489483Y290583D01*
X489108Y290292D01*
X488858Y289875D01*
X488775Y289500D01*
X490525D01*
G01X493250D02*
Y292000D01*
X491708Y290208D01*
X493792D01*
G01X475773Y310483D02*
X498273D01*
G01X479722Y455375D02*
X479930Y455708D01*
X480055Y456083D01*
Y456417D01*
X479930Y456750D01*
X479722Y457000D01*
X479430Y457125D01*
X479138Y457042D01*
X478888Y456833D01*
X478722Y456458D01*
X478638Y455958D01*
X478472Y455667D01*
X478180Y455542D01*
X477888Y455625D01*
X477680Y455833D01*
X477555Y456125D01*
Y456417D01*
X477638Y456708D01*
X477847Y456958D01*
G01X477763Y460267D02*
X477638Y460017D01*
X477555Y459725D01*
Y459392D01*
X477680Y459017D01*
X477888Y458725D01*
X478138Y458517D01*
X478555Y458350D01*
X478930Y458308D01*
X479305Y458392D01*
X479555Y458517D01*
X479805Y458767D01*
X479972Y459058D01*
X480055Y459350D01*
Y459642D01*
X479972Y459933D01*
X479847Y460183D01*
X479680Y460392D01*
G01X480055Y462450D02*
X477555D01*
X478055Y461950D01*
G01X480055D02*
Y462950D01*
G01X477555Y465550D02*
X477638Y465217D01*
X477847Y464967D01*
X478097Y464800D01*
X478430Y464675D01*
X478805Y464633D01*
X479180Y464675D01*
X479513Y464800D01*
X479763Y464967D01*
X479972Y465217D01*
X480055Y465550D01*
X479972Y465883D01*
X479763Y466133D01*
X479513Y466300D01*
X479180Y466425D01*
X478805Y466467D01*
X478430Y466425D01*
X478097Y466300D01*
X477847Y466133D01*
X477638Y465883D01*
X477555Y465550D01*
G01X480055Y468567D02*
X479513Y468650D01*
X479055Y468775D01*
X478638Y468942D01*
X478180Y469150D01*
X477555Y469483D01*
Y467817D01*
G01Y471750D02*
X477638Y471417D01*
X477847Y471167D01*
X478097Y471000D01*
X478430Y470875D01*
X478805Y470833D01*
X479180Y470875D01*
X479513Y471000D01*
X479763Y471167D01*
X479972Y471417D01*
X480055Y471750D01*
X479972Y472083D01*
X479763Y472333D01*
X479513Y472500D01*
X479180Y472625D01*
X478805Y472667D01*
X478430Y472625D01*
X478097Y472500D01*
X477847Y472333D01*
X477638Y472083D01*
X477555Y471750D01*
G01X475722Y455375D02*
X475930Y455708D01*
X476055Y456083D01*
Y456417D01*
X475930Y456750D01*
X475722Y457000D01*
X475430Y457125D01*
X475138Y457042D01*
X474888Y456833D01*
X474722Y456458D01*
X474638Y455958D01*
X474472Y455667D01*
X474180Y455542D01*
X473888Y455625D01*
X473680Y455833D01*
X473555Y456125D01*
Y456417D01*
X473638Y456708D01*
X473847Y456958D01*
G01X473763Y460267D02*
X473638Y460017D01*
X473555Y459725D01*
Y459392D01*
X473680Y459017D01*
X473888Y458725D01*
X474138Y458517D01*
X474555Y458350D01*
X474930Y458308D01*
X475305Y458392D01*
X475555Y458517D01*
X475805Y458767D01*
X475972Y459058D01*
X476055Y459350D01*
Y459642D01*
X475972Y459933D01*
X475847Y460183D01*
X475680Y460392D01*
G01X476055Y462450D02*
X473555D01*
X474055Y461950D01*
G01X476055D02*
Y462950D01*
G01X473555Y465550D02*
X473638Y465217D01*
X473847Y464967D01*
X474097Y464800D01*
X474430Y464675D01*
X474805Y464633D01*
X475180Y464675D01*
X475513Y464800D01*
X475763Y464967D01*
X475972Y465217D01*
X476055Y465550D01*
X475972Y465883D01*
X475763Y466133D01*
X475513Y466300D01*
X475180Y466425D01*
X474805Y466467D01*
X474430Y466425D01*
X474097Y466300D01*
X473847Y466133D01*
X473638Y465883D01*
X473555Y465550D01*
G01X476055Y468567D02*
X475513Y468650D01*
X475055Y468775D01*
X474638Y468942D01*
X474180Y469150D01*
X473555Y469483D01*
Y467817D01*
G01X476055Y471750D02*
X473555D01*
X474055Y471250D01*
G01X476055D02*
Y472250D01*
G01X471722Y455375D02*
X471930Y455708D01*
X472055Y456083D01*
Y456417D01*
X471930Y456750D01*
X471722Y457000D01*
X471430Y457125D01*
X471138Y457042D01*
X470888Y456833D01*
X470722Y456458D01*
X470638Y455958D01*
X470472Y455667D01*
X470180Y455542D01*
X469888Y455625D01*
X469680Y455833D01*
X469555Y456125D01*
Y456417D01*
X469638Y456708D01*
X469847Y456958D01*
G01X469763Y460267D02*
X469638Y460017D01*
X469555Y459725D01*
Y459392D01*
X469680Y459017D01*
X469888Y458725D01*
X470138Y458517D01*
X470555Y458350D01*
X470930Y458308D01*
X471305Y458392D01*
X471555Y458517D01*
X471805Y458767D01*
X471972Y459058D01*
X472055Y459350D01*
Y459642D01*
X471972Y459933D01*
X471847Y460183D01*
X471680Y460392D01*
G01X472055Y462450D02*
X469555D01*
X470055Y461950D01*
G01X472055D02*
Y462950D01*
G01X469555Y465550D02*
X469638Y465217D01*
X469847Y464967D01*
X470097Y464800D01*
X470430Y464675D01*
X470805Y464633D01*
X471180Y464675D01*
X471513Y464800D01*
X471763Y464967D01*
X471972Y465217D01*
X472055Y465550D01*
X471972Y465883D01*
X471763Y466133D01*
X471513Y466300D01*
X471180Y466425D01*
X470805Y466467D01*
X470430Y466425D01*
X470097Y466300D01*
X469847Y466133D01*
X469638Y465883D01*
X469555Y465550D01*
G01X472055Y468567D02*
X471513Y468650D01*
X471055Y468775D01*
X470638Y468942D01*
X470180Y469150D01*
X469555Y469483D01*
Y467817D01*
G01X469972Y470958D02*
X469722Y471208D01*
X469597Y471500D01*
X469555Y471833D01*
X469638Y472250D01*
X469847Y472542D01*
X470097Y472625D01*
X470347Y472583D01*
X470555Y472417D01*
X470972Y471583D01*
X471263Y471208D01*
X471680Y470958D01*
X472055Y470875D01*
Y472625D01*
G01X467722Y455375D02*
X467930Y455708D01*
X468055Y456083D01*
Y456417D01*
X467930Y456750D01*
X467722Y457000D01*
X467430Y457125D01*
X467138Y457042D01*
X466888Y456833D01*
X466722Y456458D01*
X466638Y455958D01*
X466472Y455667D01*
X466180Y455542D01*
X465888Y455625D01*
X465680Y455833D01*
X465555Y456125D01*
Y456417D01*
X465638Y456708D01*
X465847Y456958D01*
G01X465763Y460267D02*
X465638Y460017D01*
X465555Y459725D01*
Y459392D01*
X465680Y459017D01*
X465888Y458725D01*
X466138Y458517D01*
X466555Y458350D01*
X466930Y458308D01*
X467305Y458392D01*
X467555Y458517D01*
X467805Y458767D01*
X467972Y459058D01*
X468055Y459350D01*
Y459642D01*
X467972Y459933D01*
X467847Y460183D01*
X467680Y460392D01*
G01X468055Y462450D02*
X465555D01*
X466055Y461950D01*
G01X468055D02*
Y462950D01*
G01X465555Y465550D02*
X465638Y465217D01*
X465847Y464967D01*
X466097Y464800D01*
X466430Y464675D01*
X466805Y464633D01*
X467180Y464675D01*
X467513Y464800D01*
X467763Y464967D01*
X467972Y465217D01*
X468055Y465550D01*
X467972Y465883D01*
X467763Y466133D01*
X467513Y466300D01*
X467180Y466425D01*
X466805Y466467D01*
X466430Y466425D01*
X466097Y466300D01*
X465847Y466133D01*
X465638Y465883D01*
X465555Y465550D01*
G01X468055Y468567D02*
X467513Y468650D01*
X467055Y468775D01*
X466638Y468942D01*
X466180Y469150D01*
X465555Y469483D01*
Y467817D01*
G01X467555Y470833D02*
X467847Y471083D01*
X468013Y471417D01*
X468055Y471792D01*
X468013Y472125D01*
X467805Y472458D01*
X467555Y472667D01*
X467305Y472708D01*
X467013Y472625D01*
X466805Y472333D01*
X466722Y472042D01*
Y471667D01*
G01Y472042D02*
X466597Y472292D01*
X466388Y472500D01*
X466138Y472583D01*
X465888Y472500D01*
X465680Y472292D01*
X465555Y471917D01*
X465597Y471542D01*
X465763Y471167D01*
G01X476445Y787425D02*
X476653Y787758D01*
X476778Y788133D01*
Y788467D01*
X476653Y788800D01*
X476445Y789050D01*
X476153Y789175D01*
X475861Y789092D01*
X475611Y788883D01*
X475445Y788508D01*
X475361Y788008D01*
X475195Y787717D01*
X474903Y787592D01*
X474611Y787675D01*
X474403Y787883D01*
X474278Y788175D01*
Y788467D01*
X474361Y788758D01*
X474570Y789008D01*
G01X476778Y790567D02*
X474278D01*
Y791608D01*
X474403Y791942D01*
X474570Y792150D01*
X474903Y792233D01*
X475236Y792150D01*
X475445Y791900D01*
X475570Y791608D01*
Y790567D01*
G01Y791608D02*
X476778Y792233D01*
G01Y794500D02*
X476736Y794792D01*
X476611Y795125D01*
X476403Y795333D01*
X476111Y795417D01*
X475820Y795333D01*
X475570Y795083D01*
X475445Y794708D01*
Y794292D01*
X475361Y794042D01*
X475153Y793833D01*
X474861Y793750D01*
X474570Y793875D01*
X474361Y794167D01*
X474278Y794500D01*
X474361Y794833D01*
X474570Y795125D01*
X474861Y795250D01*
X475153Y795167D01*
X475361Y794958D01*
X475445Y794708D01*
Y794292D01*
X475570Y793917D01*
X475820Y793667D01*
X476111Y793583D01*
X476403Y793667D01*
X476611Y793875D01*
X476736Y794208D01*
X476778Y794500D01*
G01X475736Y796808D02*
X475445Y797100D01*
X475278Y797350D01*
X475195Y797683D01*
X475278Y797975D01*
X475445Y798183D01*
X475695Y798350D01*
X475986Y798392D01*
X476236Y798350D01*
X476486Y798183D01*
X476695Y797933D01*
X476778Y797642D01*
X476695Y797308D01*
X476445Y797017D01*
X476070Y796850D01*
X475653Y796808D01*
X475111Y796892D01*
X474820Y797017D01*
X474528Y797225D01*
X474320Y797517D01*
X474278Y797808D01*
X474361Y798100D01*
X474570Y798308D01*
G01X476778Y800700D02*
X476736Y800992D01*
X476611Y801325D01*
X476403Y801533D01*
X476111Y801617D01*
X475820Y801533D01*
X475570Y801283D01*
X475445Y800908D01*
Y800492D01*
X475361Y800242D01*
X475153Y800033D01*
X474861Y799950D01*
X474570Y800075D01*
X474361Y800367D01*
X474278Y800700D01*
X474361Y801033D01*
X474570Y801325D01*
X474861Y801450D01*
X475153Y801367D01*
X475361Y801158D01*
X475445Y800908D01*
Y800492D01*
X475570Y800117D01*
X475820Y799867D01*
X476111Y799783D01*
X476403Y799867D01*
X476611Y800075D01*
X476736Y800408D01*
X476778Y800700D01*
G01X469945Y787425D02*
X470153Y787758D01*
X470278Y788133D01*
Y788467D01*
X470153Y788800D01*
X469945Y789050D01*
X469653Y789175D01*
X469361Y789092D01*
X469111Y788883D01*
X468945Y788508D01*
X468861Y788008D01*
X468695Y787717D01*
X468403Y787592D01*
X468111Y787675D01*
X467903Y787883D01*
X467778Y788175D01*
Y788467D01*
X467861Y788758D01*
X468070Y789008D01*
G01X470278Y790567D02*
X467778D01*
Y791608D01*
X467903Y791942D01*
X468070Y792150D01*
X468403Y792233D01*
X468736Y792150D01*
X468945Y791900D01*
X469070Y791608D01*
Y790567D01*
G01Y791608D02*
X470278Y792233D01*
G01Y794500D02*
X470236Y794792D01*
X470111Y795125D01*
X469903Y795333D01*
X469611Y795417D01*
X469320Y795333D01*
X469070Y795083D01*
X468945Y794708D01*
Y794292D01*
X468861Y794042D01*
X468653Y793833D01*
X468361Y793750D01*
X468070Y793875D01*
X467861Y794167D01*
X467778Y794500D01*
X467861Y794833D01*
X468070Y795125D01*
X468361Y795250D01*
X468653Y795167D01*
X468861Y794958D01*
X468945Y794708D01*
Y794292D01*
X469070Y793917D01*
X469320Y793667D01*
X469611Y793583D01*
X469903Y793667D01*
X470111Y793875D01*
X470236Y794208D01*
X470278Y794500D01*
G01Y797517D02*
X469736Y797600D01*
X469278Y797725D01*
X468861Y797892D01*
X468403Y798100D01*
X467778Y798433D01*
Y796767D01*
G01X469778Y799783D02*
X470070Y800033D01*
X470236Y800367D01*
X470278Y800742D01*
X470236Y801075D01*
X470028Y801408D01*
X469778Y801617D01*
X469528Y801658D01*
X469236Y801575D01*
X469028Y801283D01*
X468945Y800992D01*
Y800617D01*
G01Y800992D02*
X468820Y801242D01*
X468611Y801450D01*
X468361Y801533D01*
X468111Y801450D01*
X467903Y801242D01*
X467778Y800867D01*
X467820Y800492D01*
X467986Y800117D01*
G01X477778Y810700D02*
X473778D01*
Y803300D01*
G01Y806800D02*
X477778D01*
Y814200D01*
G01X471278Y810700D02*
X467278D01*
Y803300D01*
G01Y806800D02*
X471278D01*
Y814200D01*
G01X475945Y815925D02*
X476153Y816258D01*
X476278Y816633D01*
Y816967D01*
X476153Y817300D01*
X475945Y817550D01*
X475653Y817675D01*
X475361Y817592D01*
X475111Y817383D01*
X474945Y817008D01*
X474861Y816508D01*
X474695Y816217D01*
X474403Y816092D01*
X474111Y816175D01*
X473903Y816383D01*
X473778Y816675D01*
Y816967D01*
X473861Y817258D01*
X474070Y817508D01*
G01X476278Y819067D02*
X473778D01*
Y820108D01*
X473903Y820442D01*
X474070Y820650D01*
X474403Y820733D01*
X474736Y820650D01*
X474945Y820400D01*
X475070Y820108D01*
Y819067D01*
G01Y820108D02*
X476278Y820733D01*
G01Y823000D02*
X476236Y823292D01*
X476111Y823625D01*
X475903Y823833D01*
X475611Y823917D01*
X475320Y823833D01*
X475070Y823583D01*
X474945Y823208D01*
Y822792D01*
X474861Y822542D01*
X474653Y822333D01*
X474361Y822250D01*
X474070Y822375D01*
X473861Y822667D01*
X473778Y823000D01*
X473861Y823333D01*
X474070Y823625D01*
X474361Y823750D01*
X474653Y823667D01*
X474861Y823458D01*
X474945Y823208D01*
Y822792D01*
X475070Y822417D01*
X475320Y822167D01*
X475611Y822083D01*
X475903Y822167D01*
X476111Y822375D01*
X476236Y822708D01*
X476278Y823000D01*
G01Y826017D02*
X475736Y826100D01*
X475278Y826225D01*
X474861Y826392D01*
X474403Y826600D01*
X473778Y826933D01*
Y825267D01*
G01X476278Y829200D02*
X473778D01*
X474278Y828700D01*
G01X476278D02*
Y829700D01*
G01X469445Y815925D02*
X469653Y816258D01*
X469778Y816633D01*
Y816967D01*
X469653Y817300D01*
X469445Y817550D01*
X469153Y817675D01*
X468861Y817592D01*
X468611Y817383D01*
X468445Y817008D01*
X468361Y816508D01*
X468195Y816217D01*
X467903Y816092D01*
X467611Y816175D01*
X467403Y816383D01*
X467278Y816675D01*
Y816967D01*
X467361Y817258D01*
X467570Y817508D01*
G01X469778Y819067D02*
X467278D01*
Y820108D01*
X467403Y820442D01*
X467570Y820650D01*
X467903Y820733D01*
X468236Y820650D01*
X468445Y820400D01*
X468570Y820108D01*
Y819067D01*
G01Y820108D02*
X469778Y820733D01*
G01Y823000D02*
X469736Y823292D01*
X469611Y823625D01*
X469403Y823833D01*
X469111Y823917D01*
X468820Y823833D01*
X468570Y823583D01*
X468445Y823208D01*
Y822792D01*
X468361Y822542D01*
X468153Y822333D01*
X467861Y822250D01*
X467570Y822375D01*
X467361Y822667D01*
X467278Y823000D01*
X467361Y823333D01*
X467570Y823625D01*
X467861Y823750D01*
X468153Y823667D01*
X468361Y823458D01*
X468445Y823208D01*
Y822792D01*
X468570Y822417D01*
X468820Y822167D01*
X469111Y822083D01*
X469403Y822167D01*
X469611Y822375D01*
X469736Y822708D01*
X469778Y823000D01*
G01Y826017D02*
X469236Y826100D01*
X468778Y826225D01*
X468361Y826392D01*
X467903Y826600D01*
X467278Y826933D01*
Y825267D01*
G01X469403Y828283D02*
X469611Y828533D01*
X469736Y828825D01*
X469778Y829200D01*
X469695Y829575D01*
X469528Y829867D01*
X469236Y830075D01*
X468903Y830117D01*
X468570Y830033D01*
X468361Y829825D01*
X468195Y829533D01*
X468153Y829242D01*
X468195Y828950D01*
X468361Y828575D01*
X467278Y828700D01*
Y829825D01*
G01X474445Y853925D02*
X474653Y854258D01*
X474778Y854633D01*
Y854967D01*
X474653Y855300D01*
X474445Y855550D01*
X474153Y855675D01*
X473861Y855592D01*
X473611Y855383D01*
X473445Y855008D01*
X473361Y854508D01*
X473195Y854217D01*
X472903Y854092D01*
X472611Y854175D01*
X472403Y854383D01*
X472278Y854675D01*
Y854967D01*
X472361Y855258D01*
X472570Y855508D01*
G01X474778Y857067D02*
X472278D01*
Y858108D01*
X472403Y858442D01*
X472570Y858650D01*
X472903Y858733D01*
X473236Y858650D01*
X473445Y858400D01*
X473570Y858108D01*
Y857067D01*
G01Y858108D02*
X474778Y858733D01*
G01Y861000D02*
X474736Y861292D01*
X474611Y861625D01*
X474403Y861833D01*
X474111Y861917D01*
X473820Y861833D01*
X473570Y861583D01*
X473445Y861208D01*
Y860792D01*
X473361Y860542D01*
X473153Y860333D01*
X472861Y860250D01*
X472570Y860375D01*
X472361Y860667D01*
X472278Y861000D01*
X472361Y861333D01*
X472570Y861625D01*
X472861Y861750D01*
X473153Y861667D01*
X473361Y861458D01*
X473445Y861208D01*
Y860792D01*
X473570Y860417D01*
X473820Y860167D01*
X474111Y860083D01*
X474403Y860167D01*
X474611Y860375D01*
X474736Y860708D01*
X474778Y861000D01*
G01Y864017D02*
X474236Y864100D01*
X473778Y864225D01*
X473361Y864392D01*
X472903Y864600D01*
X472278Y864933D01*
Y863267D01*
G01X473736Y866408D02*
X473445Y866700D01*
X473278Y866950D01*
X473195Y867283D01*
X473278Y867575D01*
X473445Y867783D01*
X473695Y867950D01*
X473986Y867992D01*
X474236Y867950D01*
X474486Y867783D01*
X474695Y867533D01*
X474778Y867242D01*
X474695Y866908D01*
X474445Y866617D01*
X474070Y866450D01*
X473653Y866408D01*
X473111Y866492D01*
X472820Y866617D01*
X472528Y866825D01*
X472320Y867117D01*
X472278Y867408D01*
X472361Y867700D01*
X472570Y867908D01*
G01X475778Y881200D02*
X471778D01*
Y873800D01*
G01Y870300D02*
X475778D01*
Y877700D01*
G01X474445Y883425D02*
X474653Y883758D01*
X474778Y884133D01*
Y884467D01*
X474653Y884800D01*
X474445Y885050D01*
X474153Y885175D01*
X473861Y885092D01*
X473611Y884883D01*
X473445Y884508D01*
X473361Y884008D01*
X473195Y883717D01*
X472903Y883592D01*
X472611Y883675D01*
X472403Y883883D01*
X472278Y884175D01*
Y884467D01*
X472361Y884758D01*
X472570Y885008D01*
G01X474778Y886567D02*
X472278D01*
Y887608D01*
X472403Y887942D01*
X472570Y888150D01*
X472903Y888233D01*
X473236Y888150D01*
X473445Y887900D01*
X473570Y887608D01*
Y886567D01*
G01Y887608D02*
X474778Y888233D01*
G01Y890500D02*
X474736Y890792D01*
X474611Y891125D01*
X474403Y891333D01*
X474111Y891417D01*
X473820Y891333D01*
X473570Y891083D01*
X473445Y890708D01*
Y890292D01*
X473361Y890042D01*
X473153Y889833D01*
X472861Y889750D01*
X472570Y889875D01*
X472361Y890167D01*
X472278Y890500D01*
X472361Y890833D01*
X472570Y891125D01*
X472861Y891250D01*
X473153Y891167D01*
X473361Y890958D01*
X473445Y890708D01*
Y890292D01*
X473570Y889917D01*
X473820Y889667D01*
X474111Y889583D01*
X474403Y889667D01*
X474611Y889875D01*
X474736Y890208D01*
X474778Y890500D01*
G01Y893517D02*
X474236Y893600D01*
X473778Y893725D01*
X473361Y893892D01*
X472903Y894100D01*
X472278Y894433D01*
Y892767D01*
G01X474778Y897200D02*
X472278D01*
X474070Y895658D01*
Y897742D01*
G01X483667Y92925D02*
X483875Y93258D01*
X484000Y93633D01*
Y93967D01*
X483875Y94300D01*
X483667Y94550D01*
X483375Y94675D01*
X483083Y94592D01*
X482833Y94383D01*
X482667Y94008D01*
X482583Y93508D01*
X482417Y93217D01*
X482125Y93092D01*
X481833Y93175D01*
X481625Y93383D01*
X481500Y93675D01*
Y93967D01*
X481583Y94258D01*
X481792Y94508D01*
G01X484000Y96067D02*
X481500D01*
Y97108D01*
X481625Y97442D01*
X481792Y97650D01*
X482125Y97733D01*
X482458Y97650D01*
X482667Y97400D01*
X482792Y97108D01*
Y96067D01*
G01Y97108D02*
X484000Y97733D01*
G01X482958Y99208D02*
X482667Y99500D01*
X482500Y99750D01*
X482417Y100083D01*
X482500Y100375D01*
X482667Y100583D01*
X482917Y100750D01*
X483208Y100792D01*
X483458Y100750D01*
X483708Y100583D01*
X483917Y100333D01*
X484000Y100042D01*
X483917Y99708D01*
X483667Y99417D01*
X483292Y99250D01*
X482875Y99208D01*
X482333Y99292D01*
X482042Y99417D01*
X481750Y99625D01*
X481542Y99917D01*
X481500Y100208D01*
X481583Y100500D01*
X481792Y100708D01*
G01X482958Y102308D02*
X482667Y102600D01*
X482500Y102850D01*
X482417Y103183D01*
X482500Y103475D01*
X482667Y103683D01*
X482917Y103850D01*
X483208Y103892D01*
X483458Y103850D01*
X483708Y103683D01*
X483917Y103433D01*
X484000Y103142D01*
X483917Y102808D01*
X483667Y102517D01*
X483292Y102350D01*
X482875Y102308D01*
X482333Y102392D01*
X482042Y102517D01*
X481750Y102725D01*
X481542Y103017D01*
X481500Y103308D01*
X481583Y103600D01*
X481792Y103808D01*
G01X483500Y105283D02*
X483792Y105533D01*
X483958Y105867D01*
X484000Y106242D01*
X483958Y106575D01*
X483750Y106908D01*
X483500Y107117D01*
X483250Y107158D01*
X482958Y107075D01*
X482750Y106783D01*
X482667Y106492D01*
Y106117D01*
G01Y106492D02*
X482542Y106742D01*
X482333Y106950D01*
X482083Y107033D01*
X481833Y106950D01*
X481625Y106742D01*
X481500Y106367D01*
X481542Y105992D01*
X481708Y105617D01*
G01X488167Y92925D02*
X488375Y93258D01*
X488500Y93633D01*
Y93967D01*
X488375Y94300D01*
X488167Y94550D01*
X487875Y94675D01*
X487583Y94592D01*
X487333Y94383D01*
X487167Y94008D01*
X487083Y93508D01*
X486917Y93217D01*
X486625Y93092D01*
X486333Y93175D01*
X486125Y93383D01*
X486000Y93675D01*
Y93967D01*
X486083Y94258D01*
X486292Y94508D01*
G01X488500Y96067D02*
X486000D01*
Y97108D01*
X486125Y97442D01*
X486292Y97650D01*
X486625Y97733D01*
X486958Y97650D01*
X487167Y97400D01*
X487292Y97108D01*
Y96067D01*
G01Y97108D02*
X488500Y97733D01*
G01X487458Y99208D02*
X487167Y99500D01*
X487000Y99750D01*
X486917Y100083D01*
X487000Y100375D01*
X487167Y100583D01*
X487417Y100750D01*
X487708Y100792D01*
X487958Y100750D01*
X488208Y100583D01*
X488417Y100333D01*
X488500Y100042D01*
X488417Y99708D01*
X488167Y99417D01*
X487792Y99250D01*
X487375Y99208D01*
X486833Y99292D01*
X486542Y99417D01*
X486250Y99625D01*
X486042Y99917D01*
X486000Y100208D01*
X486083Y100500D01*
X486292Y100708D01*
G01X488500Y103017D02*
X487958Y103100D01*
X487500Y103225D01*
X487083Y103392D01*
X486625Y103600D01*
X486000Y103933D01*
Y102267D01*
G01X488500Y106200D02*
X486000D01*
X486500Y105700D01*
G01X488500D02*
Y106700D01*
G01X481375Y121833D02*
X481708Y121625D01*
X482083Y121500D01*
X482417D01*
X482750Y121625D01*
X483000Y121833D01*
X483125Y122125D01*
X483042Y122417D01*
X482833Y122667D01*
X482458Y122833D01*
X481958Y122917D01*
X481667Y123083D01*
X481542Y123375D01*
X481625Y123667D01*
X481833Y123875D01*
X482125Y124000D01*
X482417D01*
X482708Y123917D01*
X482958Y123708D01*
G01X485350Y124000D02*
Y121500D01*
G01X484392Y124000D02*
X486308D01*
G01X487617Y121500D02*
Y124000D01*
X488617D01*
X488950Y123875D01*
X489200Y123583D01*
X489283Y123250D01*
X489200Y122917D01*
X488992Y122667D01*
X488617Y122542D01*
X487617D01*
G01X491550Y121500D02*
Y124000D01*
X491050Y123500D01*
G01Y121500D02*
X492050D01*
G01X493733Y122000D02*
X493983Y121708D01*
X494317Y121542D01*
X494692Y121500D01*
X495025Y121542D01*
X495358Y121750D01*
X495567Y122000D01*
X495608Y122250D01*
X495525Y122542D01*
X495233Y122750D01*
X494942Y122833D01*
X494567D01*
G01X494942D02*
X495192Y122958D01*
X495400Y123167D01*
X495483Y123417D01*
X495400Y123667D01*
X495192Y123875D01*
X494817Y124000D01*
X494442Y123958D01*
X494067Y123792D01*
G01X497750Y121500D02*
Y124000D01*
X497250Y123500D01*
G01Y121500D02*
X498250D01*
G01X489525Y135233D02*
X489858Y135025D01*
X490233Y134900D01*
X490567D01*
X490900Y135025D01*
X491150Y135233D01*
X491275Y135525D01*
X491192Y135817D01*
X490983Y136067D01*
X490608Y136233D01*
X490108Y136317D01*
X489817Y136483D01*
X489692Y136775D01*
X489775Y137067D01*
X489983Y137275D01*
X490275Y137400D01*
X490567D01*
X490858Y137317D01*
X491108Y137108D01*
G01X493500Y137400D02*
Y134900D01*
G01X492542Y137400D02*
X494458D01*
G01X495767Y134900D02*
Y137400D01*
X496767D01*
X497100Y137275D01*
X497350Y136983D01*
X497433Y136650D01*
X497350Y136317D01*
X497142Y136067D01*
X496767Y135942D01*
X495767D01*
G01X499700Y134900D02*
Y137400D01*
X499200Y136900D01*
G01Y134900D02*
X500200D01*
G01X501883Y135400D02*
X502133Y135108D01*
X502467Y134942D01*
X502842Y134900D01*
X503175Y134942D01*
X503508Y135150D01*
X503717Y135400D01*
X503758Y135650D01*
X503675Y135942D01*
X503383Y136150D01*
X503092Y136233D01*
X502717D01*
G01X503092D02*
X503342Y136358D01*
X503550Y136567D01*
X503633Y136817D01*
X503550Y137067D01*
X503342Y137275D01*
X502967Y137400D01*
X502592Y137358D01*
X502217Y137192D01*
G01X493925Y129833D02*
X494258Y129625D01*
X494633Y129500D01*
X494967D01*
X495300Y129625D01*
X495550Y129833D01*
X495675Y130125D01*
X495592Y130417D01*
X495383Y130667D01*
X495008Y130833D01*
X494508Y130917D01*
X494217Y131083D01*
X494092Y131375D01*
X494175Y131667D01*
X494383Y131875D01*
X494675Y132000D01*
X494967D01*
X495258Y131917D01*
X495508Y131708D01*
G01X497900Y132000D02*
Y129500D01*
G01X496942Y132000D02*
X498858D01*
G01X500167Y129500D02*
Y132000D01*
X501167D01*
X501500Y131875D01*
X501750Y131583D01*
X501833Y131250D01*
X501750Y130917D01*
X501542Y130667D01*
X501167Y130542D01*
X500167D01*
G01X504600Y129500D02*
Y132000D01*
X503058Y130208D01*
X505142D01*
G01X506283Y129875D02*
X506533Y129667D01*
X506825Y129542D01*
X507200Y129500D01*
X507575Y129583D01*
X507867Y129750D01*
X508075Y130042D01*
X508117Y130375D01*
X508033Y130708D01*
X507825Y130917D01*
X507533Y131083D01*
X507242Y131125D01*
X506950Y131083D01*
X506575Y130917D01*
X506700Y132000D01*
X507825D01*
G01X485096Y217925D02*
X485304Y218258D01*
X485429Y218633D01*
Y218967D01*
X485304Y219300D01*
X485096Y219550D01*
X484804Y219675D01*
X484512Y219592D01*
X484262Y219383D01*
X484096Y219008D01*
X484012Y218508D01*
X483846Y218217D01*
X483554Y218092D01*
X483262Y218175D01*
X483054Y218383D01*
X482929Y218675D01*
Y218967D01*
X483012Y219258D01*
X483221Y219508D01*
G01X482929Y221900D02*
X485429D01*
G01X482929Y220942D02*
Y222858D01*
G01X485429Y224167D02*
X482929D01*
Y225167D01*
X483054Y225500D01*
X483346Y225750D01*
X483679Y225833D01*
X484012Y225750D01*
X484262Y225542D01*
X484387Y225167D01*
Y224167D01*
G01X484929Y227183D02*
X485221Y227433D01*
X485387Y227767D01*
X485429Y228142D01*
X485387Y228475D01*
X485179Y228808D01*
X484929Y229017D01*
X484679Y229058D01*
X484387Y228975D01*
X484179Y228683D01*
X484096Y228392D01*
Y228017D01*
G01Y228392D02*
X483971Y228642D01*
X483762Y228850D01*
X483512Y228933D01*
X483262Y228850D01*
X483054Y228642D01*
X482929Y228267D01*
X482971Y227892D01*
X483137Y227517D01*
G01X483346Y230408D02*
X483096Y230658D01*
X482971Y230950D01*
X482929Y231283D01*
X483012Y231700D01*
X483221Y231992D01*
X483471Y232075D01*
X483721Y232033D01*
X483929Y231867D01*
X484346Y231033D01*
X484637Y230658D01*
X485054Y230408D01*
X485429Y230325D01*
Y232075D01*
G01X493596Y217925D02*
X493804Y218258D01*
X493929Y218633D01*
Y218967D01*
X493804Y219300D01*
X493596Y219550D01*
X493304Y219675D01*
X493012Y219592D01*
X492762Y219383D01*
X492596Y219008D01*
X492512Y218508D01*
X492346Y218217D01*
X492054Y218092D01*
X491762Y218175D01*
X491554Y218383D01*
X491429Y218675D01*
Y218967D01*
X491512Y219258D01*
X491721Y219508D01*
G01X491429Y221900D02*
X493929D01*
G01X491429Y220942D02*
Y222858D01*
G01X493929Y224167D02*
X491429D01*
Y225167D01*
X491554Y225500D01*
X491846Y225750D01*
X492179Y225833D01*
X492512Y225750D01*
X492762Y225542D01*
X492887Y225167D01*
Y224167D01*
G01X493429Y227183D02*
X493721Y227433D01*
X493887Y227767D01*
X493929Y228142D01*
X493887Y228475D01*
X493679Y228808D01*
X493429Y229017D01*
X493179Y229058D01*
X492887Y228975D01*
X492679Y228683D01*
X492596Y228392D01*
Y228017D01*
G01Y228392D02*
X492471Y228642D01*
X492262Y228850D01*
X492012Y228933D01*
X491762Y228850D01*
X491554Y228642D01*
X491429Y228267D01*
X491471Y227892D01*
X491637Y227517D01*
G01X493429Y230283D02*
X493721Y230533D01*
X493887Y230867D01*
X493929Y231242D01*
X493887Y231575D01*
X493679Y231908D01*
X493429Y232117D01*
X493179Y232158D01*
X492887Y232075D01*
X492679Y231783D01*
X492596Y231492D01*
Y231117D01*
G01Y231492D02*
X492471Y231742D01*
X492262Y231950D01*
X492012Y232033D01*
X491762Y231950D01*
X491554Y231742D01*
X491429Y231367D01*
X491471Y230992D01*
X491637Y230617D01*
G01X489596Y215425D02*
X489804Y215758D01*
X489929Y216133D01*
Y216467D01*
X489804Y216800D01*
X489596Y217050D01*
X489304Y217175D01*
X489012Y217092D01*
X488762Y216883D01*
X488596Y216508D01*
X488512Y216008D01*
X488346Y215717D01*
X488054Y215592D01*
X487762Y215675D01*
X487554Y215883D01*
X487429Y216175D01*
Y216467D01*
X487512Y216758D01*
X487721Y217008D01*
G01X487429Y219400D02*
X489929D01*
G01X487429Y218442D02*
Y220358D01*
G01X489929Y221667D02*
X487429D01*
Y222667D01*
X487554Y223000D01*
X487846Y223250D01*
X488179Y223333D01*
X488512Y223250D01*
X488762Y223042D01*
X488887Y222667D01*
Y221667D01*
G01X489429Y224683D02*
X489721Y224933D01*
X489887Y225267D01*
X489929Y225642D01*
X489887Y225975D01*
X489679Y226308D01*
X489429Y226517D01*
X489179Y226558D01*
X488887Y226475D01*
X488679Y226183D01*
X488596Y225892D01*
Y225517D01*
G01Y225892D02*
X488471Y226142D01*
X488262Y226350D01*
X488012Y226433D01*
X487762Y226350D01*
X487554Y226142D01*
X487429Y225767D01*
X487471Y225392D01*
X487637Y225017D01*
G01X489929Y229200D02*
X487429D01*
X489221Y227658D01*
Y229742D01*
G01X480596Y215425D02*
X480804Y215758D01*
X480929Y216133D01*
Y216467D01*
X480804Y216800D01*
X480596Y217050D01*
X480304Y217175D01*
X480012Y217092D01*
X479762Y216883D01*
X479596Y216508D01*
X479512Y216008D01*
X479346Y215717D01*
X479054Y215592D01*
X478762Y215675D01*
X478554Y215883D01*
X478429Y216175D01*
Y216467D01*
X478512Y216758D01*
X478721Y217008D01*
G01X478429Y219400D02*
X480929D01*
G01X478429Y218442D02*
Y220358D01*
G01X480929Y221667D02*
X478429D01*
Y222667D01*
X478554Y223000D01*
X478846Y223250D01*
X479179Y223333D01*
X479512Y223250D01*
X479762Y223042D01*
X479887Y222667D01*
Y221667D01*
G01X480429Y224683D02*
X480721Y224933D01*
X480887Y225267D01*
X480929Y225642D01*
X480887Y225975D01*
X480679Y226308D01*
X480429Y226517D01*
X480179Y226558D01*
X479887Y226475D01*
X479679Y226183D01*
X479596Y225892D01*
Y225517D01*
G01Y225892D02*
X479471Y226142D01*
X479262Y226350D01*
X479012Y226433D01*
X478762Y226350D01*
X478554Y226142D01*
X478429Y225767D01*
X478471Y225392D01*
X478637Y225017D01*
G01X480554Y227783D02*
X480762Y228033D01*
X480887Y228325D01*
X480929Y228700D01*
X480846Y229075D01*
X480679Y229367D01*
X480387Y229575D01*
X480054Y229617D01*
X479721Y229533D01*
X479512Y229325D01*
X479346Y229033D01*
X479304Y228742D01*
X479346Y228450D01*
X479512Y228075D01*
X478429Y228200D01*
Y229325D01*
G01X497322Y320275D02*
G03I-1850J0D01*
G01X481525Y312833D02*
X481858Y312625D01*
X482233Y312500D01*
X482567D01*
X482900Y312625D01*
X483150Y312833D01*
X483275Y313125D01*
X483192Y313417D01*
X482983Y313667D01*
X482608Y313833D01*
X482108Y313917D01*
X481817Y314083D01*
X481692Y314375D01*
X481775Y314667D01*
X481983Y314875D01*
X482275Y315000D01*
X482567D01*
X482858Y314917D01*
X483108Y314708D01*
G01X484625Y312500D02*
X486375Y315000D01*
G01X484625D02*
X486375Y312500D01*
G01X487808Y314583D02*
X488058Y314833D01*
X488350Y314958D01*
X488683Y315000D01*
X489100Y314917D01*
X489392Y314708D01*
X489475Y314458D01*
X489433Y314208D01*
X489267Y314000D01*
X488433Y313583D01*
X488058Y313292D01*
X487808Y312875D01*
X487725Y312500D01*
X489475D01*
G01X497322Y426575D02*
G03I-1850J0D01*
G01X487722Y455375D02*
X487930Y455708D01*
X488055Y456083D01*
Y456417D01*
X487930Y456750D01*
X487722Y457000D01*
X487430Y457125D01*
X487138Y457042D01*
X486888Y456833D01*
X486722Y456458D01*
X486638Y455958D01*
X486472Y455667D01*
X486180Y455542D01*
X485888Y455625D01*
X485680Y455833D01*
X485555Y456125D01*
Y456417D01*
X485638Y456708D01*
X485847Y456958D01*
G01X485763Y460267D02*
X485638Y460017D01*
X485555Y459725D01*
Y459392D01*
X485680Y459017D01*
X485888Y458725D01*
X486138Y458517D01*
X486555Y458350D01*
X486930Y458308D01*
X487305Y458392D01*
X487555Y458517D01*
X487805Y458767D01*
X487972Y459058D01*
X488055Y459350D01*
Y459642D01*
X487972Y459933D01*
X487847Y460183D01*
X487680Y460392D01*
G01X488055Y462450D02*
X485555D01*
X486055Y461950D01*
G01X488055D02*
Y462950D01*
G01X485555Y465550D02*
X485638Y465217D01*
X485847Y464967D01*
X486097Y464800D01*
X486430Y464675D01*
X486805Y464633D01*
X487180Y464675D01*
X487513Y464800D01*
X487763Y464967D01*
X487972Y465217D01*
X488055Y465550D01*
X487972Y465883D01*
X487763Y466133D01*
X487513Y466300D01*
X487180Y466425D01*
X486805Y466467D01*
X486430Y466425D01*
X486097Y466300D01*
X485847Y466133D01*
X485638Y465883D01*
X485555Y465550D01*
G01X487013Y467858D02*
X486722Y468150D01*
X486555Y468400D01*
X486472Y468733D01*
X486555Y469025D01*
X486722Y469233D01*
X486972Y469400D01*
X487263Y469442D01*
X487513Y469400D01*
X487763Y469233D01*
X487972Y468983D01*
X488055Y468692D01*
X487972Y468358D01*
X487722Y468067D01*
X487347Y467900D01*
X486930Y467858D01*
X486388Y467942D01*
X486097Y468067D01*
X485805Y468275D01*
X485597Y468567D01*
X485555Y468858D01*
X485638Y469150D01*
X485847Y469358D01*
G01X488055Y471667D02*
X487513Y471750D01*
X487055Y471875D01*
X486638Y472042D01*
X486180Y472250D01*
X485555Y472583D01*
Y470917D01*
G01X491722Y455375D02*
X491930Y455708D01*
X492055Y456083D01*
Y456417D01*
X491930Y456750D01*
X491722Y457000D01*
X491430Y457125D01*
X491138Y457042D01*
X490888Y456833D01*
X490722Y456458D01*
X490638Y455958D01*
X490472Y455667D01*
X490180Y455542D01*
X489888Y455625D01*
X489680Y455833D01*
X489555Y456125D01*
Y456417D01*
X489638Y456708D01*
X489847Y456958D01*
G01X489763Y460267D02*
X489638Y460017D01*
X489555Y459725D01*
Y459392D01*
X489680Y459017D01*
X489888Y458725D01*
X490138Y458517D01*
X490555Y458350D01*
X490930Y458308D01*
X491305Y458392D01*
X491555Y458517D01*
X491805Y458767D01*
X491972Y459058D01*
X492055Y459350D01*
Y459642D01*
X491972Y459933D01*
X491847Y460183D01*
X491680Y460392D01*
G01X492055Y462450D02*
X489555D01*
X490055Y461950D01*
G01X492055D02*
Y462950D01*
G01X489555Y465550D02*
X489638Y465217D01*
X489847Y464967D01*
X490097Y464800D01*
X490430Y464675D01*
X490805Y464633D01*
X491180Y464675D01*
X491513Y464800D01*
X491763Y464967D01*
X491972Y465217D01*
X492055Y465550D01*
X491972Y465883D01*
X491763Y466133D01*
X491513Y466300D01*
X491180Y466425D01*
X490805Y466467D01*
X490430Y466425D01*
X490097Y466300D01*
X489847Y466133D01*
X489638Y465883D01*
X489555Y465550D01*
G01X491013Y467858D02*
X490722Y468150D01*
X490555Y468400D01*
X490472Y468733D01*
X490555Y469025D01*
X490722Y469233D01*
X490972Y469400D01*
X491263Y469442D01*
X491513Y469400D01*
X491763Y469233D01*
X491972Y468983D01*
X492055Y468692D01*
X491972Y468358D01*
X491722Y468067D01*
X491347Y467900D01*
X490930Y467858D01*
X490388Y467942D01*
X490097Y468067D01*
X489805Y468275D01*
X489597Y468567D01*
X489555Y468858D01*
X489638Y469150D01*
X489847Y469358D01*
G01X492055Y471750D02*
X492013Y472042D01*
X491888Y472375D01*
X491680Y472583D01*
X491388Y472667D01*
X491097Y472583D01*
X490847Y472333D01*
X490722Y471958D01*
Y471542D01*
X490638Y471292D01*
X490430Y471083D01*
X490138Y471000D01*
X489847Y471125D01*
X489638Y471417D01*
X489555Y471750D01*
X489638Y472083D01*
X489847Y472375D01*
X490138Y472500D01*
X490430Y472417D01*
X490638Y472208D01*
X490722Y471958D01*
Y471542D01*
X490847Y471167D01*
X491097Y470917D01*
X491388Y470833D01*
X491680Y470917D01*
X491888Y471125D01*
X492013Y471458D01*
X492055Y471750D01*
G01X483722Y455375D02*
X483930Y455708D01*
X484055Y456083D01*
Y456417D01*
X483930Y456750D01*
X483722Y457000D01*
X483430Y457125D01*
X483138Y457042D01*
X482888Y456833D01*
X482722Y456458D01*
X482638Y455958D01*
X482472Y455667D01*
X482180Y455542D01*
X481888Y455625D01*
X481680Y455833D01*
X481555Y456125D01*
Y456417D01*
X481638Y456708D01*
X481847Y456958D01*
G01X481763Y460267D02*
X481638Y460017D01*
X481555Y459725D01*
Y459392D01*
X481680Y459017D01*
X481888Y458725D01*
X482138Y458517D01*
X482555Y458350D01*
X482930Y458308D01*
X483305Y458392D01*
X483555Y458517D01*
X483805Y458767D01*
X483972Y459058D01*
X484055Y459350D01*
Y459642D01*
X483972Y459933D01*
X483847Y460183D01*
X483680Y460392D01*
G01X484055Y462450D02*
X481555D01*
X482055Y461950D01*
G01X484055D02*
Y462950D01*
G01X481555Y465550D02*
X481638Y465217D01*
X481847Y464967D01*
X482097Y464800D01*
X482430Y464675D01*
X482805Y464633D01*
X483180Y464675D01*
X483513Y464800D01*
X483763Y464967D01*
X483972Y465217D01*
X484055Y465550D01*
X483972Y465883D01*
X483763Y466133D01*
X483513Y466300D01*
X483180Y466425D01*
X482805Y466467D01*
X482430Y466425D01*
X482097Y466300D01*
X481847Y466133D01*
X481638Y465883D01*
X481555Y465550D01*
G01X483013Y467858D02*
X482722Y468150D01*
X482555Y468400D01*
X482472Y468733D01*
X482555Y469025D01*
X482722Y469233D01*
X482972Y469400D01*
X483263Y469442D01*
X483513Y469400D01*
X483763Y469233D01*
X483972Y468983D01*
X484055Y468692D01*
X483972Y468358D01*
X483722Y468067D01*
X483347Y467900D01*
X482930Y467858D01*
X482388Y467942D01*
X482097Y468067D01*
X481805Y468275D01*
X481597Y468567D01*
X481555Y468858D01*
X481638Y469150D01*
X481847Y469358D01*
G01X483763Y471042D02*
X483972Y471333D01*
X484055Y471667D01*
X483972Y472000D01*
X483722Y472292D01*
X483347Y472500D01*
X482972Y472583D01*
X482513D01*
X482138Y472500D01*
X481805Y472292D01*
X481638Y472042D01*
X481555Y471750D01*
X481638Y471417D01*
X481805Y471167D01*
X482055Y471000D01*
X482388Y470917D01*
X482680Y471000D01*
X482972Y471208D01*
X483138Y471458D01*
X483180Y471750D01*
X483097Y472083D01*
X482888Y472333D01*
X482513Y472583D01*
G01X480945Y853925D02*
X481153Y854258D01*
X481278Y854633D01*
Y854967D01*
X481153Y855300D01*
X480945Y855550D01*
X480653Y855675D01*
X480361Y855592D01*
X480111Y855383D01*
X479945Y855008D01*
X479861Y854508D01*
X479695Y854217D01*
X479403Y854092D01*
X479111Y854175D01*
X478903Y854383D01*
X478778Y854675D01*
Y854967D01*
X478861Y855258D01*
X479070Y855508D01*
G01X481278Y857067D02*
X478778D01*
Y858108D01*
X478903Y858442D01*
X479070Y858650D01*
X479403Y858733D01*
X479736Y858650D01*
X479945Y858400D01*
X480070Y858108D01*
Y857067D01*
G01Y858108D02*
X481278Y858733D01*
G01Y861000D02*
X481236Y861292D01*
X481111Y861625D01*
X480903Y861833D01*
X480611Y861917D01*
X480320Y861833D01*
X480070Y861583D01*
X479945Y861208D01*
Y860792D01*
X479861Y860542D01*
X479653Y860333D01*
X479361Y860250D01*
X479070Y860375D01*
X478861Y860667D01*
X478778Y861000D01*
X478861Y861333D01*
X479070Y861625D01*
X479361Y861750D01*
X479653Y861667D01*
X479861Y861458D01*
X479945Y861208D01*
Y860792D01*
X480070Y860417D01*
X480320Y860167D01*
X480611Y860083D01*
X480903Y860167D01*
X481111Y860375D01*
X481236Y860708D01*
X481278Y861000D01*
G01Y864017D02*
X480736Y864100D01*
X480278Y864225D01*
X479861Y864392D01*
X479403Y864600D01*
X478778Y864933D01*
Y863267D01*
G01X479195Y866408D02*
X478945Y866658D01*
X478820Y866950D01*
X478778Y867283D01*
X478861Y867700D01*
X479070Y867992D01*
X479320Y868075D01*
X479570Y868033D01*
X479778Y867867D01*
X480195Y867033D01*
X480486Y866658D01*
X480903Y866408D01*
X481278Y866325D01*
Y868075D01*
G01X482278Y881200D02*
X478278D01*
Y873800D01*
G01Y870300D02*
X482278D01*
Y877700D01*
G01X480945Y883425D02*
X481153Y883758D01*
X481278Y884133D01*
Y884467D01*
X481153Y884800D01*
X480945Y885050D01*
X480653Y885175D01*
X480361Y885092D01*
X480111Y884883D01*
X479945Y884508D01*
X479861Y884008D01*
X479695Y883717D01*
X479403Y883592D01*
X479111Y883675D01*
X478903Y883883D01*
X478778Y884175D01*
Y884467D01*
X478861Y884758D01*
X479070Y885008D01*
G01X481278Y886567D02*
X478778D01*
Y887608D01*
X478903Y887942D01*
X479070Y888150D01*
X479403Y888233D01*
X479736Y888150D01*
X479945Y887900D01*
X480070Y887608D01*
Y886567D01*
G01Y887608D02*
X481278Y888233D01*
G01Y890500D02*
X481236Y890792D01*
X481111Y891125D01*
X480903Y891333D01*
X480611Y891417D01*
X480320Y891333D01*
X480070Y891083D01*
X479945Y890708D01*
Y890292D01*
X479861Y890042D01*
X479653Y889833D01*
X479361Y889750D01*
X479070Y889875D01*
X478861Y890167D01*
X478778Y890500D01*
X478861Y890833D01*
X479070Y891125D01*
X479361Y891250D01*
X479653Y891167D01*
X479861Y890958D01*
X479945Y890708D01*
Y890292D01*
X480070Y889917D01*
X480320Y889667D01*
X480611Y889583D01*
X480903Y889667D01*
X481111Y889875D01*
X481236Y890208D01*
X481278Y890500D01*
G01X480236Y892808D02*
X479945Y893100D01*
X479778Y893350D01*
X479695Y893683D01*
X479778Y893975D01*
X479945Y894183D01*
X480195Y894350D01*
X480486Y894392D01*
X480736Y894350D01*
X480986Y894183D01*
X481195Y893933D01*
X481278Y893642D01*
X481195Y893308D01*
X480945Y893017D01*
X480570Y892850D01*
X480153Y892808D01*
X479611Y892892D01*
X479320Y893017D01*
X479028Y893225D01*
X478820Y893517D01*
X478778Y893808D01*
X478861Y894100D01*
X479070Y894308D01*
G01X480986Y895992D02*
X481195Y896283D01*
X481278Y896617D01*
X481195Y896950D01*
X480945Y897242D01*
X480570Y897450D01*
X480195Y897533D01*
X479736D01*
X479361Y897450D01*
X479028Y897242D01*
X478861Y896992D01*
X478778Y896700D01*
X478861Y896367D01*
X479028Y896117D01*
X479278Y895950D01*
X479611Y895867D01*
X479903Y895950D01*
X480195Y896158D01*
X480361Y896408D01*
X480403Y896700D01*
X480320Y897033D01*
X480111Y897283D01*
X479736Y897533D01*
G01X499096Y211925D02*
X499304Y212258D01*
X499429Y212633D01*
Y212967D01*
X499304Y213300D01*
X499096Y213550D01*
X498804Y213675D01*
X498512Y213592D01*
X498262Y213383D01*
X498096Y213008D01*
X498012Y212508D01*
X497846Y212217D01*
X497554Y212092D01*
X497262Y212175D01*
X497054Y212383D01*
X496929Y212675D01*
Y212967D01*
X497012Y213258D01*
X497221Y213508D01*
G01X496929Y215900D02*
X499429D01*
G01X496929Y214942D02*
Y216858D01*
G01X499429Y218167D02*
X496929D01*
Y219167D01*
X497054Y219500D01*
X497346Y219750D01*
X497679Y219833D01*
X498012Y219750D01*
X498262Y219542D01*
X498387Y219167D01*
Y218167D01*
G01X498929Y221183D02*
X499221Y221433D01*
X499387Y221767D01*
X499429Y222142D01*
X499387Y222475D01*
X499179Y222808D01*
X498929Y223017D01*
X498679Y223058D01*
X498387Y222975D01*
X498179Y222683D01*
X498096Y222392D01*
Y222017D01*
G01Y222392D02*
X497971Y222642D01*
X497762Y222850D01*
X497512Y222933D01*
X497262Y222850D01*
X497054Y222642D01*
X496929Y222267D01*
X496971Y221892D01*
X497137Y221517D01*
G01X496929Y225200D02*
X497012Y224867D01*
X497221Y224617D01*
X497471Y224450D01*
X497804Y224325D01*
X498179Y224283D01*
X498554Y224325D01*
X498887Y224450D01*
X499137Y224617D01*
X499346Y224867D01*
X499429Y225200D01*
X499346Y225533D01*
X499137Y225783D01*
X498887Y225950D01*
X498554Y226075D01*
X498179Y226117D01*
X497804Y226075D01*
X497471Y225950D01*
X497221Y225783D01*
X497012Y225533D01*
X496929Y225200D01*
G01X503667Y211925D02*
X503875Y212258D01*
X504000Y212633D01*
Y212967D01*
X503875Y213300D01*
X503667Y213550D01*
X503375Y213675D01*
X503083Y213592D01*
X502833Y213383D01*
X502667Y213008D01*
X502583Y212508D01*
X502417Y212217D01*
X502125Y212092D01*
X501833Y212175D01*
X501625Y212383D01*
X501500Y212675D01*
Y212967D01*
X501583Y213258D01*
X501792Y213508D01*
G01X501500Y215900D02*
X504000D01*
G01X501500Y214942D02*
Y216858D01*
G01X504000Y218167D02*
X501500D01*
Y219167D01*
X501625Y219500D01*
X501917Y219750D01*
X502250Y219833D01*
X502583Y219750D01*
X502833Y219542D01*
X502958Y219167D01*
Y218167D01*
G01X503500Y221183D02*
X503792Y221433D01*
X503958Y221767D01*
X504000Y222142D01*
X503958Y222475D01*
X503750Y222808D01*
X503500Y223017D01*
X503250Y223058D01*
X502958Y222975D01*
X502750Y222683D01*
X502667Y222392D01*
Y222017D01*
G01Y222392D02*
X502542Y222642D01*
X502333Y222850D01*
X502083Y222933D01*
X501833Y222850D01*
X501625Y222642D01*
X501500Y222267D01*
X501542Y221892D01*
X501708Y221517D01*
G01X504000Y225200D02*
X503958Y225492D01*
X503833Y225825D01*
X503625Y226033D01*
X503333Y226117D01*
X503042Y226033D01*
X502792Y225783D01*
X502667Y225408D01*
Y224992D01*
X502583Y224742D01*
X502375Y224533D01*
X502083Y224450D01*
X501792Y224575D01*
X501583Y224867D01*
X501500Y225200D01*
X501583Y225533D01*
X501792Y225825D01*
X502083Y225950D01*
X502375Y225867D01*
X502583Y225658D01*
X502667Y225408D01*
Y224992D01*
X502792Y224617D01*
X503042Y224367D01*
X503333Y224283D01*
X503625Y224367D01*
X503833Y224575D01*
X503958Y224908D01*
X504000Y225200D01*
G01X528000Y248500D02*
X518000D01*
Y255000D01*
X500000D01*
Y261500D01*
X497500D01*
Y266000D01*
X494500Y269000D01*
Y263000D01*
X497500Y266000D01*
G01X502354Y257233D02*
X502687Y257025D01*
X503062Y256900D01*
X503396D01*
X503729Y257025D01*
X503979Y257233D01*
X504104Y257525D01*
X504021Y257817D01*
X503812Y258067D01*
X503437Y258233D01*
X502937Y258317D01*
X502646Y258483D01*
X502521Y258775D01*
X502604Y259067D01*
X502812Y259275D01*
X503104Y259400D01*
X503396D01*
X503687Y259317D01*
X503937Y259108D01*
G01X507246Y259192D02*
X506996Y259317D01*
X506704Y259400D01*
X506371D01*
X505996Y259275D01*
X505704Y259067D01*
X505496Y258817D01*
X505329Y258400D01*
X505287Y258025D01*
X505371Y257650D01*
X505496Y257400D01*
X505746Y257150D01*
X506037Y256983D01*
X506329Y256900D01*
X506621D01*
X506912Y256983D01*
X507162Y257108D01*
X507371Y257275D01*
G01X508721Y257192D02*
X509012Y256983D01*
X509346Y256900D01*
X509679Y256983D01*
X509971Y257233D01*
X510179Y257608D01*
X510262Y257983D01*
Y258442D01*
X510179Y258817D01*
X509971Y259150D01*
X509721Y259317D01*
X509429Y259400D01*
X509096Y259317D01*
X508846Y259150D01*
X508679Y258900D01*
X508596Y258567D01*
X508679Y258275D01*
X508887Y257983D01*
X509137Y257817D01*
X509429Y257775D01*
X509762Y257858D01*
X510012Y258067D01*
X510262Y258442D01*
G01X512529Y256900D02*
Y259400D01*
X512029Y258900D01*
G01Y256900D02*
X513029D01*
G01X515546D02*
X515629Y257442D01*
X515754Y257900D01*
X515921Y258317D01*
X516129Y258775D01*
X516462Y259400D01*
X514796D01*
G01X502354Y261733D02*
X502687Y261525D01*
X503062Y261400D01*
X503396D01*
X503729Y261525D01*
X503979Y261733D01*
X504104Y262025D01*
X504021Y262317D01*
X503812Y262567D01*
X503437Y262733D01*
X502937Y262817D01*
X502646Y262983D01*
X502521Y263275D01*
X502604Y263567D01*
X502812Y263775D01*
X503104Y263900D01*
X503396D01*
X503687Y263817D01*
X503937Y263608D01*
G01X507246Y263692D02*
X506996Y263817D01*
X506704Y263900D01*
X506371D01*
X505996Y263775D01*
X505704Y263567D01*
X505496Y263317D01*
X505329Y262900D01*
X505287Y262525D01*
X505371Y262150D01*
X505496Y261900D01*
X505746Y261650D01*
X506037Y261483D01*
X506329Y261400D01*
X506621D01*
X506912Y261483D01*
X507162Y261608D01*
X507371Y261775D01*
G01X508721Y261692D02*
X509012Y261483D01*
X509346Y261400D01*
X509679Y261483D01*
X509971Y261733D01*
X510179Y262108D01*
X510262Y262483D01*
Y262942D01*
X510179Y263317D01*
X509971Y263650D01*
X509721Y263817D01*
X509429Y263900D01*
X509096Y263817D01*
X508846Y263650D01*
X508679Y263400D01*
X508596Y263067D01*
X508679Y262775D01*
X508887Y262483D01*
X509137Y262317D01*
X509429Y262275D01*
X509762Y262358D01*
X510012Y262567D01*
X510262Y262942D01*
G01X512529Y261400D02*
Y263900D01*
X512029Y263400D01*
G01Y261400D02*
X513029D01*
G01X515629D02*
X515921Y261442D01*
X516254Y261567D01*
X516462Y261775D01*
X516546Y262067D01*
X516462Y262358D01*
X516212Y262608D01*
X515837Y262733D01*
X515421D01*
X515171Y262817D01*
X514962Y263025D01*
X514879Y263317D01*
X515004Y263608D01*
X515296Y263817D01*
X515629Y263900D01*
X515962Y263817D01*
X516254Y263608D01*
X516379Y263317D01*
X516296Y263025D01*
X516087Y262817D01*
X515837Y262733D01*
X515421D01*
X515046Y262608D01*
X514796Y262358D01*
X514712Y262067D01*
X514796Y261775D01*
X515004Y261567D01*
X515337Y261442D01*
X515629Y261400D01*
G01X502354Y266233D02*
X502687Y266025D01*
X503062Y265900D01*
X503396D01*
X503729Y266025D01*
X503979Y266233D01*
X504104Y266525D01*
X504021Y266817D01*
X503812Y267067D01*
X503437Y267233D01*
X502937Y267317D01*
X502646Y267483D01*
X502521Y267775D01*
X502604Y268067D01*
X502812Y268275D01*
X503104Y268400D01*
X503396D01*
X503687Y268317D01*
X503937Y268108D01*
G01X507246Y268192D02*
X506996Y268317D01*
X506704Y268400D01*
X506371D01*
X505996Y268275D01*
X505704Y268067D01*
X505496Y267817D01*
X505329Y267400D01*
X505287Y267025D01*
X505371Y266650D01*
X505496Y266400D01*
X505746Y266150D01*
X506037Y265983D01*
X506329Y265900D01*
X506621D01*
X506912Y265983D01*
X507162Y266108D01*
X507371Y266275D01*
G01X508721Y266192D02*
X509012Y265983D01*
X509346Y265900D01*
X509679Y265983D01*
X509971Y266233D01*
X510179Y266608D01*
X510262Y266983D01*
Y267442D01*
X510179Y267817D01*
X509971Y268150D01*
X509721Y268317D01*
X509429Y268400D01*
X509096Y268317D01*
X508846Y268150D01*
X508679Y267900D01*
X508596Y267567D01*
X508679Y267275D01*
X508887Y266983D01*
X509137Y266817D01*
X509429Y266775D01*
X509762Y266858D01*
X510012Y267067D01*
X510262Y267442D01*
G01X512529Y265900D02*
Y268400D01*
X512029Y267900D01*
G01Y265900D02*
X513029D01*
G01X514712Y266275D02*
X514962Y266067D01*
X515254Y265942D01*
X515629Y265900D01*
X516004Y265983D01*
X516296Y266150D01*
X516504Y266442D01*
X516546Y266775D01*
X516462Y267108D01*
X516254Y267317D01*
X515962Y267483D01*
X515671Y267525D01*
X515379Y267483D01*
X515004Y267317D01*
X515129Y268400D01*
X516254D01*
G01X502354Y271233D02*
X502687Y271025D01*
X503062Y270900D01*
X503396D01*
X503729Y271025D01*
X503979Y271233D01*
X504104Y271525D01*
X504021Y271817D01*
X503812Y272067D01*
X503437Y272233D01*
X502937Y272317D01*
X502646Y272483D01*
X502521Y272775D01*
X502604Y273067D01*
X502812Y273275D01*
X503104Y273400D01*
X503396D01*
X503687Y273317D01*
X503937Y273108D01*
G01X507246Y273192D02*
X506996Y273317D01*
X506704Y273400D01*
X506371D01*
X505996Y273275D01*
X505704Y273067D01*
X505496Y272817D01*
X505329Y272400D01*
X505287Y272025D01*
X505371Y271650D01*
X505496Y271400D01*
X505746Y271150D01*
X506037Y270983D01*
X506329Y270900D01*
X506621D01*
X506912Y270983D01*
X507162Y271108D01*
X507371Y271275D01*
G01X508721Y271192D02*
X509012Y270983D01*
X509346Y270900D01*
X509679Y270983D01*
X509971Y271233D01*
X510179Y271608D01*
X510262Y271983D01*
Y272442D01*
X510179Y272817D01*
X509971Y273150D01*
X509721Y273317D01*
X509429Y273400D01*
X509096Y273317D01*
X508846Y273150D01*
X508679Y272900D01*
X508596Y272567D01*
X508679Y272275D01*
X508887Y271983D01*
X509137Y271817D01*
X509429Y271775D01*
X509762Y271858D01*
X510012Y272067D01*
X510262Y272442D01*
G01X512529Y270900D02*
Y273400D01*
X512029Y272900D01*
G01Y270900D02*
X513029D01*
G01X514837Y271942D02*
X515129Y272233D01*
X515379Y272400D01*
X515712Y272483D01*
X516004Y272400D01*
X516212Y272233D01*
X516379Y271983D01*
X516421Y271692D01*
X516379Y271442D01*
X516212Y271192D01*
X515962Y270983D01*
X515671Y270900D01*
X515337Y270983D01*
X515046Y271233D01*
X514879Y271608D01*
X514837Y272025D01*
X514921Y272567D01*
X515046Y272858D01*
X515254Y273150D01*
X515546Y273358D01*
X515837Y273400D01*
X516129Y273317D01*
X516337Y273108D01*
G01X509425Y282833D02*
X509758Y282625D01*
X510133Y282500D01*
X510467D01*
X510800Y282625D01*
X511050Y282833D01*
X511175Y283125D01*
X511092Y283417D01*
X510883Y283667D01*
X510508Y283833D01*
X510008Y283917D01*
X509717Y284083D01*
X509592Y284375D01*
X509675Y284667D01*
X509883Y284875D01*
X510175Y285000D01*
X510467D01*
X510758Y284917D01*
X511008Y284708D01*
G01X512567Y282500D02*
Y285000D01*
X513608D01*
X513942Y284875D01*
X514150Y284708D01*
X514233Y284375D01*
X514150Y284042D01*
X513900Y283833D01*
X513608Y283708D01*
X512567D01*
G01X513608D02*
X514233Y282500D01*
G01X516500D02*
X516792Y282542D01*
X517125Y282667D01*
X517333Y282875D01*
X517417Y283167D01*
X517333Y283458D01*
X517083Y283708D01*
X516708Y283833D01*
X516292D01*
X516042Y283917D01*
X515833Y284125D01*
X515750Y284417D01*
X515875Y284708D01*
X516167Y284917D01*
X516500Y285000D01*
X516833Y284917D01*
X517125Y284708D01*
X517250Y284417D01*
X517167Y284125D01*
X516958Y283917D01*
X516708Y283833D01*
X516292D01*
X515917Y283708D01*
X515667Y283458D01*
X515583Y283167D01*
X515667Y282875D01*
X515875Y282667D01*
X516208Y282542D01*
X516500Y282500D01*
G01X518808Y283542D02*
X519100Y283833D01*
X519350Y284000D01*
X519683Y284083D01*
X519975Y284000D01*
X520183Y283833D01*
X520350Y283583D01*
X520392Y283292D01*
X520350Y283042D01*
X520183Y282792D01*
X519933Y282583D01*
X519642Y282500D01*
X519308Y282583D01*
X519017Y282833D01*
X518850Y283208D01*
X518808Y283625D01*
X518892Y284167D01*
X519017Y284458D01*
X519225Y284750D01*
X519517Y284958D01*
X519808Y285000D01*
X520100Y284917D01*
X520308Y284708D01*
G01X521783Y282875D02*
X522033Y282667D01*
X522325Y282542D01*
X522700Y282500D01*
X523075Y282583D01*
X523367Y282750D01*
X523575Y283042D01*
X523617Y283375D01*
X523533Y283708D01*
X523325Y283917D01*
X523033Y284083D01*
X522742Y284125D01*
X522450Y284083D01*
X522075Y283917D01*
X522200Y285000D01*
X523325D01*
G01X506167Y275925D02*
X506375Y276258D01*
X506500Y276633D01*
Y276967D01*
X506375Y277300D01*
X506167Y277550D01*
X505875Y277675D01*
X505583Y277592D01*
X505333Y277383D01*
X505167Y277008D01*
X505083Y276508D01*
X504917Y276217D01*
X504625Y276092D01*
X504333Y276175D01*
X504125Y276383D01*
X504000Y276675D01*
Y276967D01*
X504083Y277258D01*
X504292Y277508D01*
G01X506500Y279067D02*
X504000D01*
Y280108D01*
X504125Y280442D01*
X504292Y280650D01*
X504625Y280733D01*
X504958Y280650D01*
X505167Y280400D01*
X505292Y280108D01*
Y279067D01*
G01Y280108D02*
X506500Y280733D01*
G01X505458Y282208D02*
X505167Y282500D01*
X505000Y282750D01*
X504917Y283083D01*
X505000Y283375D01*
X505167Y283583D01*
X505417Y283750D01*
X505708Y283792D01*
X505958Y283750D01*
X506208Y283583D01*
X506417Y283333D01*
X506500Y283042D01*
X506417Y282708D01*
X506167Y282417D01*
X505792Y282250D01*
X505375Y282208D01*
X504833Y282292D01*
X504542Y282417D01*
X504250Y282625D01*
X504042Y282917D01*
X504000Y283208D01*
X504083Y283500D01*
X504292Y283708D01*
G01X506125Y285183D02*
X506333Y285433D01*
X506458Y285725D01*
X506500Y286100D01*
X506417Y286475D01*
X506250Y286767D01*
X505958Y286975D01*
X505625Y287017D01*
X505292Y286933D01*
X505083Y286725D01*
X504917Y286433D01*
X504875Y286142D01*
X504917Y285850D01*
X505083Y285475D01*
X504000Y285600D01*
Y286725D01*
G01X506208Y288492D02*
X506417Y288783D01*
X506500Y289117D01*
X506417Y289450D01*
X506167Y289742D01*
X505792Y289950D01*
X505417Y290033D01*
X504958D01*
X504583Y289950D01*
X504250Y289742D01*
X504083Y289492D01*
X504000Y289200D01*
X504083Y288867D01*
X504250Y288617D01*
X504500Y288450D01*
X504833Y288367D01*
X505125Y288450D01*
X505417Y288658D01*
X505583Y288908D01*
X505625Y289200D01*
X505542Y289533D01*
X505333Y289783D01*
X504958Y290033D01*
G01X498273Y310483D02*
Y295083D01*
G01X509667Y295375D02*
X509875Y295708D01*
X510000Y296083D01*
Y296417D01*
X509875Y296750D01*
X509667Y297000D01*
X509375Y297125D01*
X509083Y297042D01*
X508833Y296833D01*
X508667Y296458D01*
X508583Y295958D01*
X508417Y295667D01*
X508125Y295542D01*
X507833Y295625D01*
X507625Y295833D01*
X507500Y296125D01*
Y296417D01*
X507583Y296708D01*
X507792Y296958D01*
G01X507708Y300267D02*
X507583Y300017D01*
X507500Y299725D01*
Y299392D01*
X507625Y299017D01*
X507833Y298725D01*
X508083Y298517D01*
X508500Y298350D01*
X508875Y298308D01*
X509250Y298392D01*
X509500Y298517D01*
X509750Y298767D01*
X509917Y299058D01*
X510000Y299350D01*
Y299642D01*
X509917Y299933D01*
X509792Y300183D01*
X509625Y300392D01*
G01X510000Y302450D02*
X507500D01*
X508000Y301950D01*
G01X510000D02*
Y302950D01*
G01X507500Y305550D02*
X507583Y305217D01*
X507792Y304967D01*
X508042Y304800D01*
X508375Y304675D01*
X508750Y304633D01*
X509125Y304675D01*
X509458Y304800D01*
X509708Y304967D01*
X509917Y305217D01*
X510000Y305550D01*
X509917Y305883D01*
X509708Y306133D01*
X509458Y306300D01*
X509125Y306425D01*
X508750Y306467D01*
X508375Y306425D01*
X508042Y306300D01*
X507792Y306133D01*
X507583Y305883D01*
X507500Y305550D01*
G01X509708Y307942D02*
X509917Y308233D01*
X510000Y308567D01*
X509917Y308900D01*
X509667Y309192D01*
X509292Y309400D01*
X508917Y309483D01*
X508458D01*
X508083Y309400D01*
X507750Y309192D01*
X507583Y308942D01*
X507500Y308650D01*
X507583Y308317D01*
X507750Y308067D01*
X508000Y307900D01*
X508333Y307817D01*
X508625Y307900D01*
X508917Y308108D01*
X509083Y308358D01*
X509125Y308650D01*
X509042Y308983D01*
X508833Y309233D01*
X508458Y309483D01*
G01X510000Y311667D02*
X509458Y311750D01*
X509000Y311875D01*
X508583Y312042D01*
X508125Y312250D01*
X507500Y312583D01*
Y310917D01*
G01X505667Y297375D02*
X505875Y297708D01*
X506000Y298083D01*
Y298417D01*
X505875Y298750D01*
X505667Y299000D01*
X505375Y299125D01*
X505083Y299042D01*
X504833Y298833D01*
X504667Y298458D01*
X504583Y297958D01*
X504417Y297667D01*
X504125Y297542D01*
X503833Y297625D01*
X503625Y297833D01*
X503500Y298125D01*
Y298417D01*
X503583Y298708D01*
X503792Y298958D01*
G01X503708Y302267D02*
X503583Y302017D01*
X503500Y301725D01*
Y301392D01*
X503625Y301017D01*
X503833Y300725D01*
X504083Y300517D01*
X504500Y300350D01*
X504875Y300308D01*
X505250Y300392D01*
X505500Y300517D01*
X505750Y300767D01*
X505917Y301058D01*
X506000Y301350D01*
Y301642D01*
X505917Y301933D01*
X505792Y302183D01*
X505625Y302392D01*
G01X506000Y304450D02*
X503500D01*
X504000Y303950D01*
G01X506000D02*
Y304950D01*
G01X503917Y306758D02*
X503667Y307008D01*
X503542Y307300D01*
X503500Y307633D01*
X503583Y308050D01*
X503792Y308342D01*
X504042Y308425D01*
X504292Y308383D01*
X504500Y308217D01*
X504917Y307383D01*
X505208Y307008D01*
X505625Y306758D01*
X506000Y306675D01*
Y308425D01*
G01X504958Y309858D02*
X504667Y310150D01*
X504500Y310400D01*
X504417Y310733D01*
X504500Y311025D01*
X504667Y311233D01*
X504917Y311400D01*
X505208Y311442D01*
X505458Y311400D01*
X505708Y311233D01*
X505917Y310983D01*
X506000Y310692D01*
X505917Y310358D01*
X505667Y310067D01*
X505292Y309900D01*
X504875Y309858D01*
X504333Y309942D01*
X504042Y310067D01*
X503750Y310275D01*
X503542Y310567D01*
X503500Y310858D01*
X503583Y311150D01*
X503792Y311358D01*
G01X506000Y313750D02*
X503500D01*
X504000Y313250D01*
G01X506000D02*
Y314250D01*
G01X517000Y293000D02*
X521000D01*
Y323000D01*
X517000D01*
Y330000D01*
X520500D01*
Y337500D01*
X510500D01*
Y315500D01*
X500500D01*
Y311000D01*
G01X507165Y320275D02*
G03I-1850J0D01*
G01X497322D02*
X503465D01*
G01X505315Y328268D02*
Y322125D01*
G01Y414882D02*
Y331968D01*
G01X507165Y330118D02*
G03I-1850J0D01*
G01X512032Y392835D02*
X512240Y393168D01*
X512365Y393543D01*
Y393877D01*
X512240Y394210D01*
X512032Y394460D01*
X511740Y394585D01*
X511448Y394502D01*
X511198Y394293D01*
X511032Y393918D01*
X510948Y393418D01*
X510782Y393127D01*
X510490Y393002D01*
X510198Y393085D01*
X509990Y393293D01*
X509865Y393585D01*
Y393877D01*
X509948Y394168D01*
X510157Y394418D01*
G01X510073Y397727D02*
X509948Y397477D01*
X509865Y397185D01*
Y396852D01*
X509990Y396477D01*
X510198Y396185D01*
X510448Y395977D01*
X510865Y395810D01*
X511240Y395768D01*
X511615Y395852D01*
X511865Y395977D01*
X512115Y396227D01*
X512282Y396518D01*
X512365Y396810D01*
Y397102D01*
X512282Y397393D01*
X512157Y397643D01*
X511990Y397852D01*
G01X512365Y399910D02*
X509865D01*
X510365Y399410D01*
G01X512365D02*
Y400410D01*
G01X510282Y402218D02*
X510032Y402468D01*
X509907Y402760D01*
X509865Y403093D01*
X509948Y403510D01*
X510157Y403802D01*
X510407Y403885D01*
X510657Y403843D01*
X510865Y403677D01*
X511282Y402843D01*
X511573Y402468D01*
X511990Y402218D01*
X512365Y402135D01*
Y403885D01*
G01Y406027D02*
X511823Y406110D01*
X511365Y406235D01*
X510948Y406402D01*
X510490Y406610D01*
X509865Y406943D01*
Y405277D01*
G01X511865Y408293D02*
X512157Y408543D01*
X512323Y408877D01*
X512365Y409252D01*
X512323Y409585D01*
X512115Y409918D01*
X511865Y410127D01*
X511615Y410168D01*
X511323Y410085D01*
X511115Y409793D01*
X511032Y409502D01*
Y409127D01*
G01Y409502D02*
X510907Y409752D01*
X510698Y409960D01*
X510448Y410043D01*
X510198Y409960D01*
X509990Y409752D01*
X509865Y409377D01*
X509907Y409002D01*
X510073Y408627D01*
G01X507165Y416732D02*
G03I-1850J0D01*
G01X497322Y426575D02*
X503465D01*
G01X507165D02*
G03I-1850J0D01*
G01X505315Y424725D02*
Y418582D01*
G01X517400Y143600D02*
Y154400D01*
X522600D01*
Y143600D01*
X517400D01*
G01X520667Y159375D02*
X520875Y159708D01*
X521000Y160083D01*
Y160417D01*
X520875Y160750D01*
X520667Y161000D01*
X520375Y161125D01*
X520083Y161042D01*
X519833Y160833D01*
X519667Y160458D01*
X519583Y159958D01*
X519417Y159667D01*
X519125Y159542D01*
X518833Y159625D01*
X518625Y159833D01*
X518500Y160125D01*
Y160417D01*
X518583Y160708D01*
X518792Y160958D01*
G01X518500Y162517D02*
X521000D01*
Y164183D01*
G01Y167283D02*
Y165617D01*
X518500D01*
Y167283D01*
G01X519708Y166617D02*
Y165617D01*
G01X521000Y168633D02*
X518500D01*
Y169467D01*
X518625Y169800D01*
X518792Y170050D01*
X519042Y170258D01*
X519333Y170425D01*
X519750Y170467D01*
X520167Y170425D01*
X520458Y170258D01*
X520708Y170050D01*
X520875Y169800D01*
X521000Y169467D01*
Y168633D01*
G01X518917Y171858D02*
X518667Y172108D01*
X518542Y172400D01*
X518500Y172733D01*
X518583Y173150D01*
X518792Y173442D01*
X519042Y173525D01*
X519292Y173483D01*
X519500Y173317D01*
X519917Y172483D01*
X520208Y172108D01*
X520625Y171858D01*
X521000Y171775D01*
Y173525D01*
G01X520625Y174833D02*
X520833Y175083D01*
X520958Y175375D01*
X521000Y175750D01*
X520917Y176125D01*
X520750Y176417D01*
X520458Y176625D01*
X520125Y176667D01*
X519792Y176583D01*
X519583Y176375D01*
X519417Y176083D01*
X519375Y175792D01*
X519417Y175500D01*
X519583Y175125D01*
X518500Y175250D01*
Y176375D01*
G01X524602Y190263D02*
X524810Y190596D01*
X524935Y190971D01*
Y191305D01*
X524810Y191638D01*
X524602Y191888D01*
X524310Y192013D01*
X524018Y191930D01*
X523768Y191721D01*
X523602Y191346D01*
X523518Y190846D01*
X523352Y190555D01*
X523060Y190430D01*
X522768Y190513D01*
X522560Y190721D01*
X522435Y191013D01*
Y191305D01*
X522518Y191596D01*
X522727Y191846D01*
G01X522435Y194238D02*
X524935D01*
G01X522435Y193280D02*
Y195196D01*
G01X524935Y196505D02*
X522435D01*
Y197505D01*
X522560Y197838D01*
X522852Y198088D01*
X523185Y198171D01*
X523518Y198088D01*
X523768Y197880D01*
X523893Y197505D01*
Y196505D01*
G01X524935Y200438D02*
X522435D01*
X522935Y199938D01*
G01X524935D02*
Y200938D01*
G01Y203538D02*
X522435D01*
X522935Y203038D01*
G01X524935D02*
Y204038D01*
G01Y206555D02*
X524393Y206638D01*
X523935Y206763D01*
X523518Y206930D01*
X523060Y207138D01*
X522435Y207471D01*
Y205805D01*
G01X529096Y250325D02*
X529304Y250658D01*
X529429Y251033D01*
Y251367D01*
X529304Y251700D01*
X529096Y251950D01*
X528804Y252075D01*
X528512Y251992D01*
X528262Y251783D01*
X528096Y251408D01*
X528012Y250908D01*
X527846Y250617D01*
X527554Y250492D01*
X527262Y250575D01*
X527054Y250783D01*
X526929Y251075D01*
Y251367D01*
X527012Y251658D01*
X527221Y251908D01*
G01X529429Y253467D02*
X526929D01*
Y254508D01*
X527054Y254842D01*
X527221Y255050D01*
X527554Y255133D01*
X527887Y255050D01*
X528096Y254800D01*
X528221Y254508D01*
Y253467D01*
G01Y254508D02*
X529429Y255133D01*
G01X528387Y256608D02*
X528096Y256900D01*
X527929Y257150D01*
X527846Y257483D01*
X527929Y257775D01*
X528096Y257983D01*
X528346Y258150D01*
X528637Y258192D01*
X528887Y258150D01*
X529137Y257983D01*
X529346Y257733D01*
X529429Y257442D01*
X529346Y257108D01*
X529096Y256817D01*
X528721Y256650D01*
X528304Y256608D01*
X527762Y256692D01*
X527471Y256817D01*
X527179Y257025D01*
X526971Y257317D01*
X526929Y257608D01*
X527012Y257900D01*
X527221Y258108D01*
G01X529429Y260500D02*
X529387Y260792D01*
X529262Y261125D01*
X529054Y261333D01*
X528762Y261417D01*
X528471Y261333D01*
X528221Y261083D01*
X528096Y260708D01*
Y260292D01*
X528012Y260042D01*
X527804Y259833D01*
X527512Y259750D01*
X527221Y259875D01*
X527012Y260167D01*
X526929Y260500D01*
X527012Y260833D01*
X527221Y261125D01*
X527512Y261250D01*
X527804Y261167D01*
X528012Y260958D01*
X528096Y260708D01*
Y260292D01*
X528221Y259917D01*
X528471Y259667D01*
X528762Y259583D01*
X529054Y259667D01*
X529262Y259875D01*
X529387Y260208D01*
X529429Y260500D01*
G01Y263600D02*
X526929D01*
X527429Y263100D01*
G01X529429D02*
Y264100D01*
G01X524596Y250325D02*
X524804Y250658D01*
X524929Y251033D01*
Y251367D01*
X524804Y251700D01*
X524596Y251950D01*
X524304Y252075D01*
X524012Y251992D01*
X523762Y251783D01*
X523596Y251408D01*
X523512Y250908D01*
X523346Y250617D01*
X523054Y250492D01*
X522762Y250575D01*
X522554Y250783D01*
X522429Y251075D01*
Y251367D01*
X522512Y251658D01*
X522721Y251908D01*
G01X524929Y253467D02*
X522429D01*
Y254508D01*
X522554Y254842D01*
X522721Y255050D01*
X523054Y255133D01*
X523387Y255050D01*
X523596Y254800D01*
X523721Y254508D01*
Y253467D01*
G01Y254508D02*
X524929Y255133D01*
G01X523887Y256608D02*
X523596Y256900D01*
X523429Y257150D01*
X523346Y257483D01*
X523429Y257775D01*
X523596Y257983D01*
X523846Y258150D01*
X524137Y258192D01*
X524387Y258150D01*
X524637Y257983D01*
X524846Y257733D01*
X524929Y257442D01*
X524846Y257108D01*
X524596Y256817D01*
X524221Y256650D01*
X523804Y256608D01*
X523262Y256692D01*
X522971Y256817D01*
X522679Y257025D01*
X522471Y257317D01*
X522429Y257608D01*
X522512Y257900D01*
X522721Y258108D01*
G01X524929Y260500D02*
X524887Y260792D01*
X524762Y261125D01*
X524554Y261333D01*
X524262Y261417D01*
X523971Y261333D01*
X523721Y261083D01*
X523596Y260708D01*
Y260292D01*
X523512Y260042D01*
X523304Y259833D01*
X523012Y259750D01*
X522721Y259875D01*
X522512Y260167D01*
X522429Y260500D01*
X522512Y260833D01*
X522721Y261125D01*
X523012Y261250D01*
X523304Y261167D01*
X523512Y260958D01*
X523596Y260708D01*
Y260292D01*
X523721Y259917D01*
X523971Y259667D01*
X524262Y259583D01*
X524554Y259667D01*
X524762Y259875D01*
X524887Y260208D01*
X524929Y260500D01*
G01Y263600D02*
X524887Y263892D01*
X524762Y264225D01*
X524554Y264433D01*
X524262Y264517D01*
X523971Y264433D01*
X523721Y264183D01*
X523596Y263808D01*
Y263392D01*
X523512Y263142D01*
X523304Y262933D01*
X523012Y262850D01*
X522721Y262975D01*
X522512Y263267D01*
X522429Y263600D01*
X522512Y263933D01*
X522721Y264225D01*
X523012Y264350D01*
X523304Y264267D01*
X523512Y264058D01*
X523596Y263808D01*
Y263392D01*
X523721Y263017D01*
X523971Y262767D01*
X524262Y262683D01*
X524554Y262767D01*
X524762Y262975D01*
X524887Y263308D01*
X524929Y263600D01*
G01X519867Y259225D02*
X520075Y259558D01*
X520200Y259933D01*
Y260267D01*
X520075Y260600D01*
X519867Y260850D01*
X519575Y260975D01*
X519283Y260892D01*
X519033Y260683D01*
X518867Y260308D01*
X518783Y259808D01*
X518617Y259517D01*
X518325Y259392D01*
X518033Y259475D01*
X517825Y259683D01*
X517700Y259975D01*
Y260267D01*
X517783Y260558D01*
X517992Y260808D01*
G01X517700Y263200D02*
X520200D01*
G01X517700Y262242D02*
Y264158D01*
G01X520200Y265467D02*
X517700D01*
Y266467D01*
X517825Y266800D01*
X518117Y267050D01*
X518450Y267133D01*
X518783Y267050D01*
X519033Y266842D01*
X519158Y266467D01*
Y265467D01*
G01X519825Y268483D02*
X520033Y268733D01*
X520158Y269025D01*
X520200Y269400D01*
X520117Y269775D01*
X519950Y270067D01*
X519658Y270275D01*
X519325Y270317D01*
X518992Y270233D01*
X518783Y270025D01*
X518617Y269733D01*
X518575Y269442D01*
X518617Y269150D01*
X518783Y268775D01*
X517700Y268900D01*
Y270025D01*
G01X519908Y271792D02*
X520117Y272083D01*
X520200Y272417D01*
X520117Y272750D01*
X519867Y273042D01*
X519492Y273250D01*
X519117Y273333D01*
X518658D01*
X518283Y273250D01*
X517950Y273042D01*
X517783Y272792D01*
X517700Y272500D01*
X517783Y272167D01*
X517950Y271917D01*
X518200Y271750D01*
X518533Y271667D01*
X518825Y271750D01*
X519117Y271958D01*
X519283Y272208D01*
X519325Y272500D01*
X519242Y272833D01*
X519033Y273083D01*
X518658Y273333D01*
G01X524596Y266325D02*
X524804Y266658D01*
X524929Y267033D01*
Y267367D01*
X524804Y267700D01*
X524596Y267950D01*
X524304Y268075D01*
X524012Y267992D01*
X523762Y267783D01*
X523596Y267408D01*
X523512Y266908D01*
X523346Y266617D01*
X523054Y266492D01*
X522762Y266575D01*
X522554Y266783D01*
X522429Y267075D01*
Y267367D01*
X522512Y267658D01*
X522721Y267908D01*
G01X524929Y269467D02*
X522429D01*
Y270508D01*
X522554Y270842D01*
X522721Y271050D01*
X523054Y271133D01*
X523387Y271050D01*
X523596Y270800D01*
X523721Y270508D01*
Y269467D01*
G01Y270508D02*
X524929Y271133D01*
G01Y273400D02*
X524887Y273692D01*
X524762Y274025D01*
X524554Y274233D01*
X524262Y274317D01*
X523971Y274233D01*
X523721Y273983D01*
X523596Y273608D01*
Y273192D01*
X523512Y272942D01*
X523304Y272733D01*
X523012Y272650D01*
X522721Y272775D01*
X522512Y273067D01*
X522429Y273400D01*
X522512Y273733D01*
X522721Y274025D01*
X523012Y274150D01*
X523304Y274067D01*
X523512Y273858D01*
X523596Y273608D01*
Y273192D01*
X523721Y272817D01*
X523971Y272567D01*
X524262Y272483D01*
X524554Y272567D01*
X524762Y272775D01*
X524887Y273108D01*
X524929Y273400D01*
G01X523887Y275708D02*
X523596Y276000D01*
X523429Y276250D01*
X523346Y276583D01*
X523429Y276875D01*
X523596Y277083D01*
X523846Y277250D01*
X524137Y277292D01*
X524387Y277250D01*
X524637Y277083D01*
X524846Y276833D01*
X524929Y276542D01*
X524846Y276208D01*
X524596Y275917D01*
X524221Y275750D01*
X523804Y275708D01*
X523262Y275792D01*
X522971Y275917D01*
X522679Y276125D01*
X522471Y276417D01*
X522429Y276708D01*
X522512Y277000D01*
X522721Y277208D01*
G01X523887Y278808D02*
X523596Y279100D01*
X523429Y279350D01*
X523346Y279683D01*
X523429Y279975D01*
X523596Y280183D01*
X523846Y280350D01*
X524137Y280392D01*
X524387Y280350D01*
X524637Y280183D01*
X524846Y279933D01*
X524929Y279642D01*
X524846Y279308D01*
X524596Y279017D01*
X524221Y278850D01*
X523804Y278808D01*
X523262Y278892D01*
X522971Y279017D01*
X522679Y279225D01*
X522471Y279517D01*
X522429Y279808D01*
X522512Y280100D01*
X522721Y280308D01*
G01X529096Y266325D02*
X529304Y266658D01*
X529429Y267033D01*
Y267367D01*
X529304Y267700D01*
X529096Y267950D01*
X528804Y268075D01*
X528512Y267992D01*
X528262Y267783D01*
X528096Y267408D01*
X528012Y266908D01*
X527846Y266617D01*
X527554Y266492D01*
X527262Y266575D01*
X527054Y266783D01*
X526929Y267075D01*
Y267367D01*
X527012Y267658D01*
X527221Y267908D01*
G01X529429Y269467D02*
X526929D01*
Y270508D01*
X527054Y270842D01*
X527221Y271050D01*
X527554Y271133D01*
X527887Y271050D01*
X528096Y270800D01*
X528221Y270508D01*
Y269467D01*
G01Y270508D02*
X529429Y271133D01*
G01X528387Y272608D02*
X528096Y272900D01*
X527929Y273150D01*
X527846Y273483D01*
X527929Y273775D01*
X528096Y273983D01*
X528346Y274150D01*
X528637Y274192D01*
X528887Y274150D01*
X529137Y273983D01*
X529346Y273733D01*
X529429Y273442D01*
X529346Y273108D01*
X529096Y272817D01*
X528721Y272650D01*
X528304Y272608D01*
X527762Y272692D01*
X527471Y272817D01*
X527179Y273025D01*
X526971Y273317D01*
X526929Y273608D01*
X527012Y273900D01*
X527221Y274108D01*
G01X529054Y275583D02*
X529262Y275833D01*
X529387Y276125D01*
X529429Y276500D01*
X529346Y276875D01*
X529179Y277167D01*
X528887Y277375D01*
X528554Y277417D01*
X528221Y277333D01*
X528012Y277125D01*
X527846Y276833D01*
X527804Y276542D01*
X527846Y276250D01*
X528012Y275875D01*
X526929Y276000D01*
Y277125D01*
G01X529429Y279600D02*
X529387Y279892D01*
X529262Y280225D01*
X529054Y280433D01*
X528762Y280517D01*
X528471Y280433D01*
X528221Y280183D01*
X528096Y279808D01*
Y279392D01*
X528012Y279142D01*
X527804Y278933D01*
X527512Y278850D01*
X527221Y278975D01*
X527012Y279267D01*
X526929Y279600D01*
X527012Y279933D01*
X527221Y280225D01*
X527512Y280350D01*
X527804Y280267D01*
X528012Y280058D01*
X528096Y279808D01*
Y279392D01*
X528221Y279017D01*
X528471Y278767D01*
X528762Y278683D01*
X529054Y278767D01*
X529262Y278975D01*
X529387Y279308D01*
X529429Y279600D01*
G01X527767Y284792D02*
X527517Y284917D01*
X527225Y285000D01*
X526892D01*
X526517Y284875D01*
X526225Y284667D01*
X526017Y284417D01*
X525850Y284000D01*
X525808Y283625D01*
X525892Y283250D01*
X526017Y283000D01*
X526267Y282750D01*
X526558Y282583D01*
X526850Y282500D01*
X527142D01*
X527433Y282583D01*
X527683Y282708D01*
X527892Y282875D01*
G01X529033Y283000D02*
X529283Y282708D01*
X529617Y282542D01*
X529992Y282500D01*
X530325Y282542D01*
X530658Y282750D01*
X530867Y283000D01*
X530908Y283250D01*
X530825Y283542D01*
X530533Y283750D01*
X530242Y283833D01*
X529867D01*
G01X530242D02*
X530492Y283958D01*
X530700Y284167D01*
X530783Y284417D01*
X530700Y284667D01*
X530492Y284875D01*
X530117Y285000D01*
X529742Y284958D01*
X529367Y284792D01*
G01X532258Y284583D02*
X532508Y284833D01*
X532800Y284958D01*
X533133Y285000D01*
X533550Y284917D01*
X533842Y284708D01*
X533925Y284458D01*
X533883Y284208D01*
X533717Y284000D01*
X532883Y283583D01*
X532508Y283292D01*
X532258Y282875D01*
X532175Y282500D01*
X533925D01*
G01X536150D02*
X536442Y282542D01*
X536775Y282667D01*
X536983Y282875D01*
X537067Y283167D01*
X536983Y283458D01*
X536733Y283708D01*
X536358Y283833D01*
X535942D01*
X535692Y283917D01*
X535483Y284125D01*
X535400Y284417D01*
X535525Y284708D01*
X535817Y284917D01*
X536150Y285000D01*
X536483Y284917D01*
X536775Y284708D01*
X536900Y284417D01*
X536817Y284125D01*
X536608Y283917D01*
X536358Y283833D01*
X535942D01*
X535567Y283708D01*
X535317Y283458D01*
X535233Y283167D01*
X535317Y282875D01*
X535525Y282667D01*
X535858Y282542D01*
X536150Y282500D01*
G01X514167Y294375D02*
X514375Y294708D01*
X514500Y295083D01*
Y295417D01*
X514375Y295750D01*
X514167Y296000D01*
X513875Y296125D01*
X513583Y296042D01*
X513333Y295833D01*
X513167Y295458D01*
X513083Y294958D01*
X512917Y294667D01*
X512625Y294542D01*
X512333Y294625D01*
X512125Y294833D01*
X512000Y295125D01*
Y295417D01*
X512083Y295708D01*
X512292Y295958D01*
G01X512208Y299267D02*
X512083Y299017D01*
X512000Y298725D01*
Y298392D01*
X512125Y298017D01*
X512333Y297725D01*
X512583Y297517D01*
X513000Y297350D01*
X513375Y297308D01*
X513750Y297392D01*
X514000Y297517D01*
X514250Y297767D01*
X514417Y298058D01*
X514500Y298350D01*
Y298642D01*
X514417Y298933D01*
X514292Y299183D01*
X514125Y299392D01*
G01X514500Y301450D02*
X512000D01*
X512500Y300950D01*
G01X514500D02*
Y301950D01*
G01X512000Y304550D02*
X512083Y304217D01*
X512292Y303967D01*
X512542Y303800D01*
X512875Y303675D01*
X513250Y303633D01*
X513625Y303675D01*
X513958Y303800D01*
X514208Y303967D01*
X514417Y304217D01*
X514500Y304550D01*
X514417Y304883D01*
X514208Y305133D01*
X513958Y305300D01*
X513625Y305425D01*
X513250Y305467D01*
X512875Y305425D01*
X512542Y305300D01*
X512292Y305133D01*
X512083Y304883D01*
X512000Y304550D01*
G01X514208Y306942D02*
X514417Y307233D01*
X514500Y307567D01*
X514417Y307900D01*
X514167Y308192D01*
X513792Y308400D01*
X513417Y308483D01*
X512958D01*
X512583Y308400D01*
X512250Y308192D01*
X512083Y307942D01*
X512000Y307650D01*
X512083Y307317D01*
X512250Y307067D01*
X512500Y306900D01*
X512833Y306817D01*
X513125Y306900D01*
X513417Y307108D01*
X513583Y307358D01*
X513625Y307650D01*
X513542Y307983D01*
X513333Y308233D01*
X512958Y308483D01*
G01X514500Y310750D02*
X512000D01*
X512500Y310250D01*
G01X514500D02*
Y311250D01*
G01X518667Y294375D02*
X518875Y294708D01*
X519000Y295083D01*
Y295417D01*
X518875Y295750D01*
X518667Y296000D01*
X518375Y296125D01*
X518083Y296042D01*
X517833Y295833D01*
X517667Y295458D01*
X517583Y294958D01*
X517417Y294667D01*
X517125Y294542D01*
X516833Y294625D01*
X516625Y294833D01*
X516500Y295125D01*
Y295417D01*
X516583Y295708D01*
X516792Y295958D01*
G01X516708Y299267D02*
X516583Y299017D01*
X516500Y298725D01*
Y298392D01*
X516625Y298017D01*
X516833Y297725D01*
X517083Y297517D01*
X517500Y297350D01*
X517875Y297308D01*
X518250Y297392D01*
X518500Y297517D01*
X518750Y297767D01*
X518917Y298058D01*
X519000Y298350D01*
Y298642D01*
X518917Y298933D01*
X518792Y299183D01*
X518625Y299392D01*
G01X519000Y301450D02*
X516500D01*
X517000Y300950D01*
G01X519000D02*
Y301950D01*
G01X516500Y304550D02*
X516583Y304217D01*
X516792Y303967D01*
X517042Y303800D01*
X517375Y303675D01*
X517750Y303633D01*
X518125Y303675D01*
X518458Y303800D01*
X518708Y303967D01*
X518917Y304217D01*
X519000Y304550D01*
X518917Y304883D01*
X518708Y305133D01*
X518458Y305300D01*
X518125Y305425D01*
X517750Y305467D01*
X517375Y305425D01*
X517042Y305300D01*
X516792Y305133D01*
X516583Y304883D01*
X516500Y304550D01*
G01X518708Y306942D02*
X518917Y307233D01*
X519000Y307567D01*
X518917Y307900D01*
X518667Y308192D01*
X518292Y308400D01*
X517917Y308483D01*
X517458D01*
X517083Y308400D01*
X516750Y308192D01*
X516583Y307942D01*
X516500Y307650D01*
X516583Y307317D01*
X516750Y307067D01*
X517000Y306900D01*
X517333Y306817D01*
X517625Y306900D01*
X517917Y307108D01*
X518083Y307358D01*
X518125Y307650D01*
X518042Y307983D01*
X517833Y308233D01*
X517458Y308483D01*
G01X516917Y309958D02*
X516667Y310208D01*
X516542Y310500D01*
X516500Y310833D01*
X516583Y311250D01*
X516792Y311542D01*
X517042Y311625D01*
X517292Y311583D01*
X517500Y311417D01*
X517917Y310583D01*
X518208Y310208D01*
X518625Y309958D01*
X519000Y309875D01*
Y311625D01*
G01X528722Y301875D02*
X528930Y302208D01*
X529055Y302583D01*
Y302917D01*
X528930Y303250D01*
X528722Y303500D01*
X528430Y303625D01*
X528138Y303542D01*
X527888Y303333D01*
X527722Y302958D01*
X527638Y302458D01*
X527472Y302167D01*
X527180Y302042D01*
X526888Y302125D01*
X526680Y302333D01*
X526555Y302625D01*
Y302917D01*
X526638Y303208D01*
X526847Y303458D01*
G01X526763Y306767D02*
X526638Y306517D01*
X526555Y306225D01*
Y305892D01*
X526680Y305517D01*
X526888Y305225D01*
X527138Y305017D01*
X527555Y304850D01*
X527930Y304808D01*
X528305Y304892D01*
X528555Y305017D01*
X528805Y305267D01*
X528972Y305558D01*
X529055Y305850D01*
Y306142D01*
X528972Y306433D01*
X528847Y306683D01*
X528680Y306892D01*
G01X529055Y308950D02*
X526555D01*
X527055Y308450D01*
G01X529055D02*
Y309450D01*
G01X526555Y312050D02*
X526638Y311717D01*
X526847Y311467D01*
X527097Y311300D01*
X527430Y311175D01*
X527805Y311133D01*
X528180Y311175D01*
X528513Y311300D01*
X528763Y311467D01*
X528972Y311717D01*
X529055Y312050D01*
X528972Y312383D01*
X528763Y312633D01*
X528513Y312800D01*
X528180Y312925D01*
X527805Y312967D01*
X527430Y312925D01*
X527097Y312800D01*
X526847Y312633D01*
X526638Y312383D01*
X526555Y312050D01*
G01X528763Y314442D02*
X528972Y314733D01*
X529055Y315067D01*
X528972Y315400D01*
X528722Y315692D01*
X528347Y315900D01*
X527972Y315983D01*
X527513D01*
X527138Y315900D01*
X526805Y315692D01*
X526638Y315442D01*
X526555Y315150D01*
X526638Y314817D01*
X526805Y314567D01*
X527055Y314400D01*
X527388Y314317D01*
X527680Y314400D01*
X527972Y314608D01*
X528138Y314858D01*
X528180Y315150D01*
X528097Y315483D01*
X527888Y315733D01*
X527513Y315983D01*
G01X528555Y317333D02*
X528847Y317583D01*
X529013Y317917D01*
X529055Y318292D01*
X529013Y318625D01*
X528805Y318958D01*
X528555Y319167D01*
X528305Y319208D01*
X528013Y319125D01*
X527805Y318833D01*
X527722Y318542D01*
Y318167D01*
G01Y318542D02*
X527597Y318792D01*
X527388Y319000D01*
X527138Y319083D01*
X526888Y319000D01*
X526680Y318792D01*
X526555Y318417D01*
X526597Y318042D01*
X526763Y317667D01*
G01X524722Y305375D02*
X524930Y305708D01*
X525055Y306083D01*
Y306417D01*
X524930Y306750D01*
X524722Y307000D01*
X524430Y307125D01*
X524138Y307042D01*
X523888Y306833D01*
X523722Y306458D01*
X523638Y305958D01*
X523472Y305667D01*
X523180Y305542D01*
X522888Y305625D01*
X522680Y305833D01*
X522555Y306125D01*
Y306417D01*
X522638Y306708D01*
X522847Y306958D01*
G01X522763Y310267D02*
X522638Y310017D01*
X522555Y309725D01*
Y309392D01*
X522680Y309017D01*
X522888Y308725D01*
X523138Y308517D01*
X523555Y308350D01*
X523930Y308308D01*
X524305Y308392D01*
X524555Y308517D01*
X524805Y308767D01*
X524972Y309058D01*
X525055Y309350D01*
Y309642D01*
X524972Y309933D01*
X524847Y310183D01*
X524680Y310392D01*
G01X525055Y312450D02*
X522555D01*
X523055Y311950D01*
G01X525055D02*
Y312950D01*
G01X522555Y315550D02*
X522638Y315217D01*
X522847Y314967D01*
X523097Y314800D01*
X523430Y314675D01*
X523805Y314633D01*
X524180Y314675D01*
X524513Y314800D01*
X524763Y314967D01*
X524972Y315217D01*
X525055Y315550D01*
X524972Y315883D01*
X524763Y316133D01*
X524513Y316300D01*
X524180Y316425D01*
X523805Y316467D01*
X523430Y316425D01*
X523097Y316300D01*
X522847Y316133D01*
X522638Y315883D01*
X522555Y315550D01*
G01X524763Y317942D02*
X524972Y318233D01*
X525055Y318567D01*
X524972Y318900D01*
X524722Y319192D01*
X524347Y319400D01*
X523972Y319483D01*
X523513D01*
X523138Y319400D01*
X522805Y319192D01*
X522638Y318942D01*
X522555Y318650D01*
X522638Y318317D01*
X522805Y318067D01*
X523055Y317900D01*
X523388Y317817D01*
X523680Y317900D01*
X523972Y318108D01*
X524138Y318358D01*
X524180Y318650D01*
X524097Y318983D01*
X523888Y319233D01*
X523513Y319483D01*
G01X525055Y322250D02*
X522555D01*
X524347Y320708D01*
Y322792D01*
G01X524930Y335833D02*
X525263Y335625D01*
X525638Y335500D01*
X525972D01*
X526305Y335625D01*
X526555Y335833D01*
X526680Y336125D01*
X526597Y336417D01*
X526388Y336667D01*
X526013Y336833D01*
X525513Y336917D01*
X525222Y337083D01*
X525097Y337375D01*
X525180Y337667D01*
X525388Y337875D01*
X525680Y338000D01*
X525972D01*
X526263Y337917D01*
X526513Y337708D01*
G01X529822Y337792D02*
X529572Y337917D01*
X529280Y338000D01*
X528947D01*
X528572Y337875D01*
X528280Y337667D01*
X528072Y337417D01*
X527905Y337000D01*
X527863Y336625D01*
X527947Y336250D01*
X528072Y336000D01*
X528322Y335750D01*
X528613Y335583D01*
X528905Y335500D01*
X529197D01*
X529488Y335583D01*
X529738Y335708D01*
X529947Y335875D01*
G01X532005Y335500D02*
Y338000D01*
X531505Y337500D01*
G01Y335500D02*
X532505D01*
G01X535105Y338000D02*
X534772Y337917D01*
X534522Y337708D01*
X534355Y337458D01*
X534230Y337125D01*
X534188Y336750D01*
X534230Y336375D01*
X534355Y336042D01*
X534522Y335792D01*
X534772Y335583D01*
X535105Y335500D01*
X535438Y335583D01*
X535688Y335792D01*
X535855Y336042D01*
X535980Y336375D01*
X536022Y336750D01*
X535980Y337125D01*
X535855Y337458D01*
X535688Y337708D01*
X535438Y337917D01*
X535105Y338000D01*
G01X537497Y335792D02*
X537788Y335583D01*
X538122Y335500D01*
X538455Y335583D01*
X538747Y335833D01*
X538955Y336208D01*
X539038Y336583D01*
Y337042D01*
X538955Y337417D01*
X538747Y337750D01*
X538497Y337917D01*
X538205Y338000D01*
X537872Y337917D01*
X537622Y337750D01*
X537455Y337500D01*
X537372Y337167D01*
X537455Y336875D01*
X537663Y336583D01*
X537913Y336417D01*
X538205Y336375D01*
X538538Y336458D01*
X538788Y336667D01*
X539038Y337042D01*
G01X540388Y335875D02*
X540638Y335667D01*
X540930Y335542D01*
X541305Y335500D01*
X541680Y335583D01*
X541972Y335750D01*
X542180Y336042D01*
X542222Y336375D01*
X542138Y336708D01*
X541930Y336917D01*
X541638Y337083D01*
X541347Y337125D01*
X541055Y337083D01*
X540680Y336917D01*
X540805Y338000D01*
X541930D01*
G01X524898Y339616D02*
X525231Y339408D01*
X525606Y339283D01*
X525940D01*
X526273Y339408D01*
X526523Y339616D01*
X526648Y339908D01*
X526565Y340200D01*
X526356Y340450D01*
X525981Y340616D01*
X525481Y340700D01*
X525190Y340866D01*
X525065Y341158D01*
X525148Y341450D01*
X525356Y341658D01*
X525648Y341783D01*
X525940D01*
X526231Y341700D01*
X526481Y341491D01*
G01X529790Y341575D02*
X529540Y341700D01*
X529248Y341783D01*
X528915D01*
X528540Y341658D01*
X528248Y341450D01*
X528040Y341200D01*
X527873Y340783D01*
X527831Y340408D01*
X527915Y340033D01*
X528040Y339783D01*
X528290Y339533D01*
X528581Y339366D01*
X528873Y339283D01*
X529165D01*
X529456Y339366D01*
X529706Y339491D01*
X529915Y339658D01*
G01X531973Y339283D02*
Y341783D01*
X531473Y341283D01*
G01Y339283D02*
X532473D01*
G01X535073Y341783D02*
X534740Y341700D01*
X534490Y341491D01*
X534323Y341241D01*
X534198Y340908D01*
X534156Y340533D01*
X534198Y340158D01*
X534323Y339825D01*
X534490Y339575D01*
X534740Y339366D01*
X535073Y339283D01*
X535406Y339366D01*
X535656Y339575D01*
X535823Y339825D01*
X535948Y340158D01*
X535990Y340533D01*
X535948Y340908D01*
X535823Y341241D01*
X535656Y341491D01*
X535406Y341700D01*
X535073Y341783D01*
G01X537465Y339575D02*
X537756Y339366D01*
X538090Y339283D01*
X538423Y339366D01*
X538715Y339616D01*
X538923Y339991D01*
X539006Y340366D01*
Y340825D01*
X538923Y341200D01*
X538715Y341533D01*
X538465Y341700D01*
X538173Y341783D01*
X537840Y341700D01*
X537590Y341533D01*
X537423Y341283D01*
X537340Y340950D01*
X537423Y340658D01*
X537631Y340366D01*
X537881Y340200D01*
X538173Y340158D01*
X538506Y340241D01*
X538756Y340450D01*
X539006Y340825D01*
G01X540481Y340325D02*
X540773Y340616D01*
X541023Y340783D01*
X541356Y340866D01*
X541648Y340783D01*
X541856Y340616D01*
X542023Y340366D01*
X542065Y340075D01*
X542023Y339825D01*
X541856Y339575D01*
X541606Y339366D01*
X541315Y339283D01*
X540981Y339366D01*
X540690Y339616D01*
X540523Y339991D01*
X540481Y340408D01*
X540565Y340950D01*
X540690Y341241D01*
X540898Y341533D01*
X541190Y341741D01*
X541481Y341783D01*
X541773Y341700D01*
X541981Y341491D01*
G01X520875Y344333D02*
X521208Y344125D01*
X521583Y344000D01*
X521917D01*
X522250Y344125D01*
X522500Y344333D01*
X522625Y344625D01*
X522542Y344917D01*
X522333Y345167D01*
X521958Y345333D01*
X521458Y345417D01*
X521167Y345583D01*
X521042Y345875D01*
X521125Y346167D01*
X521333Y346375D01*
X521625Y346500D01*
X521917D01*
X522208Y346417D01*
X522458Y346208D01*
G01X525767Y346292D02*
X525517Y346417D01*
X525225Y346500D01*
X524892D01*
X524517Y346375D01*
X524225Y346167D01*
X524017Y345917D01*
X523850Y345500D01*
X523808Y345125D01*
X523892Y344750D01*
X524017Y344500D01*
X524267Y344250D01*
X524558Y344083D01*
X524850Y344000D01*
X525142D01*
X525433Y344083D01*
X525683Y344208D01*
X525892Y344375D01*
G01X527950Y344000D02*
Y346500D01*
X527450Y346000D01*
G01Y344000D02*
X528450D01*
G01X530258Y346083D02*
X530508Y346333D01*
X530800Y346458D01*
X531133Y346500D01*
X531550Y346417D01*
X531842Y346208D01*
X531925Y345958D01*
X531883Y345708D01*
X531717Y345500D01*
X530883Y345083D01*
X530508Y344792D01*
X530258Y344375D01*
X530175Y344000D01*
X531925D01*
G01X533358Y345042D02*
X533650Y345333D01*
X533900Y345500D01*
X534233Y345583D01*
X534525Y345500D01*
X534733Y345333D01*
X534900Y345083D01*
X534942Y344792D01*
X534900Y344542D01*
X534733Y344292D01*
X534483Y344083D01*
X534192Y344000D01*
X533858Y344083D01*
X533567Y344333D01*
X533400Y344708D01*
X533358Y345125D01*
X533442Y345667D01*
X533567Y345958D01*
X533775Y346250D01*
X534067Y346458D01*
X534358Y346500D01*
X534650Y346417D01*
X534858Y346208D01*
G01X536458Y346083D02*
X536708Y346333D01*
X537000Y346458D01*
X537333Y346500D01*
X537750Y346417D01*
X538042Y346208D01*
X538125Y345958D01*
X538083Y345708D01*
X537917Y345500D01*
X537083Y345083D01*
X536708Y344792D01*
X536458Y344375D01*
X536375Y344000D01*
X538125D01*
G01X520875Y348333D02*
X521208Y348125D01*
X521583Y348000D01*
X521917D01*
X522250Y348125D01*
X522500Y348333D01*
X522625Y348625D01*
X522542Y348917D01*
X522333Y349167D01*
X521958Y349333D01*
X521458Y349417D01*
X521167Y349583D01*
X521042Y349875D01*
X521125Y350167D01*
X521333Y350375D01*
X521625Y350500D01*
X521917D01*
X522208Y350417D01*
X522458Y350208D01*
G01X525767Y350292D02*
X525517Y350417D01*
X525225Y350500D01*
X524892D01*
X524517Y350375D01*
X524225Y350167D01*
X524017Y349917D01*
X523850Y349500D01*
X523808Y349125D01*
X523892Y348750D01*
X524017Y348500D01*
X524267Y348250D01*
X524558Y348083D01*
X524850Y348000D01*
X525142D01*
X525433Y348083D01*
X525683Y348208D01*
X525892Y348375D01*
G01X527950Y348000D02*
Y350500D01*
X527450Y350000D01*
G01Y348000D02*
X528450D01*
G01X530258Y350083D02*
X530508Y350333D01*
X530800Y350458D01*
X531133Y350500D01*
X531550Y350417D01*
X531842Y350208D01*
X531925Y349958D01*
X531883Y349708D01*
X531717Y349500D01*
X530883Y349083D01*
X530508Y348792D01*
X530258Y348375D01*
X530175Y348000D01*
X531925D01*
G01X533358Y349042D02*
X533650Y349333D01*
X533900Y349500D01*
X534233Y349583D01*
X534525Y349500D01*
X534733Y349333D01*
X534900Y349083D01*
X534942Y348792D01*
X534900Y348542D01*
X534733Y348292D01*
X534483Y348083D01*
X534192Y348000D01*
X533858Y348083D01*
X533567Y348333D01*
X533400Y348708D01*
X533358Y349125D01*
X533442Y349667D01*
X533567Y349958D01*
X533775Y350250D01*
X534067Y350458D01*
X534358Y350500D01*
X534650Y350417D01*
X534858Y350208D01*
G01X536333Y348500D02*
X536583Y348208D01*
X536917Y348042D01*
X537292Y348000D01*
X537625Y348042D01*
X537958Y348250D01*
X538167Y348500D01*
X538208Y348750D01*
X538125Y349042D01*
X537833Y349250D01*
X537542Y349333D01*
X537167D01*
G01X537542D02*
X537792Y349458D01*
X538000Y349667D01*
X538083Y349917D01*
X538000Y350167D01*
X537792Y350375D01*
X537417Y350500D01*
X537042Y350458D01*
X536667Y350292D01*
G01X520875Y352333D02*
X521208Y352125D01*
X521583Y352000D01*
X521917D01*
X522250Y352125D01*
X522500Y352333D01*
X522625Y352625D01*
X522542Y352917D01*
X522333Y353167D01*
X521958Y353333D01*
X521458Y353417D01*
X521167Y353583D01*
X521042Y353875D01*
X521125Y354167D01*
X521333Y354375D01*
X521625Y354500D01*
X521917D01*
X522208Y354417D01*
X522458Y354208D01*
G01X525767Y354292D02*
X525517Y354417D01*
X525225Y354500D01*
X524892D01*
X524517Y354375D01*
X524225Y354167D01*
X524017Y353917D01*
X523850Y353500D01*
X523808Y353125D01*
X523892Y352750D01*
X524017Y352500D01*
X524267Y352250D01*
X524558Y352083D01*
X524850Y352000D01*
X525142D01*
X525433Y352083D01*
X525683Y352208D01*
X525892Y352375D01*
G01X527950Y352000D02*
Y354500D01*
X527450Y354000D01*
G01Y352000D02*
X528450D01*
G01X530258Y354083D02*
X530508Y354333D01*
X530800Y354458D01*
X531133Y354500D01*
X531550Y354417D01*
X531842Y354208D01*
X531925Y353958D01*
X531883Y353708D01*
X531717Y353500D01*
X530883Y353083D01*
X530508Y352792D01*
X530258Y352375D01*
X530175Y352000D01*
X531925D01*
G01X533358Y353042D02*
X533650Y353333D01*
X533900Y353500D01*
X534233Y353583D01*
X534525Y353500D01*
X534733Y353333D01*
X534900Y353083D01*
X534942Y352792D01*
X534900Y352542D01*
X534733Y352292D01*
X534483Y352083D01*
X534192Y352000D01*
X533858Y352083D01*
X533567Y352333D01*
X533400Y352708D01*
X533358Y353125D01*
X533442Y353667D01*
X533567Y353958D01*
X533775Y354250D01*
X534067Y354458D01*
X534358Y354500D01*
X534650Y354417D01*
X534858Y354208D01*
G01X537750Y352000D02*
Y354500D01*
X536208Y352708D01*
X538292D01*
G01X520875Y360333D02*
X521208Y360125D01*
X521583Y360000D01*
X521917D01*
X522250Y360125D01*
X522500Y360333D01*
X522625Y360625D01*
X522542Y360917D01*
X522333Y361167D01*
X521958Y361333D01*
X521458Y361417D01*
X521167Y361583D01*
X521042Y361875D01*
X521125Y362167D01*
X521333Y362375D01*
X521625Y362500D01*
X521917D01*
X522208Y362417D01*
X522458Y362208D01*
G01X525767Y362292D02*
X525517Y362417D01*
X525225Y362500D01*
X524892D01*
X524517Y362375D01*
X524225Y362167D01*
X524017Y361917D01*
X523850Y361500D01*
X523808Y361125D01*
X523892Y360750D01*
X524017Y360500D01*
X524267Y360250D01*
X524558Y360083D01*
X524850Y360000D01*
X525142D01*
X525433Y360083D01*
X525683Y360208D01*
X525892Y360375D01*
G01X527950Y360000D02*
Y362500D01*
X527450Y362000D01*
G01Y360000D02*
X528450D01*
G01X531050D02*
Y362500D01*
X530550Y362000D01*
G01Y360000D02*
X531550D01*
G01X534150Y362500D02*
X533817Y362417D01*
X533567Y362208D01*
X533400Y361958D01*
X533275Y361625D01*
X533233Y361250D01*
X533275Y360875D01*
X533400Y360542D01*
X533567Y360292D01*
X533817Y360083D01*
X534150Y360000D01*
X534483Y360083D01*
X534733Y360292D01*
X534900Y360542D01*
X535025Y360875D01*
X535067Y361250D01*
X535025Y361625D01*
X534900Y361958D01*
X534733Y362208D01*
X534483Y362417D01*
X534150Y362500D01*
G01X536458Y362083D02*
X536708Y362333D01*
X537000Y362458D01*
X537333Y362500D01*
X537750Y362417D01*
X538042Y362208D01*
X538125Y361958D01*
X538083Y361708D01*
X537917Y361500D01*
X537083Y361083D01*
X536708Y360792D01*
X536458Y360375D01*
X536375Y360000D01*
X538125D01*
G01X520875Y364333D02*
X521208Y364125D01*
X521583Y364000D01*
X521917D01*
X522250Y364125D01*
X522500Y364333D01*
X522625Y364625D01*
X522542Y364917D01*
X522333Y365167D01*
X521958Y365333D01*
X521458Y365417D01*
X521167Y365583D01*
X521042Y365875D01*
X521125Y366167D01*
X521333Y366375D01*
X521625Y366500D01*
X521917D01*
X522208Y366417D01*
X522458Y366208D01*
G01X525767Y366292D02*
X525517Y366417D01*
X525225Y366500D01*
X524892D01*
X524517Y366375D01*
X524225Y366167D01*
X524017Y365917D01*
X523850Y365500D01*
X523808Y365125D01*
X523892Y364750D01*
X524017Y364500D01*
X524267Y364250D01*
X524558Y364083D01*
X524850Y364000D01*
X525142D01*
X525433Y364083D01*
X525683Y364208D01*
X525892Y364375D01*
G01X527950Y364000D02*
Y366500D01*
X527450Y366000D01*
G01Y364000D02*
X528450D01*
G01X531050D02*
Y366500D01*
X530550Y366000D01*
G01Y364000D02*
X531550D01*
G01X534150Y366500D02*
X533817Y366417D01*
X533567Y366208D01*
X533400Y365958D01*
X533275Y365625D01*
X533233Y365250D01*
X533275Y364875D01*
X533400Y364542D01*
X533567Y364292D01*
X533817Y364083D01*
X534150Y364000D01*
X534483Y364083D01*
X534733Y364292D01*
X534900Y364542D01*
X535025Y364875D01*
X535067Y365250D01*
X535025Y365625D01*
X534900Y365958D01*
X534733Y366208D01*
X534483Y366417D01*
X534150Y366500D01*
G01X536333Y364500D02*
X536583Y364208D01*
X536917Y364042D01*
X537292Y364000D01*
X537625Y364042D01*
X537958Y364250D01*
X538167Y364500D01*
X538208Y364750D01*
X538125Y365042D01*
X537833Y365250D01*
X537542Y365333D01*
X537167D01*
G01X537542D02*
X537792Y365458D01*
X538000Y365667D01*
X538083Y365917D01*
X538000Y366167D01*
X537792Y366375D01*
X537417Y366500D01*
X537042Y366458D01*
X536667Y366292D01*
G01X520875Y368333D02*
X521208Y368125D01*
X521583Y368000D01*
X521917D01*
X522250Y368125D01*
X522500Y368333D01*
X522625Y368625D01*
X522542Y368917D01*
X522333Y369167D01*
X521958Y369333D01*
X521458Y369417D01*
X521167Y369583D01*
X521042Y369875D01*
X521125Y370167D01*
X521333Y370375D01*
X521625Y370500D01*
X521917D01*
X522208Y370417D01*
X522458Y370208D01*
G01X525767Y370292D02*
X525517Y370417D01*
X525225Y370500D01*
X524892D01*
X524517Y370375D01*
X524225Y370167D01*
X524017Y369917D01*
X523850Y369500D01*
X523808Y369125D01*
X523892Y368750D01*
X524017Y368500D01*
X524267Y368250D01*
X524558Y368083D01*
X524850Y368000D01*
X525142D01*
X525433Y368083D01*
X525683Y368208D01*
X525892Y368375D01*
G01X527950Y368000D02*
Y370500D01*
X527450Y370000D01*
G01Y368000D02*
X528450D01*
G01X531050D02*
Y370500D01*
X530550Y370000D01*
G01Y368000D02*
X531550D01*
G01X534150Y370500D02*
X533817Y370417D01*
X533567Y370208D01*
X533400Y369958D01*
X533275Y369625D01*
X533233Y369250D01*
X533275Y368875D01*
X533400Y368542D01*
X533567Y368292D01*
X533817Y368083D01*
X534150Y368000D01*
X534483Y368083D01*
X534733Y368292D01*
X534900Y368542D01*
X535025Y368875D01*
X535067Y369250D01*
X535025Y369625D01*
X534900Y369958D01*
X534733Y370208D01*
X534483Y370417D01*
X534150Y370500D01*
G01X537750Y368000D02*
Y370500D01*
X536208Y368708D01*
X538292D01*
G01X520875Y356333D02*
X521208Y356125D01*
X521583Y356000D01*
X521917D01*
X522250Y356125D01*
X522500Y356333D01*
X522625Y356625D01*
X522542Y356917D01*
X522333Y357167D01*
X521958Y357333D01*
X521458Y357417D01*
X521167Y357583D01*
X521042Y357875D01*
X521125Y358167D01*
X521333Y358375D01*
X521625Y358500D01*
X521917D01*
X522208Y358417D01*
X522458Y358208D01*
G01X525767Y358292D02*
X525517Y358417D01*
X525225Y358500D01*
X524892D01*
X524517Y358375D01*
X524225Y358167D01*
X524017Y357917D01*
X523850Y357500D01*
X523808Y357125D01*
X523892Y356750D01*
X524017Y356500D01*
X524267Y356250D01*
X524558Y356083D01*
X524850Y356000D01*
X525142D01*
X525433Y356083D01*
X525683Y356208D01*
X525892Y356375D01*
G01X527950Y356000D02*
Y358500D01*
X527450Y358000D01*
G01Y356000D02*
X528450D01*
G01X530258Y358083D02*
X530508Y358333D01*
X530800Y358458D01*
X531133Y358500D01*
X531550Y358417D01*
X531842Y358208D01*
X531925Y357958D01*
X531883Y357708D01*
X531717Y357500D01*
X530883Y357083D01*
X530508Y356792D01*
X530258Y356375D01*
X530175Y356000D01*
X531925D01*
G01X533358Y357042D02*
X533650Y357333D01*
X533900Y357500D01*
X534233Y357583D01*
X534525Y357500D01*
X534733Y357333D01*
X534900Y357083D01*
X534942Y356792D01*
X534900Y356542D01*
X534733Y356292D01*
X534483Y356083D01*
X534192Y356000D01*
X533858Y356083D01*
X533567Y356333D01*
X533400Y356708D01*
X533358Y357125D01*
X533442Y357667D01*
X533567Y357958D01*
X533775Y358250D01*
X534067Y358458D01*
X534358Y358500D01*
X534650Y358417D01*
X534858Y358208D01*
G01X536333Y356375D02*
X536583Y356167D01*
X536875Y356042D01*
X537250Y356000D01*
X537625Y356083D01*
X537917Y356250D01*
X538125Y356542D01*
X538167Y356875D01*
X538083Y357208D01*
X537875Y357417D01*
X537583Y357583D01*
X537292Y357625D01*
X537000Y357583D01*
X536625Y357417D01*
X536750Y358500D01*
X537875D01*
G01X520875Y372333D02*
X521208Y372125D01*
X521583Y372000D01*
X521917D01*
X522250Y372125D01*
X522500Y372333D01*
X522625Y372625D01*
X522542Y372917D01*
X522333Y373167D01*
X521958Y373333D01*
X521458Y373417D01*
X521167Y373583D01*
X521042Y373875D01*
X521125Y374167D01*
X521333Y374375D01*
X521625Y374500D01*
X521917D01*
X522208Y374417D01*
X522458Y374208D01*
G01X525767Y374292D02*
X525517Y374417D01*
X525225Y374500D01*
X524892D01*
X524517Y374375D01*
X524225Y374167D01*
X524017Y373917D01*
X523850Y373500D01*
X523808Y373125D01*
X523892Y372750D01*
X524017Y372500D01*
X524267Y372250D01*
X524558Y372083D01*
X524850Y372000D01*
X525142D01*
X525433Y372083D01*
X525683Y372208D01*
X525892Y372375D01*
G01X527950Y372000D02*
Y374500D01*
X527450Y374000D01*
G01Y372000D02*
X528450D01*
G01X531050D02*
Y374500D01*
X530550Y374000D01*
G01Y372000D02*
X531550D01*
G01X534150Y374500D02*
X533817Y374417D01*
X533567Y374208D01*
X533400Y373958D01*
X533275Y373625D01*
X533233Y373250D01*
X533275Y372875D01*
X533400Y372542D01*
X533567Y372292D01*
X533817Y372083D01*
X534150Y372000D01*
X534483Y372083D01*
X534733Y372292D01*
X534900Y372542D01*
X535025Y372875D01*
X535067Y373250D01*
X535025Y373625D01*
X534900Y373958D01*
X534733Y374208D01*
X534483Y374417D01*
X534150Y374500D01*
G01X536333Y372375D02*
X536583Y372167D01*
X536875Y372042D01*
X537250Y372000D01*
X537625Y372083D01*
X537917Y372250D01*
X538125Y372542D01*
X538167Y372875D01*
X538083Y373208D01*
X537875Y373417D01*
X537583Y373583D01*
X537292Y373625D01*
X537000Y373583D01*
X536625Y373417D01*
X536750Y374500D01*
X537875D01*
G01X516032Y392835D02*
X516240Y393168D01*
X516365Y393543D01*
Y393877D01*
X516240Y394210D01*
X516032Y394460D01*
X515740Y394585D01*
X515448Y394502D01*
X515198Y394293D01*
X515032Y393918D01*
X514948Y393418D01*
X514782Y393127D01*
X514490Y393002D01*
X514198Y393085D01*
X513990Y393293D01*
X513865Y393585D01*
Y393877D01*
X513948Y394168D01*
X514157Y394418D01*
G01X514073Y397727D02*
X513948Y397477D01*
X513865Y397185D01*
Y396852D01*
X513990Y396477D01*
X514198Y396185D01*
X514448Y395977D01*
X514865Y395810D01*
X515240Y395768D01*
X515615Y395852D01*
X515865Y395977D01*
X516115Y396227D01*
X516282Y396518D01*
X516365Y396810D01*
Y397102D01*
X516282Y397393D01*
X516157Y397643D01*
X515990Y397852D01*
G01X516365Y399910D02*
X513865D01*
X514365Y399410D01*
G01X516365D02*
Y400410D01*
G01X514282Y402218D02*
X514032Y402468D01*
X513907Y402760D01*
X513865Y403093D01*
X513948Y403510D01*
X514157Y403802D01*
X514407Y403885D01*
X514657Y403843D01*
X514865Y403677D01*
X515282Y402843D01*
X515573Y402468D01*
X515990Y402218D01*
X516365Y402135D01*
Y403885D01*
G01Y406027D02*
X515823Y406110D01*
X515365Y406235D01*
X514948Y406402D01*
X514490Y406610D01*
X513865Y406943D01*
Y405277D01*
G01X514282Y408418D02*
X514032Y408668D01*
X513907Y408960D01*
X513865Y409293D01*
X513948Y409710D01*
X514157Y410002D01*
X514407Y410085D01*
X514657Y410043D01*
X514865Y409877D01*
X515282Y409043D01*
X515573Y408668D01*
X515990Y408418D01*
X516365Y408335D01*
Y410085D01*
G01X528222Y392875D02*
X528430Y393208D01*
X528555Y393583D01*
Y393917D01*
X528430Y394250D01*
X528222Y394500D01*
X527930Y394625D01*
X527638Y394542D01*
X527388Y394333D01*
X527222Y393958D01*
X527138Y393458D01*
X526972Y393167D01*
X526680Y393042D01*
X526388Y393125D01*
X526180Y393333D01*
X526055Y393625D01*
Y393917D01*
X526138Y394208D01*
X526347Y394458D01*
G01X526263Y397767D02*
X526138Y397517D01*
X526055Y397225D01*
Y396892D01*
X526180Y396517D01*
X526388Y396225D01*
X526638Y396017D01*
X527055Y395850D01*
X527430Y395808D01*
X527805Y395892D01*
X528055Y396017D01*
X528305Y396267D01*
X528472Y396558D01*
X528555Y396850D01*
Y397142D01*
X528472Y397433D01*
X528347Y397683D01*
X528180Y397892D01*
G01X528555Y399950D02*
X526055D01*
X526555Y399450D01*
G01X528555D02*
Y400450D01*
G01X526472Y402258D02*
X526222Y402508D01*
X526097Y402800D01*
X526055Y403133D01*
X526138Y403550D01*
X526347Y403842D01*
X526597Y403925D01*
X526847Y403883D01*
X527055Y403717D01*
X527472Y402883D01*
X527763Y402508D01*
X528180Y402258D01*
X528555Y402175D01*
Y403925D01*
G01X527513Y405358D02*
X527222Y405650D01*
X527055Y405900D01*
X526972Y406233D01*
X527055Y406525D01*
X527222Y406733D01*
X527472Y406900D01*
X527763Y406942D01*
X528013Y406900D01*
X528263Y406733D01*
X528472Y406483D01*
X528555Y406192D01*
X528472Y405858D01*
X528222Y405567D01*
X527847Y405400D01*
X527430Y405358D01*
X526888Y405442D01*
X526597Y405567D01*
X526305Y405775D01*
X526097Y406067D01*
X526055Y406358D01*
X526138Y406650D01*
X526347Y406858D01*
G01X528263Y408542D02*
X528472Y408833D01*
X528555Y409167D01*
X528472Y409500D01*
X528222Y409792D01*
X527847Y410000D01*
X527472Y410083D01*
X527013D01*
X526638Y410000D01*
X526305Y409792D01*
X526138Y409542D01*
X526055Y409250D01*
X526138Y408917D01*
X526305Y408667D01*
X526555Y408500D01*
X526888Y408417D01*
X527180Y408500D01*
X527472Y408708D01*
X527638Y408958D01*
X527680Y409250D01*
X527597Y409583D01*
X527388Y409833D01*
X527013Y410083D01*
G01X524222Y392875D02*
X524430Y393208D01*
X524555Y393583D01*
Y393917D01*
X524430Y394250D01*
X524222Y394500D01*
X523930Y394625D01*
X523638Y394542D01*
X523388Y394333D01*
X523222Y393958D01*
X523138Y393458D01*
X522972Y393167D01*
X522680Y393042D01*
X522388Y393125D01*
X522180Y393333D01*
X522055Y393625D01*
Y393917D01*
X522138Y394208D01*
X522347Y394458D01*
G01X522263Y397767D02*
X522138Y397517D01*
X522055Y397225D01*
Y396892D01*
X522180Y396517D01*
X522388Y396225D01*
X522638Y396017D01*
X523055Y395850D01*
X523430Y395808D01*
X523805Y395892D01*
X524055Y396017D01*
X524305Y396267D01*
X524472Y396558D01*
X524555Y396850D01*
Y397142D01*
X524472Y397433D01*
X524347Y397683D01*
X524180Y397892D01*
G01X524555Y399950D02*
X522055D01*
X522555Y399450D01*
G01X524555D02*
Y400450D01*
G01X522472Y402258D02*
X522222Y402508D01*
X522097Y402800D01*
X522055Y403133D01*
X522138Y403550D01*
X522347Y403842D01*
X522597Y403925D01*
X522847Y403883D01*
X523055Y403717D01*
X523472Y402883D01*
X523763Y402508D01*
X524180Y402258D01*
X524555Y402175D01*
Y403925D01*
G01Y406067D02*
X524013Y406150D01*
X523555Y406275D01*
X523138Y406442D01*
X522680Y406650D01*
X522055Y406983D01*
Y405317D01*
G01Y409250D02*
X522138Y408917D01*
X522347Y408667D01*
X522597Y408500D01*
X522930Y408375D01*
X523305Y408333D01*
X523680Y408375D01*
X524013Y408500D01*
X524263Y408667D01*
X524472Y408917D01*
X524555Y409250D01*
X524472Y409583D01*
X524263Y409833D01*
X524013Y410000D01*
X523680Y410125D01*
X523305Y410167D01*
X522930Y410125D01*
X522597Y410000D01*
X522347Y409833D01*
X522138Y409583D01*
X522055Y409250D01*
G01X520222Y392875D02*
X520430Y393208D01*
X520555Y393583D01*
Y393917D01*
X520430Y394250D01*
X520222Y394500D01*
X519930Y394625D01*
X519638Y394542D01*
X519388Y394333D01*
X519222Y393958D01*
X519138Y393458D01*
X518972Y393167D01*
X518680Y393042D01*
X518388Y393125D01*
X518180Y393333D01*
X518055Y393625D01*
Y393917D01*
X518138Y394208D01*
X518347Y394458D01*
G01X518263Y397767D02*
X518138Y397517D01*
X518055Y397225D01*
Y396892D01*
X518180Y396517D01*
X518388Y396225D01*
X518638Y396017D01*
X519055Y395850D01*
X519430Y395808D01*
X519805Y395892D01*
X520055Y396017D01*
X520305Y396267D01*
X520472Y396558D01*
X520555Y396850D01*
Y397142D01*
X520472Y397433D01*
X520347Y397683D01*
X520180Y397892D01*
G01X520555Y399950D02*
X518055D01*
X518555Y399450D01*
G01X520555D02*
Y400450D01*
G01X518472Y402258D02*
X518222Y402508D01*
X518097Y402800D01*
X518055Y403133D01*
X518138Y403550D01*
X518347Y403842D01*
X518597Y403925D01*
X518847Y403883D01*
X519055Y403717D01*
X519472Y402883D01*
X519763Y402508D01*
X520180Y402258D01*
X520555Y402175D01*
Y403925D01*
G01Y406067D02*
X520013Y406150D01*
X519555Y406275D01*
X519138Y406442D01*
X518680Y406650D01*
X518055Y406983D01*
Y405317D01*
G01X520555Y409250D02*
X518055D01*
X518555Y408750D01*
G01X520555D02*
Y409750D01*
G01X523650Y985250D02*
X524483D01*
Y984500D01*
X524233Y984250D01*
X523942Y984083D01*
X523525Y984000D01*
X523108Y984083D01*
X522817Y984250D01*
X522567Y984500D01*
X522400Y984792D01*
X522317Y985125D01*
Y985417D01*
X522400Y985667D01*
X522567Y985958D01*
X522817Y986208D01*
X523067Y986375D01*
X523400Y986500D01*
X523692D01*
X524025Y986417D01*
X524275Y986250D01*
G01X525708Y984000D02*
Y986500D01*
X527292D01*
G01X526708Y985292D02*
X525708D01*
G01X529600Y984000D02*
Y986500D01*
X529100Y986000D01*
G01Y984000D02*
X530100D01*
G01X539667Y131375D02*
X539875Y131708D01*
X540000Y132083D01*
Y132417D01*
X539875Y132750D01*
X539667Y133000D01*
X539375Y133125D01*
X539083Y133042D01*
X538833Y132833D01*
X538667Y132458D01*
X538583Y131958D01*
X538417Y131667D01*
X538125Y131542D01*
X537833Y131625D01*
X537625Y131833D01*
X537500Y132125D01*
Y132417D01*
X537583Y132708D01*
X537792Y132958D01*
G01X537500Y135350D02*
X540000D01*
G01X537500Y134392D02*
Y136308D01*
G01X540000Y137617D02*
X537500D01*
Y138617D01*
X537625Y138950D01*
X537917Y139200D01*
X538250Y139283D01*
X538583Y139200D01*
X538833Y138992D01*
X538958Y138617D01*
Y137617D01*
G01X540000Y141550D02*
X537500D01*
X538000Y141050D01*
G01X540000D02*
Y142050D01*
G01Y144650D02*
X537500D01*
X538000Y144150D01*
G01X540000D02*
Y145150D01*
G01X538958Y146958D02*
X538667Y147250D01*
X538500Y147500D01*
X538417Y147833D01*
X538500Y148125D01*
X538667Y148333D01*
X538917Y148500D01*
X539208Y148542D01*
X539458Y148500D01*
X539708Y148333D01*
X539917Y148083D01*
X540000Y147792D01*
X539917Y147458D01*
X539667Y147167D01*
X539292Y147000D01*
X538875Y146958D01*
X538333Y147042D01*
X538042Y147167D01*
X537750Y147375D01*
X537542Y147667D01*
X537500Y147958D01*
X537583Y148250D01*
X537792Y148458D01*
G01X545167Y132925D02*
X545375Y133258D01*
X545500Y133633D01*
Y133967D01*
X545375Y134300D01*
X545167Y134550D01*
X544875Y134675D01*
X544583Y134592D01*
X544333Y134383D01*
X544167Y134008D01*
X544083Y133508D01*
X543917Y133217D01*
X543625Y133092D01*
X543333Y133175D01*
X543125Y133383D01*
X543000Y133675D01*
Y133967D01*
X543083Y134258D01*
X543292Y134508D01*
G01X545500Y136067D02*
X543000D01*
Y137108D01*
X543125Y137442D01*
X543292Y137650D01*
X543625Y137733D01*
X543958Y137650D01*
X544167Y137400D01*
X544292Y137108D01*
Y136067D01*
G01Y137108D02*
X545500Y137733D01*
G01X544458Y139208D02*
X544167Y139500D01*
X544000Y139750D01*
X543917Y140083D01*
X544000Y140375D01*
X544167Y140583D01*
X544417Y140750D01*
X544708Y140792D01*
X544958Y140750D01*
X545208Y140583D01*
X545417Y140333D01*
X545500Y140042D01*
X545417Y139708D01*
X545167Y139417D01*
X544792Y139250D01*
X544375Y139208D01*
X543833Y139292D01*
X543542Y139417D01*
X543250Y139625D01*
X543042Y139917D01*
X543000Y140208D01*
X543083Y140500D01*
X543292Y140708D01*
G01X545208Y142392D02*
X545417Y142683D01*
X545500Y143017D01*
X545417Y143350D01*
X545167Y143642D01*
X544792Y143850D01*
X544417Y143933D01*
X543958D01*
X543583Y143850D01*
X543250Y143642D01*
X543083Y143392D01*
X543000Y143100D01*
X543083Y142767D01*
X543250Y142517D01*
X543500Y142350D01*
X543833Y142267D01*
X544125Y142350D01*
X544417Y142558D01*
X544583Y142808D01*
X544625Y143100D01*
X544542Y143433D01*
X544333Y143683D01*
X543958Y143933D01*
G01X545000Y145283D02*
X545292Y145533D01*
X545458Y145867D01*
X545500Y146242D01*
X545458Y146575D01*
X545250Y146908D01*
X545000Y147117D01*
X544750Y147158D01*
X544458Y147075D01*
X544250Y146783D01*
X544167Y146492D01*
Y146117D01*
G01Y146492D02*
X544042Y146742D01*
X543833Y146950D01*
X543583Y147033D01*
X543333Y146950D01*
X543125Y146742D01*
X543000Y146367D01*
X543042Y145992D01*
X543208Y145617D01*
G01X542000Y149300D02*
X546000D01*
Y156700D01*
G01X530729Y172300D02*
X587329D01*
G01X530729Y239700D02*
Y172300D01*
G01X532429Y206000D02*
X530729Y204300D01*
G01Y207700D02*
X532429Y206000D01*
G01X539000Y285500D02*
X541000D01*
Y252500D01*
G01X587329Y239700D02*
X530729D01*
G01X538167Y249925D02*
X538375Y250258D01*
X538500Y250633D01*
Y250967D01*
X538375Y251300D01*
X538167Y251550D01*
X537875Y251675D01*
X537583Y251592D01*
X537333Y251383D01*
X537167Y251008D01*
X537083Y250508D01*
X536917Y250217D01*
X536625Y250092D01*
X536333Y250175D01*
X536125Y250383D01*
X536000Y250675D01*
Y250967D01*
X536083Y251258D01*
X536292Y251508D01*
G01X536000Y253900D02*
X538500D01*
G01X536000Y252942D02*
Y254858D01*
G01X538500Y256167D02*
X536000D01*
Y257167D01*
X536125Y257500D01*
X536417Y257750D01*
X536750Y257833D01*
X537083Y257750D01*
X537333Y257542D01*
X537458Y257167D01*
Y256167D01*
G01Y259308D02*
X537167Y259600D01*
X537000Y259850D01*
X536917Y260183D01*
X537000Y260475D01*
X537167Y260683D01*
X537417Y260850D01*
X537708Y260892D01*
X537958Y260850D01*
X538208Y260683D01*
X538417Y260433D01*
X538500Y260142D01*
X538417Y259808D01*
X538167Y259517D01*
X537792Y259350D01*
X537375Y259308D01*
X536833Y259392D01*
X536542Y259517D01*
X536250Y259725D01*
X536042Y260017D01*
X536000Y260308D01*
X536083Y260600D01*
X536292Y260808D01*
G01X536000Y263200D02*
X536083Y262867D01*
X536292Y262617D01*
X536542Y262450D01*
X536875Y262325D01*
X537250Y262283D01*
X537625Y262325D01*
X537958Y262450D01*
X538208Y262617D01*
X538417Y262867D01*
X538500Y263200D01*
X538417Y263533D01*
X538208Y263783D01*
X537958Y263950D01*
X537625Y264075D01*
X537250Y264117D01*
X536875Y264075D01*
X536542Y263950D01*
X536292Y263783D01*
X536083Y263533D01*
X536000Y263200D01*
G01X533667Y249925D02*
X533875Y250258D01*
X534000Y250633D01*
Y250967D01*
X533875Y251300D01*
X533667Y251550D01*
X533375Y251675D01*
X533083Y251592D01*
X532833Y251383D01*
X532667Y251008D01*
X532583Y250508D01*
X532417Y250217D01*
X532125Y250092D01*
X531833Y250175D01*
X531625Y250383D01*
X531500Y250675D01*
Y250967D01*
X531583Y251258D01*
X531792Y251508D01*
G01X531500Y253900D02*
X534000D01*
G01X531500Y252942D02*
Y254858D01*
G01X534000Y256167D02*
X531500D01*
Y257167D01*
X531625Y257500D01*
X531917Y257750D01*
X532250Y257833D01*
X532583Y257750D01*
X532833Y257542D01*
X532958Y257167D01*
Y256167D01*
G01X534000Y260600D02*
X531500D01*
X533292Y259058D01*
Y261142D01*
G01X534000Y263200D02*
X533958Y263492D01*
X533833Y263825D01*
X533625Y264033D01*
X533333Y264117D01*
X533042Y264033D01*
X532792Y263783D01*
X532667Y263408D01*
Y262992D01*
X532583Y262742D01*
X532375Y262533D01*
X532083Y262450D01*
X531792Y262575D01*
X531583Y262867D01*
X531500Y263200D01*
X531583Y263533D01*
X531792Y263825D01*
X532083Y263950D01*
X532375Y263867D01*
X532583Y263658D01*
X532667Y263408D01*
Y262992D01*
X532792Y262617D01*
X533042Y262367D01*
X533333Y262283D01*
X533625Y262367D01*
X533833Y262575D01*
X533958Y262908D01*
X534000Y263200D01*
G01X533596Y266325D02*
X533804Y266658D01*
X533929Y267033D01*
Y267367D01*
X533804Y267700D01*
X533596Y267950D01*
X533304Y268075D01*
X533012Y267992D01*
X532762Y267783D01*
X532596Y267408D01*
X532512Y266908D01*
X532346Y266617D01*
X532054Y266492D01*
X531762Y266575D01*
X531554Y266783D01*
X531429Y267075D01*
Y267367D01*
X531512Y267658D01*
X531721Y267908D01*
G01X533929Y269467D02*
X531429D01*
Y270508D01*
X531554Y270842D01*
X531721Y271050D01*
X532054Y271133D01*
X532387Y271050D01*
X532596Y270800D01*
X532721Y270508D01*
Y269467D01*
G01Y270508D02*
X533929Y271133D01*
G01Y273400D02*
X533887Y273692D01*
X533762Y274025D01*
X533554Y274233D01*
X533262Y274317D01*
X532971Y274233D01*
X532721Y273983D01*
X532596Y273608D01*
Y273192D01*
X532512Y272942D01*
X532304Y272733D01*
X532012Y272650D01*
X531721Y272775D01*
X531512Y273067D01*
X531429Y273400D01*
X531512Y273733D01*
X531721Y274025D01*
X532012Y274150D01*
X532304Y274067D01*
X532512Y273858D01*
X532596Y273608D01*
Y273192D01*
X532721Y272817D01*
X532971Y272567D01*
X533262Y272483D01*
X533554Y272567D01*
X533762Y272775D01*
X533887Y273108D01*
X533929Y273400D01*
G01X532887Y275708D02*
X532596Y276000D01*
X532429Y276250D01*
X532346Y276583D01*
X532429Y276875D01*
X532596Y277083D01*
X532846Y277250D01*
X533137Y277292D01*
X533387Y277250D01*
X533637Y277083D01*
X533846Y276833D01*
X533929Y276542D01*
X533846Y276208D01*
X533596Y275917D01*
X533221Y275750D01*
X532804Y275708D01*
X532262Y275792D01*
X531971Y275917D01*
X531679Y276125D01*
X531471Y276417D01*
X531429Y276708D01*
X531512Y277000D01*
X531721Y277208D01*
G01X533429Y278683D02*
X533721Y278933D01*
X533887Y279267D01*
X533929Y279642D01*
X533887Y279975D01*
X533679Y280308D01*
X533429Y280517D01*
X533179Y280558D01*
X532887Y280475D01*
X532679Y280183D01*
X532596Y279892D01*
Y279517D01*
G01Y279892D02*
X532471Y280142D01*
X532262Y280350D01*
X532012Y280433D01*
X531762Y280350D01*
X531554Y280142D01*
X531429Y279767D01*
X531471Y279392D01*
X531637Y279017D01*
G01X538096Y266325D02*
X538304Y266658D01*
X538429Y267033D01*
Y267367D01*
X538304Y267700D01*
X538096Y267950D01*
X537804Y268075D01*
X537512Y267992D01*
X537262Y267783D01*
X537096Y267408D01*
X537012Y266908D01*
X536846Y266617D01*
X536554Y266492D01*
X536262Y266575D01*
X536054Y266783D01*
X535929Y267075D01*
Y267367D01*
X536012Y267658D01*
X536221Y267908D01*
G01X538429Y269467D02*
X535929D01*
Y270508D01*
X536054Y270842D01*
X536221Y271050D01*
X536554Y271133D01*
X536887Y271050D01*
X537096Y270800D01*
X537221Y270508D01*
Y269467D01*
G01Y270508D02*
X538429Y271133D01*
G01X537387Y272608D02*
X537096Y272900D01*
X536929Y273150D01*
X536846Y273483D01*
X536929Y273775D01*
X537096Y273983D01*
X537346Y274150D01*
X537637Y274192D01*
X537887Y274150D01*
X538137Y273983D01*
X538346Y273733D01*
X538429Y273442D01*
X538346Y273108D01*
X538096Y272817D01*
X537721Y272650D01*
X537304Y272608D01*
X536762Y272692D01*
X536471Y272817D01*
X536179Y273025D01*
X535971Y273317D01*
X535929Y273608D01*
X536012Y273900D01*
X536221Y274108D01*
G01X537387Y275708D02*
X537096Y276000D01*
X536929Y276250D01*
X536846Y276583D01*
X536929Y276875D01*
X537096Y277083D01*
X537346Y277250D01*
X537637Y277292D01*
X537887Y277250D01*
X538137Y277083D01*
X538346Y276833D01*
X538429Y276542D01*
X538346Y276208D01*
X538096Y275917D01*
X537721Y275750D01*
X537304Y275708D01*
X536762Y275792D01*
X536471Y275917D01*
X536179Y276125D01*
X535971Y276417D01*
X535929Y276708D01*
X536012Y277000D01*
X536221Y277208D01*
G01X538429Y279600D02*
X535929D01*
X536429Y279100D01*
G01X538429D02*
Y280100D01*
G01X884684Y324250D02*
Y287250D01*
X532284D01*
Y324250D01*
X884684D01*
G01X540167Y392875D02*
X540375Y393208D01*
X540500Y393583D01*
Y393917D01*
X540375Y394250D01*
X540167Y394500D01*
X539875Y394625D01*
X539583Y394542D01*
X539333Y394333D01*
X539167Y393958D01*
X539083Y393458D01*
X538917Y393167D01*
X538625Y393042D01*
X538333Y393125D01*
X538125Y393333D01*
X538000Y393625D01*
Y393917D01*
X538083Y394208D01*
X538292Y394458D01*
G01X538208Y397767D02*
X538083Y397517D01*
X538000Y397225D01*
Y396892D01*
X538125Y396517D01*
X538333Y396225D01*
X538583Y396017D01*
X539000Y395850D01*
X539375Y395808D01*
X539750Y395892D01*
X540000Y396017D01*
X540250Y396267D01*
X540417Y396558D01*
X540500Y396850D01*
Y397142D01*
X540417Y397433D01*
X540292Y397683D01*
X540125Y397892D01*
G01X540500Y399950D02*
X538000D01*
X538500Y399450D01*
G01X540500D02*
Y400450D01*
G01X538417Y402258D02*
X538167Y402508D01*
X538042Y402800D01*
X538000Y403133D01*
X538083Y403550D01*
X538292Y403842D01*
X538542Y403925D01*
X538792Y403883D01*
X539000Y403717D01*
X539417Y402883D01*
X539708Y402508D01*
X540125Y402258D01*
X540500Y402175D01*
Y403925D01*
G01X539458Y405358D02*
X539167Y405650D01*
X539000Y405900D01*
X538917Y406233D01*
X539000Y406525D01*
X539167Y406733D01*
X539417Y406900D01*
X539708Y406942D01*
X539958Y406900D01*
X540208Y406733D01*
X540417Y406483D01*
X540500Y406192D01*
X540417Y405858D01*
X540167Y405567D01*
X539792Y405400D01*
X539375Y405358D01*
X538833Y405442D01*
X538542Y405567D01*
X538250Y405775D01*
X538042Y406067D01*
X538000Y406358D01*
X538083Y406650D01*
X538292Y406858D01*
G01X539458Y408458D02*
X539167Y408750D01*
X539000Y409000D01*
X538917Y409333D01*
X539000Y409625D01*
X539167Y409833D01*
X539417Y410000D01*
X539708Y410042D01*
X539958Y410000D01*
X540208Y409833D01*
X540417Y409583D01*
X540500Y409292D01*
X540417Y408958D01*
X540167Y408667D01*
X539792Y408500D01*
X539375Y408458D01*
X538833Y408542D01*
X538542Y408667D01*
X538250Y408875D01*
X538042Y409167D01*
X538000Y409458D01*
X538083Y409750D01*
X538292Y409958D01*
G01X536167Y392875D02*
X536375Y393208D01*
X536500Y393583D01*
Y393917D01*
X536375Y394250D01*
X536167Y394500D01*
X535875Y394625D01*
X535583Y394542D01*
X535333Y394333D01*
X535167Y393958D01*
X535083Y393458D01*
X534917Y393167D01*
X534625Y393042D01*
X534333Y393125D01*
X534125Y393333D01*
X534000Y393625D01*
Y393917D01*
X534083Y394208D01*
X534292Y394458D01*
G01X534208Y397767D02*
X534083Y397517D01*
X534000Y397225D01*
Y396892D01*
X534125Y396517D01*
X534333Y396225D01*
X534583Y396017D01*
X535000Y395850D01*
X535375Y395808D01*
X535750Y395892D01*
X536000Y396017D01*
X536250Y396267D01*
X536417Y396558D01*
X536500Y396850D01*
Y397142D01*
X536417Y397433D01*
X536292Y397683D01*
X536125Y397892D01*
G01X536500Y399950D02*
X534000D01*
X534500Y399450D01*
G01X536500D02*
Y400450D01*
G01X534417Y402258D02*
X534167Y402508D01*
X534042Y402800D01*
X534000Y403133D01*
X534083Y403550D01*
X534292Y403842D01*
X534542Y403925D01*
X534792Y403883D01*
X535000Y403717D01*
X535417Y402883D01*
X535708Y402508D01*
X536125Y402258D01*
X536500Y402175D01*
Y403925D01*
G01X535458Y405358D02*
X535167Y405650D01*
X535000Y405900D01*
X534917Y406233D01*
X535000Y406525D01*
X535167Y406733D01*
X535417Y406900D01*
X535708Y406942D01*
X535958Y406900D01*
X536208Y406733D01*
X536417Y406483D01*
X536500Y406192D01*
X536417Y405858D01*
X536167Y405567D01*
X535792Y405400D01*
X535375Y405358D01*
X534833Y405442D01*
X534542Y405567D01*
X534250Y405775D01*
X534042Y406067D01*
X534000Y406358D01*
X534083Y406650D01*
X534292Y406858D01*
G01X536500Y409167D02*
X535958Y409250D01*
X535500Y409375D01*
X535083Y409542D01*
X534625Y409750D01*
X534000Y410083D01*
Y408417D01*
G01X532222Y392875D02*
X532430Y393208D01*
X532555Y393583D01*
Y393917D01*
X532430Y394250D01*
X532222Y394500D01*
X531930Y394625D01*
X531638Y394542D01*
X531388Y394333D01*
X531222Y393958D01*
X531138Y393458D01*
X530972Y393167D01*
X530680Y393042D01*
X530388Y393125D01*
X530180Y393333D01*
X530055Y393625D01*
Y393917D01*
X530138Y394208D01*
X530347Y394458D01*
G01X530263Y397767D02*
X530138Y397517D01*
X530055Y397225D01*
Y396892D01*
X530180Y396517D01*
X530388Y396225D01*
X530638Y396017D01*
X531055Y395850D01*
X531430Y395808D01*
X531805Y395892D01*
X532055Y396017D01*
X532305Y396267D01*
X532472Y396558D01*
X532555Y396850D01*
Y397142D01*
X532472Y397433D01*
X532347Y397683D01*
X532180Y397892D01*
G01X532555Y399950D02*
X530055D01*
X530555Y399450D01*
G01X532555D02*
Y400450D01*
G01X530472Y402258D02*
X530222Y402508D01*
X530097Y402800D01*
X530055Y403133D01*
X530138Y403550D01*
X530347Y403842D01*
X530597Y403925D01*
X530847Y403883D01*
X531055Y403717D01*
X531472Y402883D01*
X531763Y402508D01*
X532180Y402258D01*
X532555Y402175D01*
Y403925D01*
G01X531513Y405358D02*
X531222Y405650D01*
X531055Y405900D01*
X530972Y406233D01*
X531055Y406525D01*
X531222Y406733D01*
X531472Y406900D01*
X531763Y406942D01*
X532013Y406900D01*
X532263Y406733D01*
X532472Y406483D01*
X532555Y406192D01*
X532472Y405858D01*
X532222Y405567D01*
X531847Y405400D01*
X531430Y405358D01*
X530888Y405442D01*
X530597Y405567D01*
X530305Y405775D01*
X530097Y406067D01*
X530055Y406358D01*
X530138Y406650D01*
X530347Y406858D01*
G01X532555Y409250D02*
X532513Y409542D01*
X532388Y409875D01*
X532180Y410083D01*
X531888Y410167D01*
X531597Y410083D01*
X531347Y409833D01*
X531222Y409458D01*
Y409042D01*
X531138Y408792D01*
X530930Y408583D01*
X530638Y408500D01*
X530347Y408625D01*
X530138Y408917D01*
X530055Y409250D01*
X530138Y409583D01*
X530347Y409875D01*
X530638Y410000D01*
X530930Y409917D01*
X531138Y409708D01*
X531222Y409458D01*
Y409042D01*
X531347Y408667D01*
X531597Y408417D01*
X531888Y408333D01*
X532180Y408417D01*
X532388Y408625D01*
X532513Y408958D01*
X532555Y409250D01*
G01X542375Y392333D02*
X542708Y392125D01*
X543083Y392000D01*
X543417D01*
X543750Y392125D01*
X544000Y392333D01*
X544125Y392625D01*
X544042Y392917D01*
X543833Y393167D01*
X543458Y393333D01*
X542958Y393417D01*
X542667Y393583D01*
X542542Y393875D01*
X542625Y394167D01*
X542833Y394375D01*
X543125Y394500D01*
X543417D01*
X543708Y394417D01*
X543958Y394208D01*
G01X547267Y394292D02*
X547017Y394417D01*
X546725Y394500D01*
X546392D01*
X546017Y394375D01*
X545725Y394167D01*
X545517Y393917D01*
X545350Y393500D01*
X545308Y393125D01*
X545392Y392750D01*
X545517Y392500D01*
X545767Y392250D01*
X546058Y392083D01*
X546350Y392000D01*
X546642D01*
X546933Y392083D01*
X547183Y392208D01*
X547392Y392375D01*
G01X549450Y392000D02*
Y394500D01*
X548950Y394000D01*
G01Y392000D02*
X549950D01*
G01X552550D02*
Y394500D01*
X552050Y394000D01*
G01Y392000D02*
X553050D01*
G01X554733Y392375D02*
X554983Y392167D01*
X555275Y392042D01*
X555650Y392000D01*
X556025Y392083D01*
X556317Y392250D01*
X556525Y392542D01*
X556567Y392875D01*
X556483Y393208D01*
X556275Y393417D01*
X555983Y393583D01*
X555692Y393625D01*
X555400Y393583D01*
X555025Y393417D01*
X555150Y394500D01*
X556275D01*
G01X558750Y392000D02*
X559042Y392042D01*
X559375Y392167D01*
X559583Y392375D01*
X559667Y392667D01*
X559583Y392958D01*
X559333Y393208D01*
X558958Y393333D01*
X558542D01*
X558292Y393417D01*
X558083Y393625D01*
X558000Y393917D01*
X558125Y394208D01*
X558417Y394417D01*
X558750Y394500D01*
X559083Y394417D01*
X559375Y394208D01*
X559500Y393917D01*
X559417Y393625D01*
X559208Y393417D01*
X558958Y393333D01*
X558542D01*
X558167Y393208D01*
X557917Y392958D01*
X557833Y392667D01*
X557917Y392375D01*
X558125Y392167D01*
X558458Y392042D01*
X558750Y392000D01*
G01X542375Y401333D02*
X542708Y401125D01*
X543083Y401000D01*
X543417D01*
X543750Y401125D01*
X544000Y401333D01*
X544125Y401625D01*
X544042Y401917D01*
X543833Y402167D01*
X543458Y402333D01*
X542958Y402417D01*
X542667Y402583D01*
X542542Y402875D01*
X542625Y403167D01*
X542833Y403375D01*
X543125Y403500D01*
X543417D01*
X543708Y403417D01*
X543958Y403208D01*
G01X547267Y403292D02*
X547017Y403417D01*
X546725Y403500D01*
X546392D01*
X546017Y403375D01*
X545725Y403167D01*
X545517Y402917D01*
X545350Y402500D01*
X545308Y402125D01*
X545392Y401750D01*
X545517Y401500D01*
X545767Y401250D01*
X546058Y401083D01*
X546350Y401000D01*
X546642D01*
X546933Y401083D01*
X547183Y401208D01*
X547392Y401375D01*
G01X549450Y401000D02*
Y403500D01*
X548950Y403000D01*
G01Y401000D02*
X549950D01*
G01X552550D02*
Y403500D01*
X552050Y403000D01*
G01Y401000D02*
X553050D01*
G01X554858Y402042D02*
X555150Y402333D01*
X555400Y402500D01*
X555733Y402583D01*
X556025Y402500D01*
X556233Y402333D01*
X556400Y402083D01*
X556442Y401792D01*
X556400Y401542D01*
X556233Y401292D01*
X555983Y401083D01*
X555692Y401000D01*
X555358Y401083D01*
X555067Y401333D01*
X554900Y401708D01*
X554858Y402125D01*
X554942Y402667D01*
X555067Y402958D01*
X555275Y403250D01*
X555567Y403458D01*
X555858Y403500D01*
X556150Y403417D01*
X556358Y403208D01*
G01X559250Y401000D02*
Y403500D01*
X557708Y401708D01*
X559792D01*
G01X542375Y388333D02*
X542708Y388125D01*
X543083Y388000D01*
X543417D01*
X543750Y388125D01*
X544000Y388333D01*
X544125Y388625D01*
X544042Y388917D01*
X543833Y389167D01*
X543458Y389333D01*
X542958Y389417D01*
X542667Y389583D01*
X542542Y389875D01*
X542625Y390167D01*
X542833Y390375D01*
X543125Y390500D01*
X543417D01*
X543708Y390417D01*
X543958Y390208D01*
G01X547267Y390292D02*
X547017Y390417D01*
X546725Y390500D01*
X546392D01*
X546017Y390375D01*
X545725Y390167D01*
X545517Y389917D01*
X545350Y389500D01*
X545308Y389125D01*
X545392Y388750D01*
X545517Y388500D01*
X545767Y388250D01*
X546058Y388083D01*
X546350Y388000D01*
X546642D01*
X546933Y388083D01*
X547183Y388208D01*
X547392Y388375D01*
G01X549450Y388000D02*
Y390500D01*
X548950Y390000D01*
G01Y388000D02*
X549950D01*
G01X552550D02*
Y390500D01*
X552050Y390000D01*
G01Y388000D02*
X553050D01*
G01X555567D02*
X555650Y388542D01*
X555775Y389000D01*
X555942Y389417D01*
X556150Y389875D01*
X556483Y390500D01*
X554817D01*
G01X557958Y389042D02*
X558250Y389333D01*
X558500Y389500D01*
X558833Y389583D01*
X559125Y389500D01*
X559333Y389333D01*
X559500Y389083D01*
X559542Y388792D01*
X559500Y388542D01*
X559333Y388292D01*
X559083Y388083D01*
X558792Y388000D01*
X558458Y388083D01*
X558167Y388333D01*
X558000Y388708D01*
X557958Y389125D01*
X558042Y389667D01*
X558167Y389958D01*
X558375Y390250D01*
X558667Y390458D01*
X558958Y390500D01*
X559250Y390417D01*
X559458Y390208D01*
G01X542375Y396833D02*
X542708Y396625D01*
X543083Y396500D01*
X543417D01*
X543750Y396625D01*
X544000Y396833D01*
X544125Y397125D01*
X544042Y397417D01*
X543833Y397667D01*
X543458Y397833D01*
X542958Y397917D01*
X542667Y398083D01*
X542542Y398375D01*
X542625Y398667D01*
X542833Y398875D01*
X543125Y399000D01*
X543417D01*
X543708Y398917D01*
X543958Y398708D01*
G01X547267Y398792D02*
X547017Y398917D01*
X546725Y399000D01*
X546392D01*
X546017Y398875D01*
X545725Y398667D01*
X545517Y398417D01*
X545350Y398000D01*
X545308Y397625D01*
X545392Y397250D01*
X545517Y397000D01*
X545767Y396750D01*
X546058Y396583D01*
X546350Y396500D01*
X546642D01*
X546933Y396583D01*
X547183Y396708D01*
X547392Y396875D01*
G01X549450Y396500D02*
Y399000D01*
X548950Y398500D01*
G01Y396500D02*
X549950D01*
G01X552550D02*
Y399000D01*
X552050Y398500D01*
G01Y396500D02*
X553050D01*
G01X555650D02*
X555942Y396542D01*
X556275Y396667D01*
X556483Y396875D01*
X556567Y397167D01*
X556483Y397458D01*
X556233Y397708D01*
X555858Y397833D01*
X555442D01*
X555192Y397917D01*
X554983Y398125D01*
X554900Y398417D01*
X555025Y398708D01*
X555317Y398917D01*
X555650Y399000D01*
X555983Y398917D01*
X556275Y398708D01*
X556400Y398417D01*
X556317Y398125D01*
X556108Y397917D01*
X555858Y397833D01*
X555442D01*
X555067Y397708D01*
X554817Y397458D01*
X554733Y397167D01*
X554817Y396875D01*
X555025Y396667D01*
X555358Y396542D01*
X555650Y396500D01*
G01X558750D02*
X559042Y396542D01*
X559375Y396667D01*
X559583Y396875D01*
X559667Y397167D01*
X559583Y397458D01*
X559333Y397708D01*
X558958Y397833D01*
X558542D01*
X558292Y397917D01*
X558083Y398125D01*
X558000Y398417D01*
X558125Y398708D01*
X558417Y398917D01*
X558750Y399000D01*
X559083Y398917D01*
X559375Y398708D01*
X559500Y398417D01*
X559417Y398125D01*
X559208Y397917D01*
X558958Y397833D01*
X558542D01*
X558167Y397708D01*
X557917Y397458D01*
X557833Y397167D01*
X557917Y396875D01*
X558125Y396667D01*
X558458Y396542D01*
X558750Y396500D01*
G01X560167Y132925D02*
X560375Y133258D01*
X560500Y133633D01*
Y133967D01*
X560375Y134300D01*
X560167Y134550D01*
X559875Y134675D01*
X559583Y134592D01*
X559333Y134383D01*
X559167Y134008D01*
X559083Y133508D01*
X558917Y133217D01*
X558625Y133092D01*
X558333Y133175D01*
X558125Y133383D01*
X558000Y133675D01*
Y133967D01*
X558083Y134258D01*
X558292Y134508D01*
G01X560500Y136067D02*
X558000D01*
Y137108D01*
X558125Y137442D01*
X558292Y137650D01*
X558625Y137733D01*
X558958Y137650D01*
X559167Y137400D01*
X559292Y137108D01*
Y136067D01*
G01Y137108D02*
X560500Y137733D01*
G01X559458Y139208D02*
X559167Y139500D01*
X559000Y139750D01*
X558917Y140083D01*
X559000Y140375D01*
X559167Y140583D01*
X559417Y140750D01*
X559708Y140792D01*
X559958Y140750D01*
X560208Y140583D01*
X560417Y140333D01*
X560500Y140042D01*
X560417Y139708D01*
X560167Y139417D01*
X559792Y139250D01*
X559375Y139208D01*
X558833Y139292D01*
X558542Y139417D01*
X558250Y139625D01*
X558042Y139917D01*
X558000Y140208D01*
X558083Y140500D01*
X558292Y140708D01*
G01X560208Y142392D02*
X560417Y142683D01*
X560500Y143017D01*
X560417Y143350D01*
X560167Y143642D01*
X559792Y143850D01*
X559417Y143933D01*
X558958D01*
X558583Y143850D01*
X558250Y143642D01*
X558083Y143392D01*
X558000Y143100D01*
X558083Y142767D01*
X558250Y142517D01*
X558500Y142350D01*
X558833Y142267D01*
X559125Y142350D01*
X559417Y142558D01*
X559583Y142808D01*
X559625Y143100D01*
X559542Y143433D01*
X559333Y143683D01*
X558958Y143933D01*
G01X558417Y145408D02*
X558167Y145658D01*
X558042Y145950D01*
X558000Y146283D01*
X558083Y146700D01*
X558292Y146992D01*
X558542Y147075D01*
X558792Y147033D01*
X559000Y146867D01*
X559417Y146033D01*
X559708Y145658D01*
X560125Y145408D01*
X560500Y145325D01*
Y147075D01*
G01X555167Y132925D02*
X555375Y133258D01*
X555500Y133633D01*
Y133967D01*
X555375Y134300D01*
X555167Y134550D01*
X554875Y134675D01*
X554583Y134592D01*
X554333Y134383D01*
X554167Y134008D01*
X554083Y133508D01*
X553917Y133217D01*
X553625Y133092D01*
X553333Y133175D01*
X553125Y133383D01*
X553000Y133675D01*
Y133967D01*
X553083Y134258D01*
X553292Y134508D01*
G01X555500Y136067D02*
X553000D01*
Y137108D01*
X553125Y137442D01*
X553292Y137650D01*
X553625Y137733D01*
X553958Y137650D01*
X554167Y137400D01*
X554292Y137108D01*
Y136067D01*
G01Y137108D02*
X555500Y137733D01*
G01X554458Y139208D02*
X554167Y139500D01*
X554000Y139750D01*
X553917Y140083D01*
X554000Y140375D01*
X554167Y140583D01*
X554417Y140750D01*
X554708Y140792D01*
X554958Y140750D01*
X555208Y140583D01*
X555417Y140333D01*
X555500Y140042D01*
X555417Y139708D01*
X555167Y139417D01*
X554792Y139250D01*
X554375Y139208D01*
X553833Y139292D01*
X553542Y139417D01*
X553250Y139625D01*
X553042Y139917D01*
X553000Y140208D01*
X553083Y140500D01*
X553292Y140708D01*
G01X555208Y142392D02*
X555417Y142683D01*
X555500Y143017D01*
X555417Y143350D01*
X555167Y143642D01*
X554792Y143850D01*
X554417Y143933D01*
X553958D01*
X553583Y143850D01*
X553250Y143642D01*
X553083Y143392D01*
X553000Y143100D01*
X553083Y142767D01*
X553250Y142517D01*
X553500Y142350D01*
X553833Y142267D01*
X554125Y142350D01*
X554417Y142558D01*
X554583Y142808D01*
X554625Y143100D01*
X554542Y143433D01*
X554333Y143683D01*
X553958Y143933D01*
G01X555500Y146700D02*
X553000D01*
X554792Y145158D01*
Y147242D01*
G01X550167Y132925D02*
X550375Y133258D01*
X550500Y133633D01*
Y133967D01*
X550375Y134300D01*
X550167Y134550D01*
X549875Y134675D01*
X549583Y134592D01*
X549333Y134383D01*
X549167Y134008D01*
X549083Y133508D01*
X548917Y133217D01*
X548625Y133092D01*
X548333Y133175D01*
X548125Y133383D01*
X548000Y133675D01*
Y133967D01*
X548083Y134258D01*
X548292Y134508D01*
G01X550500Y136067D02*
X548000D01*
Y137108D01*
X548125Y137442D01*
X548292Y137650D01*
X548625Y137733D01*
X548958Y137650D01*
X549167Y137400D01*
X549292Y137108D01*
Y136067D01*
G01Y137108D02*
X550500Y137733D01*
G01Y139917D02*
X549958Y140000D01*
X549500Y140125D01*
X549083Y140292D01*
X548625Y140500D01*
X548000Y140833D01*
Y139167D01*
G01Y143100D02*
X548083Y142767D01*
X548292Y142517D01*
X548542Y142350D01*
X548875Y142225D01*
X549250Y142183D01*
X549625Y142225D01*
X549958Y142350D01*
X550208Y142517D01*
X550417Y142767D01*
X550500Y143100D01*
X550417Y143433D01*
X550208Y143683D01*
X549958Y143850D01*
X549625Y143975D01*
X549250Y144017D01*
X548875Y143975D01*
X548542Y143850D01*
X548292Y143683D01*
X548083Y143433D01*
X548000Y143100D01*
G01X548417Y145408D02*
X548167Y145658D01*
X548042Y145950D01*
X548000Y146283D01*
X548083Y146700D01*
X548292Y146992D01*
X548542Y147075D01*
X548792Y147033D01*
X549000Y146867D01*
X549417Y146033D01*
X549708Y145658D01*
X550125Y145408D01*
X550500Y145325D01*
Y147075D01*
G01X557000Y149300D02*
X561000D01*
Y156700D01*
G01X552000Y149300D02*
X556000D01*
Y156700D01*
G01X551000D02*
X547000D01*
Y149300D01*
G01X554875Y256833D02*
X555208Y256625D01*
X555583Y256500D01*
X555917D01*
X556250Y256625D01*
X556500Y256833D01*
X556625Y257125D01*
X556542Y257417D01*
X556333Y257667D01*
X555958Y257833D01*
X555458Y257917D01*
X555167Y258083D01*
X555042Y258375D01*
X555125Y258667D01*
X555333Y258875D01*
X555625Y259000D01*
X555917D01*
X556208Y258917D01*
X556458Y258708D01*
G01X559767Y258792D02*
X559517Y258917D01*
X559225Y259000D01*
X558892D01*
X558517Y258875D01*
X558225Y258667D01*
X558017Y258417D01*
X557850Y258000D01*
X557808Y257625D01*
X557892Y257250D01*
X558017Y257000D01*
X558267Y256750D01*
X558558Y256583D01*
X558850Y256500D01*
X559142D01*
X559433Y256583D01*
X559683Y256708D01*
X559892Y256875D01*
G01X561950Y256500D02*
Y259000D01*
X561450Y258500D01*
G01Y256500D02*
X562450D01*
G01X565050Y259000D02*
X564717Y258917D01*
X564467Y258708D01*
X564300Y258458D01*
X564175Y258125D01*
X564133Y257750D01*
X564175Y257375D01*
X564300Y257042D01*
X564467Y256792D01*
X564717Y256583D01*
X565050Y256500D01*
X565383Y256583D01*
X565633Y256792D01*
X565800Y257042D01*
X565925Y257375D01*
X565967Y257750D01*
X565925Y258125D01*
X565800Y258458D01*
X565633Y258708D01*
X565383Y258917D01*
X565050Y259000D01*
G01X567442Y256792D02*
X567733Y256583D01*
X568067Y256500D01*
X568400Y256583D01*
X568692Y256833D01*
X568900Y257208D01*
X568983Y257583D01*
Y258042D01*
X568900Y258417D01*
X568692Y258750D01*
X568442Y258917D01*
X568150Y259000D01*
X567817Y258917D01*
X567567Y258750D01*
X567400Y258500D01*
X567317Y258167D01*
X567400Y257875D01*
X567608Y257583D01*
X567858Y257417D01*
X568150Y257375D01*
X568483Y257458D01*
X568733Y257667D01*
X568983Y258042D01*
G01X570542Y256792D02*
X570833Y256583D01*
X571167Y256500D01*
X571500Y256583D01*
X571792Y256833D01*
X572000Y257208D01*
X572083Y257583D01*
Y258042D01*
X572000Y258417D01*
X571792Y258750D01*
X571542Y258917D01*
X571250Y259000D01*
X570917Y258917D01*
X570667Y258750D01*
X570500Y258500D01*
X570417Y258167D01*
X570500Y257875D01*
X570708Y257583D01*
X570958Y257417D01*
X571250Y257375D01*
X571583Y257458D01*
X571833Y257667D01*
X572083Y258042D01*
G01X551055Y332700D02*
X547055D01*
Y325300D01*
G01X551055D02*
X555055D01*
Y332700D01*
G01Y325300D02*
X559055D01*
Y332700D01*
G01X550405Y352078D02*
Y344078D01*
X562355D01*
Y352078D01*
X550405D01*
G01X547000Y368300D02*
X549500D01*
G01X547000Y367342D02*
Y369258D01*
G01X549500Y370567D02*
X547000D01*
Y371567D01*
X547125Y371900D01*
X547417Y372150D01*
X547750Y372233D01*
X548083Y372150D01*
X548333Y371942D01*
X548458Y371567D01*
Y370567D01*
G01X549500Y374500D02*
X547000D01*
X547500Y374000D01*
G01X549500D02*
Y375000D01*
G01Y377517D02*
X548958Y377600D01*
X548500Y377725D01*
X548083Y377892D01*
X547625Y378100D01*
X547000Y378433D01*
Y376767D01*
G01Y380700D02*
X547083Y380367D01*
X547292Y380117D01*
X547542Y379950D01*
X547875Y379825D01*
X548250Y379783D01*
X548625Y379825D01*
X548958Y379950D01*
X549208Y380117D01*
X549417Y380367D01*
X549500Y380700D01*
X549417Y381033D01*
X549208Y381283D01*
X548958Y381450D01*
X548625Y381575D01*
X548250Y381617D01*
X547875Y381575D01*
X547542Y381450D01*
X547292Y381283D01*
X547083Y381033D01*
X547000Y380700D01*
G01X560955Y373600D02*
X556955D01*
Y366200D01*
G01Y373600D02*
X552955D01*
Y366200D01*
G01X559500Y375017D02*
X557000D01*
Y376058D01*
X557125Y376392D01*
X557292Y376600D01*
X557625Y376683D01*
X557958Y376600D01*
X558167Y376350D01*
X558292Y376058D01*
Y375017D01*
G01Y376058D02*
X559500Y376683D01*
G01X559125Y378033D02*
X559333Y378283D01*
X559458Y378575D01*
X559500Y378950D01*
X559417Y379325D01*
X559250Y379617D01*
X558958Y379825D01*
X558625Y379867D01*
X558292Y379783D01*
X558083Y379575D01*
X557917Y379283D01*
X557875Y378992D01*
X557917Y378700D01*
X558083Y378325D01*
X557000Y378450D01*
Y379575D01*
G01X559208Y381342D02*
X559417Y381633D01*
X559500Y381967D01*
X559417Y382300D01*
X559167Y382592D01*
X558792Y382800D01*
X558417Y382883D01*
X557958D01*
X557583Y382800D01*
X557250Y382592D01*
X557083Y382342D01*
X557000Y382050D01*
X557083Y381717D01*
X557250Y381467D01*
X557500Y381300D01*
X557833Y381217D01*
X558125Y381300D01*
X558417Y381508D01*
X558583Y381758D01*
X558625Y382050D01*
X558542Y382383D01*
X558333Y382633D01*
X557958Y382883D01*
G01X559000Y384233D02*
X559292Y384483D01*
X559458Y384817D01*
X559500Y385192D01*
X559458Y385525D01*
X559250Y385858D01*
X559000Y386067D01*
X558750Y386108D01*
X558458Y386025D01*
X558250Y385733D01*
X558167Y385442D01*
Y385067D01*
G01Y385442D02*
X558042Y385692D01*
X557833Y385900D01*
X557583Y385983D01*
X557333Y385900D01*
X557125Y385692D01*
X557000Y385317D01*
X557042Y384942D01*
X557208Y384567D01*
G01X555000Y375017D02*
X552500D01*
Y376058D01*
X552625Y376392D01*
X552792Y376600D01*
X553125Y376683D01*
X553458Y376600D01*
X553667Y376350D01*
X553792Y376058D01*
Y375017D01*
G01Y376058D02*
X555000Y376683D01*
G01X554625Y378033D02*
X554833Y378283D01*
X554958Y378575D01*
X555000Y378950D01*
X554917Y379325D01*
X554750Y379617D01*
X554458Y379825D01*
X554125Y379867D01*
X553792Y379783D01*
X553583Y379575D01*
X553417Y379283D01*
X553375Y378992D01*
X553417Y378700D01*
X553583Y378325D01*
X552500Y378450D01*
Y379575D01*
G01X554708Y381342D02*
X554917Y381633D01*
X555000Y381967D01*
X554917Y382300D01*
X554667Y382592D01*
X554292Y382800D01*
X553917Y382883D01*
X553458D01*
X553083Y382800D01*
X552750Y382592D01*
X552583Y382342D01*
X552500Y382050D01*
X552583Y381717D01*
X552750Y381467D01*
X553000Y381300D01*
X553333Y381217D01*
X553625Y381300D01*
X553917Y381508D01*
X554083Y381758D01*
X554125Y382050D01*
X554042Y382383D01*
X553833Y382633D01*
X553458Y382883D01*
G01X553958Y384358D02*
X553667Y384650D01*
X553500Y384900D01*
X553417Y385233D01*
X553500Y385525D01*
X553667Y385733D01*
X553917Y385900D01*
X554208Y385942D01*
X554458Y385900D01*
X554708Y385733D01*
X554917Y385483D01*
X555000Y385192D01*
X554917Y384858D01*
X554667Y384567D01*
X554292Y384400D01*
X553875Y384358D01*
X553333Y384442D01*
X553042Y384567D01*
X552750Y384775D01*
X552542Y385067D01*
X552500Y385358D01*
X552583Y385650D01*
X552792Y385858D01*
G01X543875Y431833D02*
X544208Y431625D01*
X544583Y431500D01*
X544917D01*
X545250Y431625D01*
X545500Y431833D01*
X545625Y432125D01*
X545542Y432417D01*
X545333Y432667D01*
X544958Y432833D01*
X544458Y432917D01*
X544167Y433083D01*
X544042Y433375D01*
X544125Y433667D01*
X544333Y433875D01*
X544625Y434000D01*
X544917D01*
X545208Y433917D01*
X545458Y433708D01*
G01X548767Y433792D02*
X548517Y433917D01*
X548225Y434000D01*
X547892D01*
X547517Y433875D01*
X547225Y433667D01*
X547017Y433417D01*
X546850Y433000D01*
X546808Y432625D01*
X546892Y432250D01*
X547017Y432000D01*
X547267Y431750D01*
X547558Y431583D01*
X547850Y431500D01*
X548142D01*
X548433Y431583D01*
X548683Y431708D01*
X548892Y431875D01*
G01X550950Y431500D02*
Y434000D01*
X550450Y433500D01*
G01Y431500D02*
X551450D01*
G01X554050D02*
Y434000D01*
X553550Y433500D01*
G01Y431500D02*
X554550D01*
G01X557067D02*
X557150Y432042D01*
X557275Y432500D01*
X557442Y432917D01*
X557650Y433375D01*
X557983Y434000D01*
X556317D01*
G01X560250Y431500D02*
Y434000D01*
X559750Y433500D01*
G01Y431500D02*
X560750D01*
G01X543875Y439833D02*
X544208Y439625D01*
X544583Y439500D01*
X544917D01*
X545250Y439625D01*
X545500Y439833D01*
X545625Y440125D01*
X545542Y440417D01*
X545333Y440667D01*
X544958Y440833D01*
X544458Y440917D01*
X544167Y441083D01*
X544042Y441375D01*
X544125Y441667D01*
X544333Y441875D01*
X544625Y442000D01*
X544917D01*
X545208Y441917D01*
X545458Y441708D01*
G01X548767Y441792D02*
X548517Y441917D01*
X548225Y442000D01*
X547892D01*
X547517Y441875D01*
X547225Y441667D01*
X547017Y441417D01*
X546850Y441000D01*
X546808Y440625D01*
X546892Y440250D01*
X547017Y440000D01*
X547267Y439750D01*
X547558Y439583D01*
X547850Y439500D01*
X548142D01*
X548433Y439583D01*
X548683Y439708D01*
X548892Y439875D01*
G01X550950Y439500D02*
Y442000D01*
X550450Y441500D01*
G01Y439500D02*
X551450D01*
G01X554050D02*
Y442000D01*
X553550Y441500D01*
G01Y439500D02*
X554550D01*
G01X557150D02*
X557442Y439542D01*
X557775Y439667D01*
X557983Y439875D01*
X558067Y440167D01*
X557983Y440458D01*
X557733Y440708D01*
X557358Y440833D01*
X556942D01*
X556692Y440917D01*
X556483Y441125D01*
X556400Y441417D01*
X556525Y441708D01*
X556817Y441917D01*
X557150Y442000D01*
X557483Y441917D01*
X557775Y441708D01*
X557900Y441417D01*
X557817Y441125D01*
X557608Y440917D01*
X557358Y440833D01*
X556942D01*
X556567Y440708D01*
X556317Y440458D01*
X556233Y440167D01*
X556317Y439875D01*
X556525Y439667D01*
X556858Y439542D01*
X557150Y439500D01*
G01X559542Y439792D02*
X559833Y439583D01*
X560167Y439500D01*
X560500Y439583D01*
X560792Y439833D01*
X561000Y440208D01*
X561083Y440583D01*
Y441042D01*
X561000Y441417D01*
X560792Y441750D01*
X560542Y441917D01*
X560250Y442000D01*
X559917Y441917D01*
X559667Y441750D01*
X559500Y441500D01*
X559417Y441167D01*
X559500Y440875D01*
X559708Y440583D01*
X559958Y440417D01*
X560250Y440375D01*
X560583Y440458D01*
X560833Y440667D01*
X561083Y441042D01*
G01X568039Y29067D02*
X565539D01*
Y30108D01*
X565664Y30442D01*
X565831Y30650D01*
X566164Y30733D01*
X566497Y30650D01*
X566706Y30400D01*
X566831Y30108D01*
Y29067D01*
G01Y30108D02*
X568039Y30733D01*
G01X567539Y32167D02*
X567789Y32375D01*
X567956Y32625D01*
X568039Y32917D01*
X567956Y33250D01*
X567789Y33500D01*
X567539Y33750D01*
X567206Y33833D01*
X565539D01*
G01X568039Y36100D02*
X565539D01*
X566039Y35600D01*
G01X568039D02*
Y36600D01*
G01X569767Y58792D02*
X569517Y58917D01*
X569225Y59000D01*
X568892D01*
X568517Y58875D01*
X568225Y58667D01*
X568017Y58417D01*
X567850Y58000D01*
X567808Y57625D01*
X567892Y57250D01*
X568017Y57000D01*
X568267Y56750D01*
X568558Y56583D01*
X568850Y56500D01*
X569142D01*
X569433Y56583D01*
X569683Y56708D01*
X569892Y56875D01*
G01X571033Y57000D02*
X571283Y56708D01*
X571617Y56542D01*
X571992Y56500D01*
X572325Y56542D01*
X572658Y56750D01*
X572867Y57000D01*
X572908Y57250D01*
X572825Y57542D01*
X572533Y57750D01*
X572242Y57833D01*
X571867D01*
G01X572242D02*
X572492Y57958D01*
X572700Y58167D01*
X572783Y58417D01*
X572700Y58667D01*
X572492Y58875D01*
X572117Y59000D01*
X571742Y58958D01*
X571367Y58792D01*
G01X574258Y58583D02*
X574508Y58833D01*
X574800Y58958D01*
X575133Y59000D01*
X575550Y58917D01*
X575842Y58708D01*
X575925Y58458D01*
X575883Y58208D01*
X575717Y58000D01*
X574883Y57583D01*
X574508Y57292D01*
X574258Y56875D01*
X574175Y56500D01*
X575925D01*
G01X578650D02*
Y59000D01*
X577108Y57208D01*
X579192D01*
G01X569767Y53792D02*
X569517Y53917D01*
X569225Y54000D01*
X568892D01*
X568517Y53875D01*
X568225Y53667D01*
X568017Y53417D01*
X567850Y53000D01*
X567808Y52625D01*
X567892Y52250D01*
X568017Y52000D01*
X568267Y51750D01*
X568558Y51583D01*
X568850Y51500D01*
X569142D01*
X569433Y51583D01*
X569683Y51708D01*
X569892Y51875D01*
G01X571033Y52000D02*
X571283Y51708D01*
X571617Y51542D01*
X571992Y51500D01*
X572325Y51542D01*
X572658Y51750D01*
X572867Y52000D01*
X572908Y52250D01*
X572825Y52542D01*
X572533Y52750D01*
X572242Y52833D01*
X571867D01*
G01X572242D02*
X572492Y52958D01*
X572700Y53167D01*
X572783Y53417D01*
X572700Y53667D01*
X572492Y53875D01*
X572117Y54000D01*
X571742Y53958D01*
X571367Y53792D01*
G01X574258Y53583D02*
X574508Y53833D01*
X574800Y53958D01*
X575133Y54000D01*
X575550Y53917D01*
X575842Y53708D01*
X575925Y53458D01*
X575883Y53208D01*
X575717Y53000D01*
X574883Y52583D01*
X574508Y52292D01*
X574258Y51875D01*
X574175Y51500D01*
X575925D01*
G01X577233Y51875D02*
X577483Y51667D01*
X577775Y51542D01*
X578150Y51500D01*
X578525Y51583D01*
X578817Y51750D01*
X579025Y52042D01*
X579067Y52375D01*
X578983Y52708D01*
X578775Y52917D01*
X578483Y53083D01*
X578192Y53125D01*
X577900Y53083D01*
X577525Y52917D01*
X577650Y54000D01*
X578775D01*
G01X570167Y129875D02*
X570375Y130208D01*
X570500Y130583D01*
Y130917D01*
X570375Y131250D01*
X570167Y131500D01*
X569875Y131625D01*
X569583Y131542D01*
X569333Y131333D01*
X569167Y130958D01*
X569083Y130458D01*
X568917Y130167D01*
X568625Y130042D01*
X568333Y130125D01*
X568125Y130333D01*
X568000Y130625D01*
Y130917D01*
X568083Y131208D01*
X568292Y131458D01*
G01X568000Y133850D02*
X570500D01*
G01X568000Y132892D02*
Y134808D01*
G01X570500Y136117D02*
X568000D01*
Y137117D01*
X568125Y137450D01*
X568417Y137700D01*
X568750Y137783D01*
X569083Y137700D01*
X569333Y137492D01*
X569458Y137117D01*
Y136117D01*
G01X570500Y140050D02*
X568000D01*
X568500Y139550D01*
G01X570500D02*
Y140550D01*
G01Y143150D02*
X568000D01*
X568500Y142650D01*
G01X570500D02*
Y143650D01*
G01X570208Y145542D02*
X570417Y145833D01*
X570500Y146167D01*
X570417Y146500D01*
X570167Y146792D01*
X569792Y147000D01*
X569417Y147083D01*
X568958D01*
X568583Y147000D01*
X568250Y146792D01*
X568083Y146542D01*
X568000Y146250D01*
X568083Y145917D01*
X568250Y145667D01*
X568500Y145500D01*
X568833Y145417D01*
X569125Y145500D01*
X569417Y145708D01*
X569583Y145958D01*
X569625Y146250D01*
X569542Y146583D01*
X569333Y146833D01*
X568958Y147083D01*
G01X565167Y132925D02*
X565375Y133258D01*
X565500Y133633D01*
Y133967D01*
X565375Y134300D01*
X565167Y134550D01*
X564875Y134675D01*
X564583Y134592D01*
X564333Y134383D01*
X564167Y134008D01*
X564083Y133508D01*
X563917Y133217D01*
X563625Y133092D01*
X563333Y133175D01*
X563125Y133383D01*
X563000Y133675D01*
Y133967D01*
X563083Y134258D01*
X563292Y134508D01*
G01X565500Y136067D02*
X563000D01*
Y137108D01*
X563125Y137442D01*
X563292Y137650D01*
X563625Y137733D01*
X563958Y137650D01*
X564167Y137400D01*
X564292Y137108D01*
Y136067D01*
G01Y137108D02*
X565500Y137733D01*
G01Y139917D02*
X564958Y140000D01*
X564500Y140125D01*
X564083Y140292D01*
X563625Y140500D01*
X563000Y140833D01*
Y139167D01*
G01Y143100D02*
X563083Y142767D01*
X563292Y142517D01*
X563542Y142350D01*
X563875Y142225D01*
X564250Y142183D01*
X564625Y142225D01*
X564958Y142350D01*
X565208Y142517D01*
X565417Y142767D01*
X565500Y143100D01*
X565417Y143433D01*
X565208Y143683D01*
X564958Y143850D01*
X564625Y143975D01*
X564250Y144017D01*
X563875Y143975D01*
X563542Y143850D01*
X563292Y143683D01*
X563083Y143433D01*
X563000Y143100D01*
G01X565000Y145283D02*
X565292Y145533D01*
X565458Y145867D01*
X565500Y146242D01*
X565458Y146575D01*
X565250Y146908D01*
X565000Y147117D01*
X564750Y147158D01*
X564458Y147075D01*
X564250Y146783D01*
X564167Y146492D01*
Y146117D01*
G01Y146492D02*
X564042Y146742D01*
X563833Y146950D01*
X563583Y147033D01*
X563333Y146950D01*
X563125Y146742D01*
X563000Y146367D01*
X563042Y145992D01*
X563208Y145617D01*
G01X577167Y143425D02*
X577375Y143758D01*
X577500Y144133D01*
Y144467D01*
X577375Y144800D01*
X577167Y145050D01*
X576875Y145175D01*
X576583Y145092D01*
X576333Y144883D01*
X576167Y144508D01*
X576083Y144008D01*
X575917Y143717D01*
X575625Y143592D01*
X575333Y143675D01*
X575125Y143883D01*
X575000Y144175D01*
Y144467D01*
X575083Y144758D01*
X575292Y145008D01*
G01X577500Y146567D02*
X575000D01*
Y147608D01*
X575125Y147942D01*
X575292Y148150D01*
X575625Y148233D01*
X575958Y148150D01*
X576167Y147900D01*
X576292Y147608D01*
Y146567D01*
G01Y147608D02*
X577500Y148233D01*
G01Y150417D02*
X576958Y150500D01*
X576500Y150625D01*
X576083Y150792D01*
X575625Y151000D01*
X575000Y151333D01*
Y149667D01*
G01Y153600D02*
X575083Y153267D01*
X575292Y153017D01*
X575542Y152850D01*
X575875Y152725D01*
X576250Y152683D01*
X576625Y152725D01*
X576958Y152850D01*
X577208Y153017D01*
X577417Y153267D01*
X577500Y153600D01*
X577417Y153933D01*
X577208Y154183D01*
X576958Y154350D01*
X576625Y154475D01*
X576250Y154517D01*
X575875Y154475D01*
X575542Y154350D01*
X575292Y154183D01*
X575083Y153933D01*
X575000Y153600D01*
G01X577500Y156700D02*
X575000D01*
X575500Y156200D01*
G01X577500D02*
Y157200D01*
G01X573000Y156700D02*
X569000D01*
Y149300D01*
G01X562000D02*
X566000D01*
Y156700D01*
G01X565555Y348433D02*
X567347D01*
X567722Y348600D01*
X567972Y348933D01*
X568055Y349350D01*
X567972Y349767D01*
X567722Y350100D01*
X567347Y350267D01*
X565555D01*
G01X568055Y352450D02*
X565555D01*
X566055Y351950D01*
G01X568055D02*
Y352950D01*
G01X567555Y354633D02*
X567847Y354883D01*
X568013Y355217D01*
X568055Y355592D01*
X568013Y355925D01*
X567805Y356258D01*
X567555Y356467D01*
X567305Y356508D01*
X567013Y356425D01*
X566805Y356133D01*
X566722Y355842D01*
Y355467D01*
G01Y355842D02*
X566597Y356092D01*
X566388Y356300D01*
X566138Y356383D01*
X565888Y356300D01*
X565680Y356092D01*
X565555Y355717D01*
X565597Y355342D01*
X565763Y354967D01*
G01X567680Y357733D02*
X567888Y357983D01*
X568013Y358275D01*
X568055Y358650D01*
X567972Y359025D01*
X567805Y359317D01*
X567513Y359525D01*
X567180Y359567D01*
X566847Y359483D01*
X566638Y359275D01*
X566472Y358983D01*
X566430Y358692D01*
X566472Y358400D01*
X566638Y358025D01*
X565555Y358150D01*
Y359275D01*
G01X562355Y345928D02*
X560355Y347928D01*
X562355Y349928D01*
G01X573300Y361000D02*
Y354800D01*
X585700D01*
Y361000D01*
G01Y367000D02*
Y373200D01*
X573300D01*
Y367000D01*
G01X567500Y386700D02*
X561300D01*
Y374300D01*
X567500D01*
G01X573500D02*
X579700D01*
Y386700D01*
X573500D01*
G01X567500Y400200D02*
X561300D01*
Y387800D01*
X567500D01*
G01X573500D02*
X579700D01*
Y400200D01*
X573500D01*
G01X567500Y413700D02*
X561300D01*
Y401300D01*
X567500D01*
G01X573500D02*
X579700D01*
Y413700D01*
X573500D01*
G01X567500Y427200D02*
X561300D01*
Y414800D01*
X567500D01*
G01X573500D02*
X579700D01*
Y427200D01*
X573500D01*
G01X583921Y-8866D02*
Y39234D01*
X580421D01*
Y49034D01*
X583921D01*
Y88134D01*
X655921D01*
Y49034D01*
X659421D01*
Y39234D01*
X655921D01*
Y-8866D01*
X583921D01*
G01X587329Y172300D02*
Y239700D01*
G01X591975Y232333D02*
X592308Y232125D01*
X592683Y232000D01*
X593017D01*
X593350Y232125D01*
X593600Y232333D01*
X593725Y232625D01*
X593642Y232917D01*
X593433Y233167D01*
X593058Y233333D01*
X592558Y233417D01*
X592267Y233583D01*
X592142Y233875D01*
X592225Y234167D01*
X592433Y234375D01*
X592725Y234500D01*
X593017D01*
X593308Y234417D01*
X593558Y234208D01*
G01X595033Y234500D02*
Y232708D01*
X595200Y232333D01*
X595533Y232083D01*
X595950Y232000D01*
X596367Y232083D01*
X596700Y232333D01*
X596867Y232708D01*
Y234500D01*
G01X598133Y232375D02*
X598383Y232167D01*
X598675Y232042D01*
X599050Y232000D01*
X599425Y232083D01*
X599717Y232250D01*
X599925Y232542D01*
X599967Y232875D01*
X599883Y233208D01*
X599675Y233417D01*
X599383Y233583D01*
X599092Y233625D01*
X598800Y233583D01*
X598425Y233417D01*
X598550Y234500D01*
X599675D01*
G01X602150Y232000D02*
X602442Y232042D01*
X602775Y232167D01*
X602983Y232375D01*
X603067Y232667D01*
X602983Y232958D01*
X602733Y233208D01*
X602358Y233333D01*
X601942D01*
X601692Y233417D01*
X601483Y233625D01*
X601400Y233917D01*
X601525Y234208D01*
X601817Y234417D01*
X602150Y234500D01*
X602483Y234417D01*
X602775Y234208D01*
X602900Y233917D01*
X602817Y233625D01*
X602608Y233417D01*
X602358Y233333D01*
X601942D01*
X601567Y233208D01*
X601317Y232958D01*
X601233Y232667D01*
X601317Y232375D01*
X601525Y232167D01*
X601858Y232042D01*
X602150Y232000D01*
G01X591667Y250925D02*
X591875Y251258D01*
X592000Y251633D01*
Y251967D01*
X591875Y252300D01*
X591667Y252550D01*
X591375Y252675D01*
X591083Y252592D01*
X590833Y252383D01*
X590667Y252008D01*
X590583Y251508D01*
X590417Y251217D01*
X590125Y251092D01*
X589833Y251175D01*
X589625Y251383D01*
X589500Y251675D01*
Y251967D01*
X589583Y252258D01*
X589792Y252508D01*
G01X592000Y254067D02*
X589500D01*
Y255108D01*
X589625Y255442D01*
X589792Y255650D01*
X590125Y255733D01*
X590458Y255650D01*
X590667Y255400D01*
X590792Y255108D01*
Y254067D01*
G01Y255108D02*
X592000Y255733D01*
G01X590958Y257208D02*
X590667Y257500D01*
X590500Y257750D01*
X590417Y258083D01*
X590500Y258375D01*
X590667Y258583D01*
X590917Y258750D01*
X591208Y258792D01*
X591458Y258750D01*
X591708Y258583D01*
X591917Y258333D01*
X592000Y258042D01*
X591917Y257708D01*
X591667Y257417D01*
X591292Y257250D01*
X590875Y257208D01*
X590333Y257292D01*
X590042Y257417D01*
X589750Y257625D01*
X589542Y257917D01*
X589500Y258208D01*
X589583Y258500D01*
X589792Y258708D01*
G01X591708Y260392D02*
X591917Y260683D01*
X592000Y261017D01*
X591917Y261350D01*
X591667Y261642D01*
X591292Y261850D01*
X590917Y261933D01*
X590458D01*
X590083Y261850D01*
X589750Y261642D01*
X589583Y261392D01*
X589500Y261100D01*
X589583Y260767D01*
X589750Y260517D01*
X590000Y260350D01*
X590333Y260267D01*
X590625Y260350D01*
X590917Y260558D01*
X591083Y260808D01*
X591125Y261100D01*
X591042Y261433D01*
X590833Y261683D01*
X590458Y261933D01*
G01X590958Y263408D02*
X590667Y263700D01*
X590500Y263950D01*
X590417Y264283D01*
X590500Y264575D01*
X590667Y264783D01*
X590917Y264950D01*
X591208Y264992D01*
X591458Y264950D01*
X591708Y264783D01*
X591917Y264533D01*
X592000Y264242D01*
X591917Y263908D01*
X591667Y263617D01*
X591292Y263450D01*
X590875Y263408D01*
X590333Y263492D01*
X590042Y263617D01*
X589750Y263825D01*
X589542Y264117D01*
X589500Y264408D01*
X589583Y264700D01*
X589792Y264908D01*
G01X583000Y250800D02*
X587000D01*
Y258200D01*
G01X586208Y270767D02*
X586083Y270517D01*
X586000Y270225D01*
Y269892D01*
X586125Y269517D01*
X586333Y269225D01*
X586583Y269017D01*
X587000Y268850D01*
X587375Y268808D01*
X587750Y268892D01*
X588000Y269017D01*
X588250Y269267D01*
X588417Y269558D01*
X588500Y269850D01*
Y270142D01*
X588417Y270433D01*
X588292Y270683D01*
X588125Y270892D01*
G01X586417Y272158D02*
X586167Y272408D01*
X586042Y272700D01*
X586000Y273033D01*
X586083Y273450D01*
X586292Y273742D01*
X586542Y273825D01*
X586792Y273783D01*
X587000Y273617D01*
X587417Y272783D01*
X587708Y272408D01*
X588125Y272158D01*
X588500Y272075D01*
Y273825D01*
G01Y275967D02*
X587958Y276050D01*
X587500Y276175D01*
X587083Y276342D01*
X586625Y276550D01*
X586000Y276883D01*
Y275217D01*
G01Y279150D02*
X586083Y278817D01*
X586292Y278567D01*
X586542Y278400D01*
X586875Y278275D01*
X587250Y278233D01*
X587625Y278275D01*
X587958Y278400D01*
X588208Y278567D01*
X588417Y278817D01*
X588500Y279150D01*
X588417Y279483D01*
X588208Y279733D01*
X587958Y279900D01*
X587625Y280025D01*
X587250Y280067D01*
X586875Y280025D01*
X586542Y279900D01*
X586292Y279733D01*
X586083Y279483D01*
X586000Y279150D01*
G01X586555Y327017D02*
X584055D01*
Y328058D01*
X584180Y328392D01*
X584347Y328600D01*
X584680Y328683D01*
X585013Y328600D01*
X585222Y328350D01*
X585347Y328058D01*
Y327017D01*
G01Y328058D02*
X586555Y328683D01*
G01Y330950D02*
X584055D01*
X584555Y330450D01*
G01X586555D02*
Y331450D01*
G01X585513Y333258D02*
X585222Y333550D01*
X585055Y333800D01*
X584972Y334133D01*
X585055Y334425D01*
X585222Y334633D01*
X585472Y334800D01*
X585763Y334842D01*
X586013Y334800D01*
X586263Y334633D01*
X586472Y334383D01*
X586555Y334092D01*
X586472Y333758D01*
X586222Y333467D01*
X585847Y333300D01*
X585430Y333258D01*
X584888Y333342D01*
X584597Y333467D01*
X584305Y333675D01*
X584097Y333967D01*
X584055Y334258D01*
X584138Y334550D01*
X584347Y334758D01*
G01X585513Y336358D02*
X585222Y336650D01*
X585055Y336900D01*
X584972Y337233D01*
X585055Y337525D01*
X585222Y337733D01*
X585472Y337900D01*
X585763Y337942D01*
X586013Y337900D01*
X586263Y337733D01*
X586472Y337483D01*
X586555Y337192D01*
X586472Y336858D01*
X586222Y336567D01*
X585847Y336400D01*
X585430Y336358D01*
X584888Y336442D01*
X584597Y336567D01*
X584305Y336775D01*
X584097Y337067D01*
X584055Y337358D01*
X584138Y337650D01*
X584347Y337858D01*
G01X590555Y327017D02*
X588055D01*
Y328058D01*
X588180Y328392D01*
X588347Y328600D01*
X588680Y328683D01*
X589013Y328600D01*
X589222Y328350D01*
X589347Y328058D01*
Y327017D01*
G01Y328058D02*
X590555Y328683D01*
G01Y330950D02*
X588055D01*
X588555Y330450D01*
G01X590555D02*
Y331450D01*
G01X589513Y333258D02*
X589222Y333550D01*
X589055Y333800D01*
X588972Y334133D01*
X589055Y334425D01*
X589222Y334633D01*
X589472Y334800D01*
X589763Y334842D01*
X590013Y334800D01*
X590263Y334633D01*
X590472Y334383D01*
X590555Y334092D01*
X590472Y333758D01*
X590222Y333467D01*
X589847Y333300D01*
X589430Y333258D01*
X588888Y333342D01*
X588597Y333467D01*
X588305Y333675D01*
X588097Y333967D01*
X588055Y334258D01*
X588138Y334550D01*
X588347Y334758D01*
G01X590555Y337067D02*
X590013Y337150D01*
X589555Y337275D01*
X589138Y337442D01*
X588680Y337650D01*
X588055Y337983D01*
Y336317D01*
G01X594555Y327017D02*
X592055D01*
Y328058D01*
X592180Y328392D01*
X592347Y328600D01*
X592680Y328683D01*
X593013Y328600D01*
X593222Y328350D01*
X593347Y328058D01*
Y327017D01*
G01Y328058D02*
X594555Y328683D01*
G01X593513Y330158D02*
X593222Y330450D01*
X593055Y330700D01*
X592972Y331033D01*
X593055Y331325D01*
X593222Y331533D01*
X593472Y331700D01*
X593763Y331742D01*
X594013Y331700D01*
X594263Y331533D01*
X594472Y331283D01*
X594555Y330992D01*
X594472Y330658D01*
X594222Y330367D01*
X593847Y330200D01*
X593430Y330158D01*
X592888Y330242D01*
X592597Y330367D01*
X592305Y330575D01*
X592097Y330867D01*
X592055Y331158D01*
X592138Y331450D01*
X592347Y331658D01*
G01X594555Y334050D02*
X592055D01*
X592555Y333550D01*
G01X594555D02*
Y334550D01*
G01Y337150D02*
X592055D01*
X592555Y336650D01*
G01X594555D02*
Y337650D01*
G01X586800Y361000D02*
Y354800D01*
X599200D01*
Y361000D01*
G01Y367000D02*
Y373200D01*
X586800D01*
Y367000D01*
G01X592975Y460333D02*
X593308Y460125D01*
X593683Y460000D01*
X594017D01*
X594350Y460125D01*
X594600Y460333D01*
X594725Y460625D01*
X594642Y460917D01*
X594433Y461167D01*
X594058Y461333D01*
X593558Y461417D01*
X593267Y461583D01*
X593142Y461875D01*
X593225Y462167D01*
X593433Y462375D01*
X593725Y462500D01*
X594017D01*
X594308Y462417D01*
X594558Y462208D01*
G01X596117Y462500D02*
Y460000D01*
X597783D01*
G01X600050D02*
Y462500D01*
X599550Y462000D01*
G01Y460000D02*
X600550D01*
G01X602233Y460375D02*
X602483Y460167D01*
X602775Y460042D01*
X603150Y460000D01*
X603525Y460083D01*
X603817Y460250D01*
X604025Y460542D01*
X604067Y460875D01*
X603983Y461208D01*
X603775Y461417D01*
X603483Y461583D01*
X603192Y461625D01*
X602900Y461583D01*
X602525Y461417D01*
X602650Y462500D01*
X603775D01*
G01X592975Y465333D02*
X593308Y465125D01*
X593683Y465000D01*
X594017D01*
X594350Y465125D01*
X594600Y465333D01*
X594725Y465625D01*
X594642Y465917D01*
X594433Y466167D01*
X594058Y466333D01*
X593558Y466417D01*
X593267Y466583D01*
X593142Y466875D01*
X593225Y467167D01*
X593433Y467375D01*
X593725Y467500D01*
X594017D01*
X594308Y467417D01*
X594558Y467208D01*
G01X596117Y467500D02*
Y465000D01*
X597783D01*
G01X600050D02*
Y467500D01*
X599550Y467000D01*
G01Y465000D02*
X600550D01*
G01X602358Y466042D02*
X602650Y466333D01*
X602900Y466500D01*
X603233Y466583D01*
X603525Y466500D01*
X603733Y466333D01*
X603900Y466083D01*
X603942Y465792D01*
X603900Y465542D01*
X603733Y465292D01*
X603483Y465083D01*
X603192Y465000D01*
X602858Y465083D01*
X602567Y465333D01*
X602400Y465708D01*
X602358Y466125D01*
X602442Y466667D01*
X602567Y466958D01*
X602775Y467250D01*
X603067Y467458D01*
X603358Y467500D01*
X603650Y467417D01*
X603858Y467208D01*
G01X592873Y455949D02*
X593206Y455741D01*
X593581Y455616D01*
X593915D01*
X594248Y455741D01*
X594498Y455949D01*
X594623Y456241D01*
X594540Y456533D01*
X594331Y456783D01*
X593956Y456949D01*
X593456Y457033D01*
X593165Y457199D01*
X593040Y457491D01*
X593123Y457783D01*
X593331Y457991D01*
X593623Y458116D01*
X593915D01*
X594206Y458033D01*
X594456Y457824D01*
G01X596015Y458116D02*
Y455616D01*
X597681D01*
G01X599948D02*
Y458116D01*
X599448Y457616D01*
G01Y455616D02*
X600448D01*
G01X602340Y455908D02*
X602631Y455699D01*
X602965Y455616D01*
X603298Y455699D01*
X603590Y455949D01*
X603798Y456324D01*
X603881Y456699D01*
Y457158D01*
X603798Y457533D01*
X603590Y457866D01*
X603340Y458033D01*
X603048Y458116D01*
X602715Y458033D01*
X602465Y457866D01*
X602298Y457616D01*
X602215Y457283D01*
X602298Y456991D01*
X602506Y456699D01*
X602756Y456533D01*
X603048Y456491D01*
X603381Y456574D01*
X603631Y456783D01*
X603881Y457158D01*
G01X592975Y477333D02*
X593308Y477125D01*
X593683Y477000D01*
X594017D01*
X594350Y477125D01*
X594600Y477333D01*
X594725Y477625D01*
X594642Y477917D01*
X594433Y478167D01*
X594058Y478333D01*
X593558Y478417D01*
X593267Y478583D01*
X593142Y478875D01*
X593225Y479167D01*
X593433Y479375D01*
X593725Y479500D01*
X594017D01*
X594308Y479417D01*
X594558Y479208D01*
G01X596117Y479500D02*
Y477000D01*
X597783D01*
G01X600050D02*
Y479500D01*
X599550Y479000D01*
G01Y477000D02*
X600550D01*
G01X603067D02*
X603150Y477542D01*
X603275Y478000D01*
X603442Y478417D01*
X603650Y478875D01*
X603983Y479500D01*
X602317D01*
G01X592975Y473333D02*
X593308Y473125D01*
X593683Y473000D01*
X594017D01*
X594350Y473125D01*
X594600Y473333D01*
X594725Y473625D01*
X594642Y473917D01*
X594433Y474167D01*
X594058Y474333D01*
X593558Y474417D01*
X593267Y474583D01*
X593142Y474875D01*
X593225Y475167D01*
X593433Y475375D01*
X593725Y475500D01*
X594017D01*
X594308Y475417D01*
X594558Y475208D01*
G01X596117Y475500D02*
Y473000D01*
X597783D01*
G01X600050D02*
Y475500D01*
X599550Y475000D01*
G01Y473000D02*
X600550D01*
G01X603150D02*
X603442Y473042D01*
X603775Y473167D01*
X603983Y473375D01*
X604067Y473667D01*
X603983Y473958D01*
X603733Y474208D01*
X603358Y474333D01*
X602942D01*
X602692Y474417D01*
X602483Y474625D01*
X602400Y474917D01*
X602525Y475208D01*
X602817Y475417D01*
X603150Y475500D01*
X603483Y475417D01*
X603775Y475208D01*
X603900Y474917D01*
X603817Y474625D01*
X603608Y474417D01*
X603358Y474333D01*
X602942D01*
X602567Y474208D01*
X602317Y473958D01*
X602233Y473667D01*
X602317Y473375D01*
X602525Y473167D01*
X602858Y473042D01*
X603150Y473000D01*
G01X592975Y469333D02*
X593308Y469125D01*
X593683Y469000D01*
X594017D01*
X594350Y469125D01*
X594600Y469333D01*
X594725Y469625D01*
X594642Y469917D01*
X594433Y470167D01*
X594058Y470333D01*
X593558Y470417D01*
X593267Y470583D01*
X593142Y470875D01*
X593225Y471167D01*
X593433Y471375D01*
X593725Y471500D01*
X594017D01*
X594308Y471417D01*
X594558Y471208D01*
G01X596117Y471500D02*
Y469000D01*
X597783D01*
G01X599258Y471083D02*
X599508Y471333D01*
X599800Y471458D01*
X600133Y471500D01*
X600550Y471417D01*
X600842Y471208D01*
X600925Y470958D01*
X600883Y470708D01*
X600717Y470500D01*
X599883Y470083D01*
X599508Y469792D01*
X599258Y469375D01*
X599175Y469000D01*
X600925D01*
G01X603150Y471500D02*
X602817Y471417D01*
X602567Y471208D01*
X602400Y470958D01*
X602275Y470625D01*
X602233Y470250D01*
X602275Y469875D01*
X602400Y469542D01*
X602567Y469292D01*
X602817Y469083D01*
X603150Y469000D01*
X603483Y469083D01*
X603733Y469292D01*
X603900Y469542D01*
X604025Y469875D01*
X604067Y470250D01*
X604025Y470625D01*
X603900Y470958D01*
X603733Y471208D01*
X603483Y471417D01*
X603150Y471500D01*
G01X592823Y481449D02*
X593156Y481241D01*
X593531Y481116D01*
X593865D01*
X594198Y481241D01*
X594448Y481449D01*
X594573Y481741D01*
X594490Y482033D01*
X594281Y482283D01*
X593906Y482449D01*
X593406Y482533D01*
X593115Y482699D01*
X592990Y482991D01*
X593073Y483283D01*
X593281Y483491D01*
X593573Y483616D01*
X593865D01*
X594156Y483533D01*
X594406Y483324D01*
G01X595965Y481116D02*
Y483616D01*
X597006D01*
X597340Y483491D01*
X597548Y483324D01*
X597631Y482991D01*
X597548Y482658D01*
X597298Y482449D01*
X597006Y482324D01*
X595965D01*
G01X597006D02*
X597631Y481116D01*
G01X599898D02*
X600190Y481158D01*
X600523Y481283D01*
X600731Y481491D01*
X600815Y481783D01*
X600731Y482074D01*
X600481Y482324D01*
X600106Y482449D01*
X599690D01*
X599440Y482533D01*
X599231Y482741D01*
X599148Y483033D01*
X599273Y483324D01*
X599565Y483533D01*
X599898Y483616D01*
X600231Y483533D01*
X600523Y483324D01*
X600648Y483033D01*
X600565Y482741D01*
X600356Y482533D01*
X600106Y482449D01*
X599690D01*
X599315Y482324D01*
X599065Y482074D01*
X598981Y481783D01*
X599065Y481491D01*
X599273Y481283D01*
X599606Y481158D01*
X599898Y481116D01*
G01X602081Y481616D02*
X602331Y481324D01*
X602665Y481158D01*
X603040Y481116D01*
X603373Y481158D01*
X603706Y481366D01*
X603915Y481616D01*
X603956Y481866D01*
X603873Y482158D01*
X603581Y482366D01*
X603290Y482449D01*
X602915D01*
G01X603290D02*
X603540Y482574D01*
X603748Y482783D01*
X603831Y483033D01*
X603748Y483283D01*
X603540Y483491D01*
X603165Y483616D01*
X602790Y483574D01*
X602415Y483408D01*
G01X606098Y481116D02*
Y483616D01*
X605598Y483116D01*
G01Y481116D02*
X606598D01*
G01X592823Y496449D02*
X593156Y496241D01*
X593531Y496116D01*
X593865D01*
X594198Y496241D01*
X594448Y496449D01*
X594573Y496741D01*
X594490Y497033D01*
X594281Y497283D01*
X593906Y497449D01*
X593406Y497533D01*
X593115Y497699D01*
X592990Y497991D01*
X593073Y498283D01*
X593281Y498491D01*
X593573Y498616D01*
X593865D01*
X594156Y498533D01*
X594406Y498324D01*
G01X595965Y496116D02*
Y498616D01*
X597006D01*
X597340Y498491D01*
X597548Y498324D01*
X597631Y497991D01*
X597548Y497658D01*
X597298Y497449D01*
X597006Y497324D01*
X595965D01*
G01X597006D02*
X597631Y496116D01*
G01X599898D02*
X600190Y496158D01*
X600523Y496283D01*
X600731Y496491D01*
X600815Y496783D01*
X600731Y497074D01*
X600481Y497324D01*
X600106Y497449D01*
X599690D01*
X599440Y497533D01*
X599231Y497741D01*
X599148Y498033D01*
X599273Y498324D01*
X599565Y498533D01*
X599898Y498616D01*
X600231Y498533D01*
X600523Y498324D01*
X600648Y498033D01*
X600565Y497741D01*
X600356Y497533D01*
X600106Y497449D01*
X599690D01*
X599315Y497324D01*
X599065Y497074D01*
X598981Y496783D01*
X599065Y496491D01*
X599273Y496283D01*
X599606Y496158D01*
X599898Y496116D01*
G01X602081Y496616D02*
X602331Y496324D01*
X602665Y496158D01*
X603040Y496116D01*
X603373Y496158D01*
X603706Y496366D01*
X603915Y496616D01*
X603956Y496866D01*
X603873Y497158D01*
X603581Y497366D01*
X603290Y497449D01*
X602915D01*
G01X603290D02*
X603540Y497574D01*
X603748Y497783D01*
X603831Y498033D01*
X603748Y498283D01*
X603540Y498491D01*
X603165Y498616D01*
X602790Y498574D01*
X602415Y498408D01*
G01X605306Y498199D02*
X605556Y498449D01*
X605848Y498574D01*
X606181Y498616D01*
X606598Y498533D01*
X606890Y498324D01*
X606973Y498074D01*
X606931Y497824D01*
X606765Y497616D01*
X605931Y497199D01*
X605556Y496908D01*
X605306Y496491D01*
X605223Y496116D01*
X606973D01*
G01X592823Y486449D02*
X593156Y486241D01*
X593531Y486116D01*
X593865D01*
X594198Y486241D01*
X594448Y486449D01*
X594573Y486741D01*
X594490Y487033D01*
X594281Y487283D01*
X593906Y487449D01*
X593406Y487533D01*
X593115Y487699D01*
X592990Y487991D01*
X593073Y488283D01*
X593281Y488491D01*
X593573Y488616D01*
X593865D01*
X594156Y488533D01*
X594406Y488324D01*
G01X595965Y486116D02*
Y488616D01*
X597006D01*
X597340Y488491D01*
X597548Y488324D01*
X597631Y487991D01*
X597548Y487658D01*
X597298Y487449D01*
X597006Y487324D01*
X595965D01*
G01X597006D02*
X597631Y486116D01*
G01X599898D02*
X600190Y486158D01*
X600523Y486283D01*
X600731Y486491D01*
X600815Y486783D01*
X600731Y487074D01*
X600481Y487324D01*
X600106Y487449D01*
X599690D01*
X599440Y487533D01*
X599231Y487741D01*
X599148Y488033D01*
X599273Y488324D01*
X599565Y488533D01*
X599898Y488616D01*
X600231Y488533D01*
X600523Y488324D01*
X600648Y488033D01*
X600565Y487741D01*
X600356Y487533D01*
X600106Y487449D01*
X599690D01*
X599315Y487324D01*
X599065Y487074D01*
X598981Y486783D01*
X599065Y486491D01*
X599273Y486283D01*
X599606Y486158D01*
X599898Y486116D01*
G01X602081Y486616D02*
X602331Y486324D01*
X602665Y486158D01*
X603040Y486116D01*
X603373Y486158D01*
X603706Y486366D01*
X603915Y486616D01*
X603956Y486866D01*
X603873Y487158D01*
X603581Y487366D01*
X603290Y487449D01*
X602915D01*
G01X603290D02*
X603540Y487574D01*
X603748Y487783D01*
X603831Y488033D01*
X603748Y488283D01*
X603540Y488491D01*
X603165Y488616D01*
X602790Y488574D01*
X602415Y488408D01*
G01X605181Y486616D02*
X605431Y486324D01*
X605765Y486158D01*
X606140Y486116D01*
X606473Y486158D01*
X606806Y486366D01*
X607015Y486616D01*
X607056Y486866D01*
X606973Y487158D01*
X606681Y487366D01*
X606390Y487449D01*
X606015D01*
G01X606390D02*
X606640Y487574D01*
X606848Y487783D01*
X606931Y488033D01*
X606848Y488283D01*
X606640Y488491D01*
X606265Y488616D01*
X605890Y488574D01*
X605515Y488408D01*
G01X592823Y491449D02*
X593156Y491241D01*
X593531Y491116D01*
X593865D01*
X594198Y491241D01*
X594448Y491449D01*
X594573Y491741D01*
X594490Y492033D01*
X594281Y492283D01*
X593906Y492449D01*
X593406Y492533D01*
X593115Y492699D01*
X592990Y492991D01*
X593073Y493283D01*
X593281Y493491D01*
X593573Y493616D01*
X593865D01*
X594156Y493533D01*
X594406Y493324D01*
G01X595965Y491116D02*
Y493616D01*
X597006D01*
X597340Y493491D01*
X597548Y493324D01*
X597631Y492991D01*
X597548Y492658D01*
X597298Y492449D01*
X597006Y492324D01*
X595965D01*
G01X597006D02*
X597631Y491116D01*
G01X599898D02*
X600190Y491158D01*
X600523Y491283D01*
X600731Y491491D01*
X600815Y491783D01*
X600731Y492074D01*
X600481Y492324D01*
X600106Y492449D01*
X599690D01*
X599440Y492533D01*
X599231Y492741D01*
X599148Y493033D01*
X599273Y493324D01*
X599565Y493533D01*
X599898Y493616D01*
X600231Y493533D01*
X600523Y493324D01*
X600648Y493033D01*
X600565Y492741D01*
X600356Y492533D01*
X600106Y492449D01*
X599690D01*
X599315Y492324D01*
X599065Y492074D01*
X598981Y491783D01*
X599065Y491491D01*
X599273Y491283D01*
X599606Y491158D01*
X599898Y491116D01*
G01X602081Y491616D02*
X602331Y491324D01*
X602665Y491158D01*
X603040Y491116D01*
X603373Y491158D01*
X603706Y491366D01*
X603915Y491616D01*
X603956Y491866D01*
X603873Y492158D01*
X603581Y492366D01*
X603290Y492449D01*
X602915D01*
G01X603290D02*
X603540Y492574D01*
X603748Y492783D01*
X603831Y493033D01*
X603748Y493283D01*
X603540Y493491D01*
X603165Y493616D01*
X602790Y493574D01*
X602415Y493408D01*
G01X606598Y491116D02*
Y493616D01*
X605056Y491824D01*
X607140D01*
G01X592823Y506449D02*
X593156Y506241D01*
X593531Y506116D01*
X593865D01*
X594198Y506241D01*
X594448Y506449D01*
X594573Y506741D01*
X594490Y507033D01*
X594281Y507283D01*
X593906Y507449D01*
X593406Y507533D01*
X593115Y507699D01*
X592990Y507991D01*
X593073Y508283D01*
X593281Y508491D01*
X593573Y508616D01*
X593865D01*
X594156Y508533D01*
X594406Y508324D01*
G01X595965Y506116D02*
Y508616D01*
X597006D01*
X597340Y508491D01*
X597548Y508324D01*
X597631Y507991D01*
X597548Y507658D01*
X597298Y507449D01*
X597006Y507324D01*
X595965D01*
G01X597006D02*
X597631Y506116D01*
G01X599898D02*
X600190Y506158D01*
X600523Y506283D01*
X600731Y506491D01*
X600815Y506783D01*
X600731Y507074D01*
X600481Y507324D01*
X600106Y507449D01*
X599690D01*
X599440Y507533D01*
X599231Y507741D01*
X599148Y508033D01*
X599273Y508324D01*
X599565Y508533D01*
X599898Y508616D01*
X600231Y508533D01*
X600523Y508324D01*
X600648Y508033D01*
X600565Y507741D01*
X600356Y507533D01*
X600106Y507449D01*
X599690D01*
X599315Y507324D01*
X599065Y507074D01*
X598981Y506783D01*
X599065Y506491D01*
X599273Y506283D01*
X599606Y506158D01*
X599898Y506116D01*
G01X602081Y506616D02*
X602331Y506324D01*
X602665Y506158D01*
X603040Y506116D01*
X603373Y506158D01*
X603706Y506366D01*
X603915Y506616D01*
X603956Y506866D01*
X603873Y507158D01*
X603581Y507366D01*
X603290Y507449D01*
X602915D01*
G01X603290D02*
X603540Y507574D01*
X603748Y507783D01*
X603831Y508033D01*
X603748Y508283D01*
X603540Y508491D01*
X603165Y508616D01*
X602790Y508574D01*
X602415Y508408D01*
G01X605181Y506491D02*
X605431Y506283D01*
X605723Y506158D01*
X606098Y506116D01*
X606473Y506199D01*
X606765Y506366D01*
X606973Y506658D01*
X607015Y506991D01*
X606931Y507324D01*
X606723Y507533D01*
X606431Y507699D01*
X606140Y507741D01*
X605848Y507699D01*
X605473Y507533D01*
X605598Y508616D01*
X606723D01*
G01X592823Y501449D02*
X593156Y501241D01*
X593531Y501116D01*
X593865D01*
X594198Y501241D01*
X594448Y501449D01*
X594573Y501741D01*
X594490Y502033D01*
X594281Y502283D01*
X593906Y502449D01*
X593406Y502533D01*
X593115Y502699D01*
X592990Y502991D01*
X593073Y503283D01*
X593281Y503491D01*
X593573Y503616D01*
X593865D01*
X594156Y503533D01*
X594406Y503324D01*
G01X595965Y501116D02*
Y503616D01*
X597006D01*
X597340Y503491D01*
X597548Y503324D01*
X597631Y502991D01*
X597548Y502658D01*
X597298Y502449D01*
X597006Y502324D01*
X595965D01*
G01X597006D02*
X597631Y501116D01*
G01X599898D02*
X600190Y501158D01*
X600523Y501283D01*
X600731Y501491D01*
X600815Y501783D01*
X600731Y502074D01*
X600481Y502324D01*
X600106Y502449D01*
X599690D01*
X599440Y502533D01*
X599231Y502741D01*
X599148Y503033D01*
X599273Y503324D01*
X599565Y503533D01*
X599898Y503616D01*
X600231Y503533D01*
X600523Y503324D01*
X600648Y503033D01*
X600565Y502741D01*
X600356Y502533D01*
X600106Y502449D01*
X599690D01*
X599315Y502324D01*
X599065Y502074D01*
X598981Y501783D01*
X599065Y501491D01*
X599273Y501283D01*
X599606Y501158D01*
X599898Y501116D01*
G01X602081Y501616D02*
X602331Y501324D01*
X602665Y501158D01*
X603040Y501116D01*
X603373Y501158D01*
X603706Y501366D01*
X603915Y501616D01*
X603956Y501866D01*
X603873Y502158D01*
X603581Y502366D01*
X603290Y502449D01*
X602915D01*
G01X603290D02*
X603540Y502574D01*
X603748Y502783D01*
X603831Y503033D01*
X603748Y503283D01*
X603540Y503491D01*
X603165Y503616D01*
X602790Y503574D01*
X602415Y503408D01*
G01X605306Y502158D02*
X605598Y502449D01*
X605848Y502616D01*
X606181Y502699D01*
X606473Y502616D01*
X606681Y502449D01*
X606848Y502199D01*
X606890Y501908D01*
X606848Y501658D01*
X606681Y501408D01*
X606431Y501199D01*
X606140Y501116D01*
X605806Y501199D01*
X605515Y501449D01*
X605348Y501824D01*
X605306Y502241D01*
X605390Y502783D01*
X605515Y503074D01*
X605723Y503366D01*
X606015Y503574D01*
X606306Y503616D01*
X606598Y503533D01*
X606806Y503324D01*
G01X604425Y199333D02*
X604758Y199125D01*
X605133Y199000D01*
X605467D01*
X605800Y199125D01*
X606050Y199333D01*
X606175Y199625D01*
X606092Y199917D01*
X605883Y200167D01*
X605508Y200333D01*
X605008Y200417D01*
X604717Y200583D01*
X604592Y200875D01*
X604675Y201167D01*
X604883Y201375D01*
X605175Y201500D01*
X605467D01*
X605758Y201417D01*
X606008Y201208D01*
G01X607567Y199000D02*
Y201500D01*
X608608D01*
X608942Y201375D01*
X609150Y201208D01*
X609233Y200875D01*
X609150Y200542D01*
X608900Y200333D01*
X608608Y200208D01*
X607567D01*
G01X608608D02*
X609233Y199000D01*
G01X610708Y200042D02*
X611000Y200333D01*
X611250Y200500D01*
X611583Y200583D01*
X611875Y200500D01*
X612083Y200333D01*
X612250Y200083D01*
X612292Y199792D01*
X612250Y199542D01*
X612083Y199292D01*
X611833Y199083D01*
X611542Y199000D01*
X611208Y199083D01*
X610917Y199333D01*
X610750Y199708D01*
X610708Y200125D01*
X610792Y200667D01*
X610917Y200958D01*
X611125Y201250D01*
X611417Y201458D01*
X611708Y201500D01*
X612000Y201417D01*
X612208Y201208D01*
G01X613892Y199292D02*
X614183Y199083D01*
X614517Y199000D01*
X614850Y199083D01*
X615142Y199333D01*
X615350Y199708D01*
X615433Y200083D01*
Y200542D01*
X615350Y200917D01*
X615142Y201250D01*
X614892Y201417D01*
X614600Y201500D01*
X614267Y201417D01*
X614017Y201250D01*
X613850Y201000D01*
X613767Y200667D01*
X613850Y200375D01*
X614058Y200083D01*
X614308Y199917D01*
X614600Y199875D01*
X614933Y199958D01*
X615183Y200167D01*
X615433Y200542D01*
G01X617617Y199000D02*
X617700Y199542D01*
X617825Y200000D01*
X617992Y200417D01*
X618200Y200875D01*
X618533Y201500D01*
X616867D01*
G01X594800Y202500D02*
Y198500D01*
X602200D01*
G01X604425Y203833D02*
X604758Y203625D01*
X605133Y203500D01*
X605467D01*
X605800Y203625D01*
X606050Y203833D01*
X606175Y204125D01*
X606092Y204417D01*
X605883Y204667D01*
X605508Y204833D01*
X605008Y204917D01*
X604717Y205083D01*
X604592Y205375D01*
X604675Y205667D01*
X604883Y205875D01*
X605175Y206000D01*
X605467D01*
X605758Y205917D01*
X606008Y205708D01*
G01X607567Y203500D02*
Y206000D01*
X608608D01*
X608942Y205875D01*
X609150Y205708D01*
X609233Y205375D01*
X609150Y205042D01*
X608900Y204833D01*
X608608Y204708D01*
X607567D01*
G01X608608D02*
X609233Y203500D01*
G01X610708Y204542D02*
X611000Y204833D01*
X611250Y205000D01*
X611583Y205083D01*
X611875Y205000D01*
X612083Y204833D01*
X612250Y204583D01*
X612292Y204292D01*
X612250Y204042D01*
X612083Y203792D01*
X611833Y203583D01*
X611542Y203500D01*
X611208Y203583D01*
X610917Y203833D01*
X610750Y204208D01*
X610708Y204625D01*
X610792Y205167D01*
X610917Y205458D01*
X611125Y205750D01*
X611417Y205958D01*
X611708Y206000D01*
X612000Y205917D01*
X612208Y205708D01*
G01X613892Y203792D02*
X614183Y203583D01*
X614517Y203500D01*
X614850Y203583D01*
X615142Y203833D01*
X615350Y204208D01*
X615433Y204583D01*
Y205042D01*
X615350Y205417D01*
X615142Y205750D01*
X614892Y205917D01*
X614600Y206000D01*
X614267Y205917D01*
X614017Y205750D01*
X613850Y205500D01*
X613767Y205167D01*
X613850Y204875D01*
X614058Y204583D01*
X614308Y204417D01*
X614600Y204375D01*
X614933Y204458D01*
X615183Y204667D01*
X615433Y205042D01*
G01X617700Y203500D02*
X617992Y203542D01*
X618325Y203667D01*
X618533Y203875D01*
X618617Y204167D01*
X618533Y204458D01*
X618283Y204708D01*
X617908Y204833D01*
X617492D01*
X617242Y204917D01*
X617033Y205125D01*
X616950Y205417D01*
X617075Y205708D01*
X617367Y205917D01*
X617700Y206000D01*
X618033Y205917D01*
X618325Y205708D01*
X618450Y205417D01*
X618367Y205125D01*
X618158Y204917D01*
X617908Y204833D01*
X617492D01*
X617117Y204708D01*
X616867Y204458D01*
X616783Y204167D01*
X616867Y203875D01*
X617075Y203667D01*
X617408Y203542D01*
X617700Y203500D01*
G01X594800Y207000D02*
Y203000D01*
X602200D01*
G01X604425Y208333D02*
X604758Y208125D01*
X605133Y208000D01*
X605467D01*
X605800Y208125D01*
X606050Y208333D01*
X606175Y208625D01*
X606092Y208917D01*
X605883Y209167D01*
X605508Y209333D01*
X605008Y209417D01*
X604717Y209583D01*
X604592Y209875D01*
X604675Y210167D01*
X604883Y210375D01*
X605175Y210500D01*
X605467D01*
X605758Y210417D01*
X606008Y210208D01*
G01X607567Y208000D02*
Y210500D01*
X608608D01*
X608942Y210375D01*
X609150Y210208D01*
X609233Y209875D01*
X609150Y209542D01*
X608900Y209333D01*
X608608Y209208D01*
X607567D01*
G01X608608D02*
X609233Y208000D01*
G01X610708Y209042D02*
X611000Y209333D01*
X611250Y209500D01*
X611583Y209583D01*
X611875Y209500D01*
X612083Y209333D01*
X612250Y209083D01*
X612292Y208792D01*
X612250Y208542D01*
X612083Y208292D01*
X611833Y208083D01*
X611542Y208000D01*
X611208Y208083D01*
X610917Y208333D01*
X610750Y208708D01*
X610708Y209125D01*
X610792Y209667D01*
X610917Y209958D01*
X611125Y210250D01*
X611417Y210458D01*
X611708Y210500D01*
X612000Y210417D01*
X612208Y210208D01*
G01X613892Y208292D02*
X614183Y208083D01*
X614517Y208000D01*
X614850Y208083D01*
X615142Y208333D01*
X615350Y208708D01*
X615433Y209083D01*
Y209542D01*
X615350Y209917D01*
X615142Y210250D01*
X614892Y210417D01*
X614600Y210500D01*
X614267Y210417D01*
X614017Y210250D01*
X613850Y210000D01*
X613767Y209667D01*
X613850Y209375D01*
X614058Y209083D01*
X614308Y208917D01*
X614600Y208875D01*
X614933Y208958D01*
X615183Y209167D01*
X615433Y209542D01*
G01X617700Y210500D02*
X617367Y210417D01*
X617117Y210208D01*
X616950Y209958D01*
X616825Y209625D01*
X616783Y209250D01*
X616825Y208875D01*
X616950Y208542D01*
X617117Y208292D01*
X617367Y208083D01*
X617700Y208000D01*
X618033Y208083D01*
X618283Y208292D01*
X618450Y208542D01*
X618575Y208875D01*
X618617Y209250D01*
X618575Y209625D01*
X618450Y209958D01*
X618283Y210208D01*
X618033Y210417D01*
X617700Y210500D01*
G01X602200Y207500D02*
Y211500D01*
X594800D01*
G01X604425Y221833D02*
X604758Y221625D01*
X605133Y221500D01*
X605467D01*
X605800Y221625D01*
X606050Y221833D01*
X606175Y222125D01*
X606092Y222417D01*
X605883Y222667D01*
X605508Y222833D01*
X605008Y222917D01*
X604717Y223083D01*
X604592Y223375D01*
X604675Y223667D01*
X604883Y223875D01*
X605175Y224000D01*
X605467D01*
X605758Y223917D01*
X606008Y223708D01*
G01X607567Y221500D02*
Y224000D01*
X608608D01*
X608942Y223875D01*
X609150Y223708D01*
X609233Y223375D01*
X609150Y223042D01*
X608900Y222833D01*
X608608Y222708D01*
X607567D01*
G01X608608D02*
X609233Y221500D01*
G01X610708Y222542D02*
X611000Y222833D01*
X611250Y223000D01*
X611583Y223083D01*
X611875Y223000D01*
X612083Y222833D01*
X612250Y222583D01*
X612292Y222292D01*
X612250Y222042D01*
X612083Y221792D01*
X611833Y221583D01*
X611542Y221500D01*
X611208Y221583D01*
X610917Y221833D01*
X610750Y222208D01*
X610708Y222625D01*
X610792Y223167D01*
X610917Y223458D01*
X611125Y223750D01*
X611417Y223958D01*
X611708Y224000D01*
X612000Y223917D01*
X612208Y223708D01*
G01X613892Y221792D02*
X614183Y221583D01*
X614517Y221500D01*
X614850Y221583D01*
X615142Y221833D01*
X615350Y222208D01*
X615433Y222583D01*
Y223042D01*
X615350Y223417D01*
X615142Y223750D01*
X614892Y223917D01*
X614600Y224000D01*
X614267Y223917D01*
X614017Y223750D01*
X613850Y223500D01*
X613767Y223167D01*
X613850Y222875D01*
X614058Y222583D01*
X614308Y222417D01*
X614600Y222375D01*
X614933Y222458D01*
X615183Y222667D01*
X615433Y223042D01*
G01X617700Y221500D02*
Y224000D01*
X617200Y223500D01*
G01Y221500D02*
X618200D01*
G01X604425Y212833D02*
X604758Y212625D01*
X605133Y212500D01*
X605467D01*
X605800Y212625D01*
X606050Y212833D01*
X606175Y213125D01*
X606092Y213417D01*
X605883Y213667D01*
X605508Y213833D01*
X605008Y213917D01*
X604717Y214083D01*
X604592Y214375D01*
X604675Y214667D01*
X604883Y214875D01*
X605175Y215000D01*
X605467D01*
X605758Y214917D01*
X606008Y214708D01*
G01X607567Y212500D02*
Y215000D01*
X608608D01*
X608942Y214875D01*
X609150Y214708D01*
X609233Y214375D01*
X609150Y214042D01*
X608900Y213833D01*
X608608Y213708D01*
X607567D01*
G01X608608D02*
X609233Y212500D01*
G01X610708Y213542D02*
X611000Y213833D01*
X611250Y214000D01*
X611583Y214083D01*
X611875Y214000D01*
X612083Y213833D01*
X612250Y213583D01*
X612292Y213292D01*
X612250Y213042D01*
X612083Y212792D01*
X611833Y212583D01*
X611542Y212500D01*
X611208Y212583D01*
X610917Y212833D01*
X610750Y213208D01*
X610708Y213625D01*
X610792Y214167D01*
X610917Y214458D01*
X611125Y214750D01*
X611417Y214958D01*
X611708Y215000D01*
X612000Y214917D01*
X612208Y214708D01*
G01X613892Y212792D02*
X614183Y212583D01*
X614517Y212500D01*
X614850Y212583D01*
X615142Y212833D01*
X615350Y213208D01*
X615433Y213583D01*
Y214042D01*
X615350Y214417D01*
X615142Y214750D01*
X614892Y214917D01*
X614600Y215000D01*
X614267Y214917D01*
X614017Y214750D01*
X613850Y214500D01*
X613767Y214167D01*
X613850Y213875D01*
X614058Y213583D01*
X614308Y213417D01*
X614600Y213375D01*
X614933Y213458D01*
X615183Y213667D01*
X615433Y214042D01*
G01X616992Y212792D02*
X617283Y212583D01*
X617617Y212500D01*
X617950Y212583D01*
X618242Y212833D01*
X618450Y213208D01*
X618533Y213583D01*
Y214042D01*
X618450Y214417D01*
X618242Y214750D01*
X617992Y214917D01*
X617700Y215000D01*
X617367Y214917D01*
X617117Y214750D01*
X616950Y214500D01*
X616867Y214167D01*
X616950Y213875D01*
X617158Y213583D01*
X617408Y213417D01*
X617700Y213375D01*
X618033Y213458D01*
X618283Y213667D01*
X618533Y214042D01*
G01X594800Y216000D02*
Y212000D01*
X602200D01*
G01X604425Y217333D02*
X604758Y217125D01*
X605133Y217000D01*
X605467D01*
X605800Y217125D01*
X606050Y217333D01*
X606175Y217625D01*
X606092Y217917D01*
X605883Y218167D01*
X605508Y218333D01*
X605008Y218417D01*
X604717Y218583D01*
X604592Y218875D01*
X604675Y219167D01*
X604883Y219375D01*
X605175Y219500D01*
X605467D01*
X605758Y219417D01*
X606008Y219208D01*
G01X607567Y217000D02*
Y219500D01*
X608608D01*
X608942Y219375D01*
X609150Y219208D01*
X609233Y218875D01*
X609150Y218542D01*
X608900Y218333D01*
X608608Y218208D01*
X607567D01*
G01X608608D02*
X609233Y217000D01*
G01X611417D02*
X611500Y217542D01*
X611625Y218000D01*
X611792Y218417D01*
X612000Y218875D01*
X612333Y219500D01*
X610667D01*
G01X614600D02*
X614267Y219417D01*
X614017Y219208D01*
X613850Y218958D01*
X613725Y218625D01*
X613683Y218250D01*
X613725Y217875D01*
X613850Y217542D01*
X614017Y217292D01*
X614267Y217083D01*
X614600Y217000D01*
X614933Y217083D01*
X615183Y217292D01*
X615350Y217542D01*
X615475Y217875D01*
X615517Y218250D01*
X615475Y218625D01*
X615350Y218958D01*
X615183Y219208D01*
X614933Y219417D01*
X614600Y219500D01*
G01X617700D02*
X617367Y219417D01*
X617117Y219208D01*
X616950Y218958D01*
X616825Y218625D01*
X616783Y218250D01*
X616825Y217875D01*
X616950Y217542D01*
X617117Y217292D01*
X617367Y217083D01*
X617700Y217000D01*
X618033Y217083D01*
X618283Y217292D01*
X618450Y217542D01*
X618575Y217875D01*
X618617Y218250D01*
X618575Y218625D01*
X618450Y218958D01*
X618283Y219208D01*
X618033Y219417D01*
X617700Y219500D01*
G01X594800Y220500D02*
Y216500D01*
X602200D01*
G01Y221000D02*
Y225000D01*
X594800D01*
G01X604425Y226333D02*
X604758Y226125D01*
X605133Y226000D01*
X605467D01*
X605800Y226125D01*
X606050Y226333D01*
X606175Y226625D01*
X606092Y226917D01*
X605883Y227167D01*
X605508Y227333D01*
X605008Y227417D01*
X604717Y227583D01*
X604592Y227875D01*
X604675Y228167D01*
X604883Y228375D01*
X605175Y228500D01*
X605467D01*
X605758Y228417D01*
X606008Y228208D01*
G01X607567Y226000D02*
Y228500D01*
X608608D01*
X608942Y228375D01*
X609150Y228208D01*
X609233Y227875D01*
X609150Y227542D01*
X608900Y227333D01*
X608608Y227208D01*
X607567D01*
G01X608608D02*
X609233Y226000D01*
G01X611417D02*
X611500Y226542D01*
X611625Y227000D01*
X611792Y227417D01*
X612000Y227875D01*
X612333Y228500D01*
X610667D01*
G01X614600D02*
X614267Y228417D01*
X614017Y228208D01*
X613850Y227958D01*
X613725Y227625D01*
X613683Y227250D01*
X613725Y226875D01*
X613850Y226542D01*
X614017Y226292D01*
X614267Y226083D01*
X614600Y226000D01*
X614933Y226083D01*
X615183Y226292D01*
X615350Y226542D01*
X615475Y226875D01*
X615517Y227250D01*
X615475Y227625D01*
X615350Y227958D01*
X615183Y228208D01*
X614933Y228417D01*
X614600Y228500D01*
G01X617700Y226000D02*
X617992Y226042D01*
X618325Y226167D01*
X618533Y226375D01*
X618617Y226667D01*
X618533Y226958D01*
X618283Y227208D01*
X617908Y227333D01*
X617492D01*
X617242Y227417D01*
X617033Y227625D01*
X616950Y227917D01*
X617075Y228208D01*
X617367Y228417D01*
X617700Y228500D01*
X618033Y228417D01*
X618325Y228208D01*
X618450Y227917D01*
X618367Y227625D01*
X618158Y227417D01*
X617908Y227333D01*
X617492D01*
X617117Y227208D01*
X616867Y226958D01*
X616783Y226667D01*
X616867Y226375D01*
X617075Y226167D01*
X617408Y226042D01*
X617700Y226000D01*
G01X602200Y225500D02*
Y229500D01*
X594800D01*
G01X600667Y236925D02*
X600875Y237258D01*
X601000Y237633D01*
Y237967D01*
X600875Y238300D01*
X600667Y238550D01*
X600375Y238675D01*
X600083Y238592D01*
X599833Y238383D01*
X599667Y238008D01*
X599583Y237508D01*
X599417Y237217D01*
X599125Y237092D01*
X598833Y237175D01*
X598625Y237383D01*
X598500Y237675D01*
Y237967D01*
X598583Y238258D01*
X598792Y238508D01*
G01X598708Y241817D02*
X598583Y241567D01*
X598500Y241275D01*
Y240942D01*
X598625Y240567D01*
X598833Y240275D01*
X599083Y240067D01*
X599500Y239900D01*
X599875Y239858D01*
X600250Y239942D01*
X600500Y240067D01*
X600750Y240317D01*
X600917Y240608D01*
X601000Y240900D01*
Y241192D01*
X600917Y241483D01*
X600792Y241733D01*
X600625Y241942D01*
G01X600708Y243292D02*
X600917Y243583D01*
X601000Y243917D01*
X600917Y244250D01*
X600667Y244542D01*
X600292Y244750D01*
X599917Y244833D01*
X599458D01*
X599083Y244750D01*
X598750Y244542D01*
X598583Y244292D01*
X598500Y244000D01*
X598583Y243667D01*
X598750Y243417D01*
X599000Y243250D01*
X599333Y243167D01*
X599625Y243250D01*
X599917Y243458D01*
X600083Y243708D01*
X600125Y244000D01*
X600042Y244333D01*
X599833Y244583D01*
X599458Y244833D01*
G01X601000Y247100D02*
X598500D01*
X599000Y246600D01*
G01X601000D02*
Y247600D01*
G01Y250700D02*
X598500D01*
X600292Y249158D01*
Y251242D01*
G01X599322Y334292D02*
X599072Y334417D01*
X598780Y334500D01*
X598447D01*
X598072Y334375D01*
X597780Y334167D01*
X597572Y333917D01*
X597405Y333500D01*
X597363Y333125D01*
X597447Y332750D01*
X597572Y332500D01*
X597822Y332250D01*
X598113Y332083D01*
X598405Y332000D01*
X598697D01*
X598988Y332083D01*
X599238Y332208D01*
X599447Y332375D01*
G01X600588Y332500D02*
X600838Y332208D01*
X601172Y332042D01*
X601547Y332000D01*
X601880Y332042D01*
X602213Y332250D01*
X602422Y332500D01*
X602463Y332750D01*
X602380Y333042D01*
X602088Y333250D01*
X601797Y333333D01*
X601422D01*
G01X601797D02*
X602047Y333458D01*
X602255Y333667D01*
X602338Y333917D01*
X602255Y334167D01*
X602047Y334375D01*
X601672Y334500D01*
X601297Y334458D01*
X600922Y334292D01*
G01X603813Y334083D02*
X604063Y334333D01*
X604355Y334458D01*
X604688Y334500D01*
X605105Y334417D01*
X605397Y334208D01*
X605480Y333958D01*
X605438Y333708D01*
X605272Y333500D01*
X604438Y333083D01*
X604063Y332792D01*
X603813Y332375D01*
X603730Y332000D01*
X605480D01*
G01X607622D02*
X607705Y332542D01*
X607830Y333000D01*
X607997Y333417D01*
X608205Y333875D01*
X608538Y334500D01*
X606872D01*
G01X609167Y353375D02*
X609375Y353708D01*
X609500Y354083D01*
Y354417D01*
X609375Y354750D01*
X609167Y355000D01*
X608875Y355125D01*
X608583Y355042D01*
X608333Y354833D01*
X608167Y354458D01*
X608083Y353958D01*
X607917Y353667D01*
X607625Y353542D01*
X607333Y353625D01*
X607125Y353833D01*
X607000Y354125D01*
Y354417D01*
X607083Y354708D01*
X607292Y354958D01*
G01X607208Y358267D02*
X607083Y358017D01*
X607000Y357725D01*
Y357392D01*
X607125Y357017D01*
X607333Y356725D01*
X607583Y356517D01*
X608000Y356350D01*
X608375Y356308D01*
X608750Y356392D01*
X609000Y356517D01*
X609250Y356767D01*
X609417Y357058D01*
X609500Y357350D01*
Y357642D01*
X609417Y357933D01*
X609292Y358183D01*
X609125Y358392D01*
G01X609500Y360450D02*
X607000D01*
X607500Y359950D01*
G01X609500D02*
Y360950D01*
G01Y363550D02*
X607000D01*
X607500Y363050D01*
G01X609500D02*
Y364050D01*
G01Y366567D02*
X608958Y366650D01*
X608500Y366775D01*
X608083Y366942D01*
X607625Y367150D01*
X607000Y367483D01*
Y365817D01*
G01Y369750D02*
X607083Y369417D01*
X607292Y369167D01*
X607542Y369000D01*
X607875Y368875D01*
X608250Y368833D01*
X608625Y368875D01*
X608958Y369000D01*
X609208Y369167D01*
X609417Y369417D01*
X609500Y369750D01*
X609417Y370083D01*
X609208Y370333D01*
X608958Y370500D01*
X608625Y370625D01*
X608250Y370667D01*
X607875Y370625D01*
X607542Y370500D01*
X607292Y370333D01*
X607083Y370083D01*
X607000Y369750D01*
G01X604667Y353375D02*
X604875Y353708D01*
X605000Y354083D01*
Y354417D01*
X604875Y354750D01*
X604667Y355000D01*
X604375Y355125D01*
X604083Y355042D01*
X603833Y354833D01*
X603667Y354458D01*
X603583Y353958D01*
X603417Y353667D01*
X603125Y353542D01*
X602833Y353625D01*
X602625Y353833D01*
X602500Y354125D01*
Y354417D01*
X602583Y354708D01*
X602792Y354958D01*
G01X602708Y358267D02*
X602583Y358017D01*
X602500Y357725D01*
Y357392D01*
X602625Y357017D01*
X602833Y356725D01*
X603083Y356517D01*
X603500Y356350D01*
X603875Y356308D01*
X604250Y356392D01*
X604500Y356517D01*
X604750Y356767D01*
X604917Y357058D01*
X605000Y357350D01*
Y357642D01*
X604917Y357933D01*
X604792Y358183D01*
X604625Y358392D01*
G01X605000Y360450D02*
X602500D01*
X603000Y359950D01*
G01X605000D02*
Y360950D01*
G01Y363550D02*
X602500D01*
X603000Y363050D01*
G01X605000D02*
Y364050D01*
G01Y366650D02*
X604958Y366942D01*
X604833Y367275D01*
X604625Y367483D01*
X604333Y367567D01*
X604042Y367483D01*
X603792Y367233D01*
X603667Y366858D01*
Y366442D01*
X603583Y366192D01*
X603375Y365983D01*
X603083Y365900D01*
X602792Y366025D01*
X602583Y366317D01*
X602500Y366650D01*
X602583Y366983D01*
X602792Y367275D01*
X603083Y367400D01*
X603375Y367317D01*
X603583Y367108D01*
X603667Y366858D01*
Y366442D01*
X603792Y366067D01*
X604042Y365817D01*
X604333Y365733D01*
X604625Y365817D01*
X604833Y366025D01*
X604958Y366358D01*
X605000Y366650D01*
G01X602917Y368958D02*
X602667Y369208D01*
X602542Y369500D01*
X602500Y369833D01*
X602583Y370250D01*
X602792Y370542D01*
X603042Y370625D01*
X603292Y370583D01*
X603500Y370417D01*
X603917Y369583D01*
X604208Y369208D01*
X604625Y368958D01*
X605000Y368875D01*
Y370625D01*
G01X606098Y390116D02*
Y383116D01*
X592698D01*
Y390116D01*
X606098D01*
G01Y381116D02*
Y374116D01*
X592698D01*
Y381116D01*
X606098D01*
G01Y398616D02*
Y391616D01*
X592698D01*
Y398616D01*
X606098D01*
G01Y407116D02*
Y400116D01*
X592698D01*
Y407116D01*
X606098D01*
G01Y423116D02*
Y416116D01*
X592698D01*
Y423116D01*
X606098D01*
G01Y415116D02*
Y408116D01*
X592698D01*
Y415116D01*
X606098D01*
G01X607925Y578333D02*
X608258Y578125D01*
X608633Y578000D01*
X608967D01*
X609300Y578125D01*
X609550Y578333D01*
X609675Y578625D01*
X609592Y578917D01*
X609383Y579167D01*
X609008Y579333D01*
X608508Y579417D01*
X608217Y579583D01*
X608092Y579875D01*
X608175Y580167D01*
X608383Y580375D01*
X608675Y580500D01*
X608967D01*
X609258Y580417D01*
X609508Y580208D01*
G01X611067Y578000D02*
Y580500D01*
X612108D01*
X612442Y580375D01*
X612650Y580208D01*
X612733Y579875D01*
X612650Y579542D01*
X612400Y579333D01*
X612108Y579208D01*
X611067D01*
G01X612108D02*
X612733Y578000D01*
G01X614917D02*
X615000Y578542D01*
X615125Y579000D01*
X615292Y579417D01*
X615500Y579875D01*
X615833Y580500D01*
X614167D01*
G01X617308Y580083D02*
X617558Y580333D01*
X617850Y580458D01*
X618183Y580500D01*
X618600Y580417D01*
X618892Y580208D01*
X618975Y579958D01*
X618933Y579708D01*
X618767Y579500D01*
X617933Y579083D01*
X617558Y578792D01*
X617308Y578375D01*
X617225Y578000D01*
X618975D01*
G01X621700D02*
Y580500D01*
X620158Y578708D01*
X622242D01*
G01X606375Y573833D02*
X606708Y573625D01*
X607083Y573500D01*
X607417D01*
X607750Y573625D01*
X608000Y573833D01*
X608125Y574125D01*
X608042Y574417D01*
X607833Y574667D01*
X607458Y574833D01*
X606958Y574917D01*
X606667Y575083D01*
X606542Y575375D01*
X606625Y575667D01*
X606833Y575875D01*
X607125Y576000D01*
X607417D01*
X607708Y575917D01*
X607958Y575708D01*
G01X611267Y575792D02*
X611017Y575917D01*
X610725Y576000D01*
X610392D01*
X610017Y575875D01*
X609725Y575667D01*
X609517Y575417D01*
X609350Y575000D01*
X609308Y574625D01*
X609392Y574250D01*
X609517Y574000D01*
X609767Y573750D01*
X610058Y573583D01*
X610350Y573500D01*
X610642D01*
X610933Y573583D01*
X611183Y573708D01*
X611392Y573875D01*
G01X613450Y573500D02*
Y576000D01*
X612950Y575500D01*
G01Y573500D02*
X613950D01*
G01X615758Y575583D02*
X616008Y575833D01*
X616300Y575958D01*
X616633Y576000D01*
X617050Y575917D01*
X617342Y575708D01*
X617425Y575458D01*
X617383Y575208D01*
X617217Y575000D01*
X616383Y574583D01*
X616008Y574292D01*
X615758Y573875D01*
X615675Y573500D01*
X617425D01*
G01X619650D02*
X619942Y573542D01*
X620275Y573667D01*
X620483Y573875D01*
X620567Y574167D01*
X620483Y574458D01*
X620233Y574708D01*
X619858Y574833D01*
X619442D01*
X619192Y574917D01*
X618983Y575125D01*
X618900Y575417D01*
X619025Y575708D01*
X619317Y575917D01*
X619650Y576000D01*
X619983Y575917D01*
X620275Y575708D01*
X620400Y575417D01*
X620317Y575125D01*
X620108Y574917D01*
X619858Y574833D01*
X619442D01*
X619067Y574708D01*
X618817Y574458D01*
X618733Y574167D01*
X618817Y573875D01*
X619025Y573667D01*
X619358Y573542D01*
X619650Y573500D01*
G01X622667D02*
X622750Y574042D01*
X622875Y574500D01*
X623042Y574917D01*
X623250Y575375D01*
X623583Y576000D01*
X621917D01*
G01X607925Y587833D02*
X608258Y587625D01*
X608633Y587500D01*
X608967D01*
X609300Y587625D01*
X609550Y587833D01*
X609675Y588125D01*
X609592Y588417D01*
X609383Y588667D01*
X609008Y588833D01*
X608508Y588917D01*
X608217Y589083D01*
X608092Y589375D01*
X608175Y589667D01*
X608383Y589875D01*
X608675Y590000D01*
X608967D01*
X609258Y589917D01*
X609508Y589708D01*
G01X611067Y587500D02*
Y590000D01*
X612108D01*
X612442Y589875D01*
X612650Y589708D01*
X612733Y589375D01*
X612650Y589042D01*
X612400Y588833D01*
X612108Y588708D01*
X611067D01*
G01X612108D02*
X612733Y587500D01*
G01X614917D02*
X615000Y588042D01*
X615125Y588500D01*
X615292Y588917D01*
X615500Y589375D01*
X615833Y590000D01*
X614167D01*
G01X617308Y589583D02*
X617558Y589833D01*
X617850Y589958D01*
X618183Y590000D01*
X618600Y589917D01*
X618892Y589708D01*
X618975Y589458D01*
X618933Y589208D01*
X618767Y589000D01*
X617933Y588583D01*
X617558Y588292D01*
X617308Y587875D01*
X617225Y587500D01*
X618975D01*
G01X620283Y587875D02*
X620533Y587667D01*
X620825Y587542D01*
X621200Y587500D01*
X621575Y587583D01*
X621867Y587750D01*
X622075Y588042D01*
X622117Y588375D01*
X622033Y588708D01*
X621825Y588917D01*
X621533Y589083D01*
X621242Y589125D01*
X620950Y589083D01*
X620575Y588917D01*
X620700Y590000D01*
X621825D01*
G01X607925Y583333D02*
X608258Y583125D01*
X608633Y583000D01*
X608967D01*
X609300Y583125D01*
X609550Y583333D01*
X609675Y583625D01*
X609592Y583917D01*
X609383Y584167D01*
X609008Y584333D01*
X608508Y584417D01*
X608217Y584583D01*
X608092Y584875D01*
X608175Y585167D01*
X608383Y585375D01*
X608675Y585500D01*
X608967D01*
X609258Y585417D01*
X609508Y585208D01*
G01X611067Y583000D02*
Y585500D01*
X612108D01*
X612442Y585375D01*
X612650Y585208D01*
X612733Y584875D01*
X612650Y584542D01*
X612400Y584333D01*
X612108Y584208D01*
X611067D01*
G01X612108D02*
X612733Y583000D01*
G01X614917D02*
X615000Y583542D01*
X615125Y584000D01*
X615292Y584417D01*
X615500Y584875D01*
X615833Y585500D01*
X614167D01*
G01X617308Y585083D02*
X617558Y585333D01*
X617850Y585458D01*
X618183Y585500D01*
X618600Y585417D01*
X618892Y585208D01*
X618975Y584958D01*
X618933Y584708D01*
X618767Y584500D01*
X617933Y584083D01*
X617558Y583792D01*
X617308Y583375D01*
X617225Y583000D01*
X618975D01*
G01X620408Y584042D02*
X620700Y584333D01*
X620950Y584500D01*
X621283Y584583D01*
X621575Y584500D01*
X621783Y584333D01*
X621950Y584083D01*
X621992Y583792D01*
X621950Y583542D01*
X621783Y583292D01*
X621533Y583083D01*
X621242Y583000D01*
X620908Y583083D01*
X620617Y583333D01*
X620450Y583708D01*
X620408Y584125D01*
X620492Y584667D01*
X620617Y584958D01*
X620825Y585250D01*
X621117Y585458D01*
X621408Y585500D01*
X621700Y585417D01*
X621908Y585208D01*
G01X608925Y605733D02*
X609258Y605525D01*
X609633Y605400D01*
X609967D01*
X610300Y605525D01*
X610550Y605733D01*
X610675Y606025D01*
X610592Y606317D01*
X610383Y606567D01*
X610008Y606733D01*
X609508Y606817D01*
X609217Y606983D01*
X609092Y607275D01*
X609175Y607567D01*
X609383Y607775D01*
X609675Y607900D01*
X609967D01*
X610258Y607817D01*
X610508Y607608D01*
G01X612067Y605400D02*
Y607900D01*
X613108D01*
X613442Y607775D01*
X613650Y607608D01*
X613733Y607275D01*
X613650Y606942D01*
X613400Y606733D01*
X613108Y606608D01*
X612067D01*
G01X613108D02*
X613733Y605400D01*
G01X615917D02*
X616000Y605942D01*
X616125Y606400D01*
X616292Y606817D01*
X616500Y607275D01*
X616833Y607900D01*
X615167D01*
G01X618308Y607483D02*
X618558Y607733D01*
X618850Y607858D01*
X619183Y607900D01*
X619600Y607817D01*
X619892Y607608D01*
X619975Y607358D01*
X619933Y607108D01*
X619767Y606900D01*
X618933Y606483D01*
X618558Y606192D01*
X618308Y605775D01*
X618225Y605400D01*
X619975D01*
G01X621492Y605692D02*
X621783Y605483D01*
X622117Y605400D01*
X622450Y605483D01*
X622742Y605733D01*
X622950Y606108D01*
X623033Y606483D01*
Y606942D01*
X622950Y607317D01*
X622742Y607650D01*
X622492Y607817D01*
X622200Y607900D01*
X621867Y607817D01*
X621617Y607650D01*
X621450Y607400D01*
X621367Y607067D01*
X621450Y606775D01*
X621658Y606483D01*
X621908Y606317D01*
X622200Y606275D01*
X622533Y606358D01*
X622783Y606567D01*
X623033Y606942D01*
G01X608925Y611733D02*
X609258Y611525D01*
X609633Y611400D01*
X609967D01*
X610300Y611525D01*
X610550Y611733D01*
X610675Y612025D01*
X610592Y612317D01*
X610383Y612567D01*
X610008Y612733D01*
X609508Y612817D01*
X609217Y612983D01*
X609092Y613275D01*
X609175Y613567D01*
X609383Y613775D01*
X609675Y613900D01*
X609967D01*
X610258Y613817D01*
X610508Y613608D01*
G01X612067Y611400D02*
Y613900D01*
X613108D01*
X613442Y613775D01*
X613650Y613608D01*
X613733Y613275D01*
X613650Y612942D01*
X613400Y612733D01*
X613108Y612608D01*
X612067D01*
G01X613108D02*
X613733Y611400D01*
G01X615917D02*
X616000Y611942D01*
X616125Y612400D01*
X616292Y612817D01*
X616500Y613275D01*
X616833Y613900D01*
X615167D01*
G01X618308Y613483D02*
X618558Y613733D01*
X618850Y613858D01*
X619183Y613900D01*
X619600Y613817D01*
X619892Y613608D01*
X619975Y613358D01*
X619933Y613108D01*
X619767Y612900D01*
X618933Y612483D01*
X618558Y612192D01*
X618308Y611775D01*
X618225Y611400D01*
X619975D01*
G01X622117D02*
X622200Y611942D01*
X622325Y612400D01*
X622492Y612817D01*
X622700Y613275D01*
X623033Y613900D01*
X621367D01*
G01X625876Y90731D02*
X623376D01*
Y91772D01*
X623501Y92106D01*
X623668Y92314D01*
X624001Y92397D01*
X624334Y92314D01*
X624543Y92064D01*
X624668Y91772D01*
Y90731D01*
G01Y91772D02*
X625876Y92397D01*
G01Y95164D02*
X623376D01*
X625168Y93622D01*
Y95706D01*
G01X625876Y97764D02*
X623376D01*
X623876Y97264D01*
G01X625876D02*
Y98264D01*
G01X624834Y100072D02*
X624543Y100364D01*
X624376Y100614D01*
X624293Y100947D01*
X624376Y101239D01*
X624543Y101447D01*
X624793Y101614D01*
X625084Y101656D01*
X625334Y101614D01*
X625584Y101447D01*
X625793Y101197D01*
X625876Y100906D01*
X625793Y100572D01*
X625543Y100281D01*
X625168Y100114D01*
X624751Y100072D01*
X624209Y100156D01*
X623918Y100281D01*
X623626Y100489D01*
X623418Y100781D01*
X623376Y101072D01*
X623459Y101364D01*
X623668Y101572D01*
G01X621376Y90731D02*
X618876D01*
Y91772D01*
X619001Y92106D01*
X619168Y92314D01*
X619501Y92397D01*
X619834Y92314D01*
X620043Y92064D01*
X620168Y91772D01*
Y90731D01*
G01Y91772D02*
X621376Y92397D01*
G01Y95164D02*
X618876D01*
X620668Y93622D01*
Y95706D01*
G01X621376Y97764D02*
X618876D01*
X619376Y97264D01*
G01X621376D02*
Y98264D01*
G01Y100781D02*
X620834Y100864D01*
X620376Y100989D01*
X619959Y101156D01*
X619501Y101364D01*
X618876Y101697D01*
Y100031D01*
G01X616876Y90731D02*
X614376D01*
Y91772D01*
X614501Y92106D01*
X614668Y92314D01*
X615001Y92397D01*
X615334Y92314D01*
X615543Y92064D01*
X615668Y91772D01*
Y90731D01*
G01Y91772D02*
X616876Y92397D01*
G01Y95164D02*
X614376D01*
X616168Y93622D01*
Y95706D01*
G01X616876Y97764D02*
X614376D01*
X614876Y97264D01*
G01X616876D02*
Y98264D01*
G01Y100864D02*
X616834Y101156D01*
X616709Y101489D01*
X616501Y101697D01*
X616209Y101781D01*
X615918Y101697D01*
X615668Y101447D01*
X615543Y101072D01*
Y100656D01*
X615459Y100406D01*
X615251Y100197D01*
X614959Y100114D01*
X614668Y100239D01*
X614459Y100531D01*
X614376Y100864D01*
X614459Y101197D01*
X614668Y101489D01*
X614959Y101614D01*
X615251Y101531D01*
X615459Y101322D01*
X615543Y101072D01*
Y100656D01*
X615668Y100281D01*
X615918Y100031D01*
X616209Y99947D01*
X616501Y100031D01*
X616709Y100239D01*
X616834Y100572D01*
X616876Y100864D01*
G01X612376Y90731D02*
X609876D01*
Y91772D01*
X610001Y92106D01*
X610168Y92314D01*
X610501Y92397D01*
X610834Y92314D01*
X611043Y92064D01*
X611168Y91772D01*
Y90731D01*
G01Y91772D02*
X612376Y92397D01*
G01Y95164D02*
X609876D01*
X611668Y93622D01*
Y95706D01*
G01X612376Y97764D02*
X609876D01*
X610376Y97264D01*
G01X612376D02*
Y98264D01*
G01X612084Y100156D02*
X612293Y100447D01*
X612376Y100781D01*
X612293Y101114D01*
X612043Y101406D01*
X611668Y101614D01*
X611293Y101697D01*
X610834D01*
X610459Y101614D01*
X610126Y101406D01*
X609959Y101156D01*
X609876Y100864D01*
X609959Y100531D01*
X610126Y100281D01*
X610376Y100114D01*
X610709Y100031D01*
X611001Y100114D01*
X611293Y100322D01*
X611459Y100572D01*
X611501Y100864D01*
X611418Y101197D01*
X611209Y101447D01*
X610834Y101697D01*
G01X620000Y326800D02*
Y338000D01*
G01X638000Y326800D02*
X620000D01*
G01X622517Y367500D02*
Y370000D01*
X623517D01*
X623850Y369875D01*
X624100Y369583D01*
X624183Y369250D01*
X624100Y368917D01*
X623892Y368667D01*
X623517Y368542D01*
X622517D01*
G01X626450Y370000D02*
Y367500D01*
G01X625492Y370000D02*
X627408D01*
G01X630467Y369792D02*
X630217Y369917D01*
X629925Y370000D01*
X629592D01*
X629217Y369875D01*
X628925Y369667D01*
X628717Y369417D01*
X628550Y369000D01*
X628508Y368625D01*
X628592Y368250D01*
X628717Y368000D01*
X628967Y367750D01*
X629258Y367583D01*
X629550Y367500D01*
X629842D01*
X630133Y367583D01*
X630383Y367708D01*
X630592Y367875D01*
G01X631858Y368542D02*
X632150Y368833D01*
X632400Y369000D01*
X632733Y369083D01*
X633025Y369000D01*
X633233Y368833D01*
X633400Y368583D01*
X633442Y368292D01*
X633400Y368042D01*
X633233Y367792D01*
X632983Y367583D01*
X632692Y367500D01*
X632358Y367583D01*
X632067Y367833D01*
X631900Y368208D01*
X631858Y368625D01*
X631942Y369167D01*
X632067Y369458D01*
X632275Y369750D01*
X632567Y369958D01*
X632858Y370000D01*
X633150Y369917D01*
X633358Y369708D01*
G01X620000Y365200D02*
Y354000D01*
G01X638000Y365200D02*
X620000D01*
G01X612375Y450833D02*
X612708Y450625D01*
X613083Y450500D01*
X613417D01*
X613750Y450625D01*
X614000Y450833D01*
X614125Y451125D01*
X614042Y451417D01*
X613833Y451667D01*
X613458Y451833D01*
X612958Y451917D01*
X612667Y452083D01*
X612542Y452375D01*
X612625Y452667D01*
X612833Y452875D01*
X613125Y453000D01*
X613417D01*
X613708Y452917D01*
X613958Y452708D01*
G01X617267Y452792D02*
X617017Y452917D01*
X616725Y453000D01*
X616392D01*
X616017Y452875D01*
X615725Y452667D01*
X615517Y452417D01*
X615350Y452000D01*
X615308Y451625D01*
X615392Y451250D01*
X615517Y451000D01*
X615767Y450750D01*
X616058Y450583D01*
X616350Y450500D01*
X616642D01*
X616933Y450583D01*
X617183Y450708D01*
X617392Y450875D01*
G01X619450Y450500D02*
Y453000D01*
X618950Y452500D01*
G01Y450500D02*
X619950D01*
G01X621758Y452583D02*
X622008Y452833D01*
X622300Y452958D01*
X622633Y453000D01*
X623050Y452917D01*
X623342Y452708D01*
X623425Y452458D01*
X623383Y452208D01*
X623217Y452000D01*
X622383Y451583D01*
X622008Y451292D01*
X621758Y450875D01*
X621675Y450500D01*
X623425D01*
G01X625650Y453000D02*
X625317Y452917D01*
X625067Y452708D01*
X624900Y452458D01*
X624775Y452125D01*
X624733Y451750D01*
X624775Y451375D01*
X624900Y451042D01*
X625067Y450792D01*
X625317Y450583D01*
X625650Y450500D01*
X625983Y450583D01*
X626233Y450792D01*
X626400Y451042D01*
X626525Y451375D01*
X626567Y451750D01*
X626525Y452125D01*
X626400Y452458D01*
X626233Y452708D01*
X625983Y452917D01*
X625650Y453000D01*
G01X628042Y450792D02*
X628333Y450583D01*
X628667Y450500D01*
X629000Y450583D01*
X629292Y450833D01*
X629500Y451208D01*
X629583Y451583D01*
Y452042D01*
X629500Y452417D01*
X629292Y452750D01*
X629042Y452917D01*
X628750Y453000D01*
X628417Y452917D01*
X628167Y452750D01*
X628000Y452500D01*
X627917Y452167D01*
X628000Y451875D01*
X628208Y451583D01*
X628458Y451417D01*
X628750Y451375D01*
X629083Y451458D01*
X629333Y451667D01*
X629583Y452042D01*
G01X612375Y446833D02*
X612708Y446625D01*
X613083Y446500D01*
X613417D01*
X613750Y446625D01*
X614000Y446833D01*
X614125Y447125D01*
X614042Y447417D01*
X613833Y447667D01*
X613458Y447833D01*
X612958Y447917D01*
X612667Y448083D01*
X612542Y448375D01*
X612625Y448667D01*
X612833Y448875D01*
X613125Y449000D01*
X613417D01*
X613708Y448917D01*
X613958Y448708D01*
G01X617267Y448792D02*
X617017Y448917D01*
X616725Y449000D01*
X616392D01*
X616017Y448875D01*
X615725Y448667D01*
X615517Y448417D01*
X615350Y448000D01*
X615308Y447625D01*
X615392Y447250D01*
X615517Y447000D01*
X615767Y446750D01*
X616058Y446583D01*
X616350Y446500D01*
X616642D01*
X616933Y446583D01*
X617183Y446708D01*
X617392Y446875D01*
G01X619450Y446500D02*
Y449000D01*
X618950Y448500D01*
G01Y446500D02*
X619950D01*
G01X621758Y448583D02*
X622008Y448833D01*
X622300Y448958D01*
X622633Y449000D01*
X623050Y448917D01*
X623342Y448708D01*
X623425Y448458D01*
X623383Y448208D01*
X623217Y448000D01*
X622383Y447583D01*
X622008Y447292D01*
X621758Y446875D01*
X621675Y446500D01*
X623425D01*
G01X625650D02*
Y449000D01*
X625150Y448500D01*
G01Y446500D02*
X626150D01*
G01X628750Y449000D02*
X628417Y448917D01*
X628167Y448708D01*
X628000Y448458D01*
X627875Y448125D01*
X627833Y447750D01*
X627875Y447375D01*
X628000Y447042D01*
X628167Y446792D01*
X628417Y446583D01*
X628750Y446500D01*
X629083Y446583D01*
X629333Y446792D01*
X629500Y447042D01*
X629625Y447375D01*
X629667Y447750D01*
X629625Y448125D01*
X629500Y448458D01*
X629333Y448708D01*
X629083Y448917D01*
X628750Y449000D01*
G01X641500Y438000D02*
X632500D01*
Y463500D01*
X611500D01*
Y492000D01*
X635000D01*
Y482000D01*
X643000D01*
Y459500D01*
X649500D01*
G01X612375Y458833D02*
X612708Y458625D01*
X613083Y458500D01*
X613417D01*
X613750Y458625D01*
X614000Y458833D01*
X614125Y459125D01*
X614042Y459417D01*
X613833Y459667D01*
X613458Y459833D01*
X612958Y459917D01*
X612667Y460083D01*
X612542Y460375D01*
X612625Y460667D01*
X612833Y460875D01*
X613125Y461000D01*
X613417D01*
X613708Y460917D01*
X613958Y460708D01*
G01X617267Y460792D02*
X617017Y460917D01*
X616725Y461000D01*
X616392D01*
X616017Y460875D01*
X615725Y460667D01*
X615517Y460417D01*
X615350Y460000D01*
X615308Y459625D01*
X615392Y459250D01*
X615517Y459000D01*
X615767Y458750D01*
X616058Y458583D01*
X616350Y458500D01*
X616642D01*
X616933Y458583D01*
X617183Y458708D01*
X617392Y458875D01*
G01X619450Y458500D02*
Y461000D01*
X618950Y460500D01*
G01Y458500D02*
X619950D01*
G01X621758Y460583D02*
X622008Y460833D01*
X622300Y460958D01*
X622633Y461000D01*
X623050Y460917D01*
X623342Y460708D01*
X623425Y460458D01*
X623383Y460208D01*
X623217Y460000D01*
X622383Y459583D01*
X622008Y459292D01*
X621758Y458875D01*
X621675Y458500D01*
X623425D01*
G01X625650Y461000D02*
X625317Y460917D01*
X625067Y460708D01*
X624900Y460458D01*
X624775Y460125D01*
X624733Y459750D01*
X624775Y459375D01*
X624900Y459042D01*
X625067Y458792D01*
X625317Y458583D01*
X625650Y458500D01*
X625983Y458583D01*
X626233Y458792D01*
X626400Y459042D01*
X626525Y459375D01*
X626567Y459750D01*
X626525Y460125D01*
X626400Y460458D01*
X626233Y460708D01*
X625983Y460917D01*
X625650Y461000D01*
G01X628667Y458500D02*
X628750Y459042D01*
X628875Y459500D01*
X629042Y459917D01*
X629250Y460375D01*
X629583Y461000D01*
X627917D01*
G01X612375Y454833D02*
X612708Y454625D01*
X613083Y454500D01*
X613417D01*
X613750Y454625D01*
X614000Y454833D01*
X614125Y455125D01*
X614042Y455417D01*
X613833Y455667D01*
X613458Y455833D01*
X612958Y455917D01*
X612667Y456083D01*
X612542Y456375D01*
X612625Y456667D01*
X612833Y456875D01*
X613125Y457000D01*
X613417D01*
X613708Y456917D01*
X613958Y456708D01*
G01X617267Y456792D02*
X617017Y456917D01*
X616725Y457000D01*
X616392D01*
X616017Y456875D01*
X615725Y456667D01*
X615517Y456417D01*
X615350Y456000D01*
X615308Y455625D01*
X615392Y455250D01*
X615517Y455000D01*
X615767Y454750D01*
X616058Y454583D01*
X616350Y454500D01*
X616642D01*
X616933Y454583D01*
X617183Y454708D01*
X617392Y454875D01*
G01X619450Y454500D02*
Y457000D01*
X618950Y456500D01*
G01Y454500D02*
X619950D01*
G01X621758Y456583D02*
X622008Y456833D01*
X622300Y456958D01*
X622633Y457000D01*
X623050Y456917D01*
X623342Y456708D01*
X623425Y456458D01*
X623383Y456208D01*
X623217Y456000D01*
X622383Y455583D01*
X622008Y455292D01*
X621758Y454875D01*
X621675Y454500D01*
X623425D01*
G01X625650Y457000D02*
X625317Y456917D01*
X625067Y456708D01*
X624900Y456458D01*
X624775Y456125D01*
X624733Y455750D01*
X624775Y455375D01*
X624900Y455042D01*
X625067Y454792D01*
X625317Y454583D01*
X625650Y454500D01*
X625983Y454583D01*
X626233Y454792D01*
X626400Y455042D01*
X626525Y455375D01*
X626567Y455750D01*
X626525Y456125D01*
X626400Y456458D01*
X626233Y456708D01*
X625983Y456917D01*
X625650Y457000D01*
G01X628750Y454500D02*
X629042Y454542D01*
X629375Y454667D01*
X629583Y454875D01*
X629667Y455167D01*
X629583Y455458D01*
X629333Y455708D01*
X628958Y455833D01*
X628542D01*
X628292Y455917D01*
X628083Y456125D01*
X628000Y456417D01*
X628125Y456708D01*
X628417Y456917D01*
X628750Y457000D01*
X629083Y456917D01*
X629375Y456708D01*
X629500Y456417D01*
X629417Y456125D01*
X629208Y455917D01*
X628958Y455833D01*
X628542D01*
X628167Y455708D01*
X627917Y455458D01*
X627833Y455167D01*
X627917Y454875D01*
X628125Y454667D01*
X628458Y454542D01*
X628750Y454500D01*
G01X616967Y466000D02*
Y468500D01*
X617967D01*
X618300Y468375D01*
X618550Y468083D01*
X618633Y467750D01*
X618550Y467417D01*
X618342Y467167D01*
X617967Y467042D01*
X616967D01*
G01X620067Y466000D02*
Y468500D01*
X621108D01*
X621442Y468375D01*
X621650Y468208D01*
X621733Y467875D01*
X621650Y467542D01*
X621400Y467333D01*
X621108Y467208D01*
X620067D01*
G01X621108D02*
X621733Y466000D01*
G01X624000D02*
Y468500D01*
X623500Y468000D01*
G01Y466000D02*
X624500D01*
G01X626183Y466375D02*
X626433Y466167D01*
X626725Y466042D01*
X627100Y466000D01*
X627475Y466083D01*
X627767Y466250D01*
X627975Y466542D01*
X628017Y466875D01*
X627933Y467208D01*
X627725Y467417D01*
X627433Y467583D01*
X627142Y467625D01*
X626850Y467583D01*
X626475Y467417D01*
X626600Y468500D01*
X627725D01*
G01X630200Y466000D02*
Y468500D01*
X629700Y468000D01*
G01Y466000D02*
X630700D01*
G01X616967Y470500D02*
Y473000D01*
X617967D01*
X618300Y472875D01*
X618550Y472583D01*
X618633Y472250D01*
X618550Y471917D01*
X618342Y471667D01*
X617967Y471542D01*
X616967D01*
G01X620067Y470500D02*
Y473000D01*
X621108D01*
X621442Y472875D01*
X621650Y472708D01*
X621733Y472375D01*
X621650Y472042D01*
X621400Y471833D01*
X621108Y471708D01*
X620067D01*
G01X621108D02*
X621733Y470500D01*
G01X624000D02*
Y473000D01*
X623500Y472500D01*
G01Y470500D02*
X624500D01*
G01X626183Y470875D02*
X626433Y470667D01*
X626725Y470542D01*
X627100Y470500D01*
X627475Y470583D01*
X627767Y470750D01*
X627975Y471042D01*
X628017Y471375D01*
X627933Y471708D01*
X627725Y471917D01*
X627433Y472083D01*
X627142Y472125D01*
X626850Y472083D01*
X626475Y471917D01*
X626600Y473000D01*
X627725D01*
G01X629408Y472583D02*
X629658Y472833D01*
X629950Y472958D01*
X630283Y473000D01*
X630700Y472917D01*
X630992Y472708D01*
X631075Y472458D01*
X631033Y472208D01*
X630867Y472000D01*
X630033Y471583D01*
X629658Y471292D01*
X629408Y470875D01*
X629325Y470500D01*
X631075D01*
G01X616500Y475467D02*
X614000D01*
Y476467D01*
X614125Y476800D01*
X614417Y477050D01*
X614750Y477133D01*
X615083Y477050D01*
X615333Y476842D01*
X615458Y476467D01*
Y475467D01*
G01X616500Y478567D02*
X614000D01*
Y479608D01*
X614125Y479942D01*
X614292Y480150D01*
X614625Y480233D01*
X614958Y480150D01*
X615167Y479900D01*
X615292Y479608D01*
Y478567D01*
G01Y479608D02*
X616500Y480233D01*
G01Y482500D02*
X614000D01*
X614500Y482000D01*
G01X616500D02*
Y483000D01*
G01X616125Y484683D02*
X616333Y484933D01*
X616458Y485225D01*
X616500Y485600D01*
X616417Y485975D01*
X616250Y486267D01*
X615958Y486475D01*
X615625Y486517D01*
X615292Y486433D01*
X615083Y486225D01*
X614917Y485933D01*
X614875Y485642D01*
X614917Y485350D01*
X615083Y484975D01*
X614000Y485100D01*
Y486225D01*
G01X615458Y487908D02*
X615167Y488200D01*
X615000Y488450D01*
X614917Y488783D01*
X615000Y489075D01*
X615167Y489283D01*
X615417Y489450D01*
X615708Y489492D01*
X615958Y489450D01*
X616208Y489283D01*
X616417Y489033D01*
X616500Y488742D01*
X616417Y488408D01*
X616167Y488117D01*
X615792Y487950D01*
X615375Y487908D01*
X614833Y487992D01*
X614542Y488117D01*
X614250Y488325D01*
X614042Y488617D01*
X614000Y488908D01*
X614083Y489200D01*
X614292Y489408D01*
G01X618967Y477500D02*
Y480000D01*
X619967D01*
X620300Y479875D01*
X620550Y479583D01*
X620633Y479250D01*
X620550Y478917D01*
X620342Y478667D01*
X619967Y478542D01*
X618967D01*
G01X622067Y477500D02*
Y480000D01*
X623108D01*
X623442Y479875D01*
X623650Y479708D01*
X623733Y479375D01*
X623650Y479042D01*
X623400Y478833D01*
X623108Y478708D01*
X622067D01*
G01X623108D02*
X623733Y477500D01*
G01X626000D02*
Y480000D01*
X625500Y479500D01*
G01Y477500D02*
X626500D01*
G01X628308Y478542D02*
X628600Y478833D01*
X628850Y479000D01*
X629183Y479083D01*
X629475Y479000D01*
X629683Y478833D01*
X629850Y478583D01*
X629892Y478292D01*
X629850Y478042D01*
X629683Y477792D01*
X629433Y477583D01*
X629142Y477500D01*
X628808Y477583D01*
X628517Y477833D01*
X628350Y478208D01*
X628308Y478625D01*
X628392Y479167D01*
X628517Y479458D01*
X628725Y479750D01*
X629017Y479958D01*
X629308Y480000D01*
X629600Y479917D01*
X629808Y479708D01*
G01X631283Y477875D02*
X631533Y477667D01*
X631825Y477542D01*
X632200Y477500D01*
X632575Y477583D01*
X632867Y477750D01*
X633075Y478042D01*
X633117Y478375D01*
X633033Y478708D01*
X632825Y478917D01*
X632533Y479083D01*
X632242Y479125D01*
X631950Y479083D01*
X631575Y478917D01*
X631700Y480000D01*
X632825D01*
G01X618967Y482000D02*
Y484500D01*
X619967D01*
X620300Y484375D01*
X620550Y484083D01*
X620633Y483750D01*
X620550Y483417D01*
X620342Y483167D01*
X619967Y483042D01*
X618967D01*
G01X622067Y482000D02*
Y484500D01*
X623108D01*
X623442Y484375D01*
X623650Y484208D01*
X623733Y483875D01*
X623650Y483542D01*
X623400Y483333D01*
X623108Y483208D01*
X622067D01*
G01X623108D02*
X623733Y482000D01*
G01X626000D02*
Y484500D01*
X625500Y484000D01*
G01Y482000D02*
X626500D01*
G01X628308Y483042D02*
X628600Y483333D01*
X628850Y483500D01*
X629183Y483583D01*
X629475Y483500D01*
X629683Y483333D01*
X629850Y483083D01*
X629892Y482792D01*
X629850Y482542D01*
X629683Y482292D01*
X629433Y482083D01*
X629142Y482000D01*
X628808Y482083D01*
X628517Y482333D01*
X628350Y482708D01*
X628308Y483125D01*
X628392Y483667D01*
X628517Y483958D01*
X628725Y484250D01*
X629017Y484458D01*
X629308Y484500D01*
X629600Y484417D01*
X629808Y484208D01*
G01X632200Y482000D02*
Y484500D01*
X631700Y484000D01*
G01Y482000D02*
X632700D01*
G01X618967Y486000D02*
Y488500D01*
X619967D01*
X620300Y488375D01*
X620550Y488083D01*
X620633Y487750D01*
X620550Y487417D01*
X620342Y487167D01*
X619967Y487042D01*
X618967D01*
G01X623817Y488292D02*
X623567Y488417D01*
X623275Y488500D01*
X622942D01*
X622567Y488375D01*
X622275Y488167D01*
X622067Y487917D01*
X621900Y487500D01*
X621858Y487125D01*
X621942Y486750D01*
X622067Y486500D01*
X622317Y486250D01*
X622608Y486083D01*
X622900Y486000D01*
X623192D01*
X623483Y486083D01*
X623733Y486208D01*
X623942Y486375D01*
G01X626000Y486000D02*
Y488500D01*
X625500Y488000D01*
G01Y486000D02*
X626500D01*
G01X629100D02*
X629392Y486042D01*
X629725Y486167D01*
X629933Y486375D01*
X630017Y486667D01*
X629933Y486958D01*
X629683Y487208D01*
X629308Y487333D01*
X628892D01*
X628642Y487417D01*
X628433Y487625D01*
X628350Y487917D01*
X628475Y488208D01*
X628767Y488417D01*
X629100Y488500D01*
X629433Y488417D01*
X629725Y488208D01*
X629850Y487917D01*
X629767Y487625D01*
X629558Y487417D01*
X629308Y487333D01*
X628892D01*
X628517Y487208D01*
X628267Y486958D01*
X628183Y486667D01*
X628267Y486375D01*
X628475Y486167D01*
X628808Y486042D01*
X629100Y486000D01*
G01X631492Y486292D02*
X631783Y486083D01*
X632117Y486000D01*
X632450Y486083D01*
X632742Y486333D01*
X632950Y486708D01*
X633033Y487083D01*
Y487542D01*
X632950Y487917D01*
X632742Y488250D01*
X632492Y488417D01*
X632200Y488500D01*
X631867Y488417D01*
X631617Y488250D01*
X631450Y488000D01*
X631367Y487667D01*
X631450Y487375D01*
X631658Y487083D01*
X631908Y486917D01*
X632200Y486875D01*
X632533Y486958D01*
X632783Y487167D01*
X633033Y487542D01*
G01X634876Y90731D02*
X632376D01*
Y91772D01*
X632501Y92106D01*
X632668Y92314D01*
X633001Y92397D01*
X633334Y92314D01*
X633543Y92064D01*
X633668Y91772D01*
Y90731D01*
G01Y91772D02*
X634876Y92397D01*
G01Y95164D02*
X632376D01*
X634168Y93622D01*
Y95706D01*
G01X634876Y97764D02*
X632376D01*
X632876Y97264D01*
G01X634876D02*
Y98264D01*
G01X634376Y99947D02*
X634668Y100197D01*
X634834Y100531D01*
X634876Y100906D01*
X634834Y101239D01*
X634626Y101572D01*
X634376Y101781D01*
X634126Y101822D01*
X633834Y101739D01*
X633626Y101447D01*
X633543Y101156D01*
Y100781D01*
G01Y101156D02*
X633418Y101406D01*
X633209Y101614D01*
X632959Y101697D01*
X632709Y101614D01*
X632501Y101406D01*
X632376Y101031D01*
X632418Y100656D01*
X632584Y100281D01*
G01X630376Y90731D02*
X627876D01*
Y91772D01*
X628001Y92106D01*
X628168Y92314D01*
X628501Y92397D01*
X628834Y92314D01*
X629043Y92064D01*
X629168Y91772D01*
Y90731D01*
G01Y91772D02*
X630376Y92397D01*
G01Y95164D02*
X627876D01*
X629668Y93622D01*
Y95706D01*
G01X630376Y97764D02*
X627876D01*
X628376Y97264D01*
G01X630376D02*
Y98264D01*
G01Y101364D02*
X627876D01*
X629668Y99822D01*
Y101906D01*
G01X641376Y91514D02*
X645376D01*
Y98914D01*
G01X636876Y91514D02*
X640876D01*
Y98914D01*
G01X638000Y338000D02*
Y326800D01*
G01X640500D02*
Y338000D01*
G01X658500Y326800D02*
X640500D01*
G01X638000Y354000D02*
Y365200D01*
G01X640500D02*
Y354000D01*
G01X658500Y365200D02*
X640500D01*
G01X641500Y376967D02*
X639000D01*
Y377967D01*
X639125Y378300D01*
X639417Y378550D01*
X639750Y378633D01*
X640083Y378550D01*
X640333Y378342D01*
X640458Y377967D01*
Y376967D01*
G01X639208Y381817D02*
X639083Y381567D01*
X639000Y381275D01*
Y380942D01*
X639125Y380567D01*
X639333Y380275D01*
X639583Y380067D01*
X640000Y379900D01*
X640375Y379858D01*
X640750Y379942D01*
X641000Y380067D01*
X641250Y380317D01*
X641417Y380608D01*
X641500Y380900D01*
Y381192D01*
X641417Y381483D01*
X641292Y381733D01*
X641125Y381942D01*
G01X641500Y384000D02*
X639000D01*
X639500Y383500D01*
G01X641500D02*
Y384500D01*
G01Y387100D02*
X641458Y387392D01*
X641333Y387725D01*
X641125Y387933D01*
X640833Y388017D01*
X640542Y387933D01*
X640292Y387683D01*
X640167Y387308D01*
Y386892D01*
X640083Y386642D01*
X639875Y386433D01*
X639583Y386350D01*
X639292Y386475D01*
X639083Y386767D01*
X639000Y387100D01*
X639083Y387433D01*
X639292Y387725D01*
X639583Y387850D01*
X639875Y387767D01*
X640083Y387558D01*
X640167Y387308D01*
Y386892D01*
X640292Y386517D01*
X640542Y386267D01*
X640833Y386183D01*
X641125Y386267D01*
X641333Y386475D01*
X641458Y386808D01*
X641500Y387100D01*
G01Y390200D02*
X639000D01*
X639500Y389700D01*
G01X641500D02*
Y390700D01*
G01X641200Y451000D02*
Y455000D01*
X633800D01*
G01X641464Y465505D02*
X638964D01*
Y466505D01*
X639089Y466838D01*
X639381Y467088D01*
X639714Y467171D01*
X640047Y467088D01*
X640297Y466880D01*
X640422Y466505D01*
Y465505D01*
G01X641464Y468605D02*
X638964D01*
Y469646D01*
X639089Y469980D01*
X639256Y470188D01*
X639589Y470271D01*
X639922Y470188D01*
X640131Y469938D01*
X640256Y469646D01*
Y468605D01*
G01Y469646D02*
X641464Y470271D01*
G01Y472538D02*
X638964D01*
X639464Y472038D01*
G01X641464D02*
Y473038D01*
G01X641089Y474721D02*
X641297Y474971D01*
X641422Y475263D01*
X641464Y475638D01*
X641381Y476013D01*
X641214Y476305D01*
X640922Y476513D01*
X640589Y476555D01*
X640256Y476471D01*
X640047Y476263D01*
X639881Y475971D01*
X639839Y475680D01*
X639881Y475388D01*
X640047Y475013D01*
X638964Y475138D01*
Y476263D01*
G01X641464Y478655D02*
X640922Y478738D01*
X640464Y478863D01*
X640047Y479030D01*
X639589Y479238D01*
X638964Y479571D01*
Y477905D01*
G01X637464Y465505D02*
X634964D01*
Y466505D01*
X635089Y466838D01*
X635381Y467088D01*
X635714Y467171D01*
X636047Y467088D01*
X636297Y466880D01*
X636422Y466505D01*
Y465505D01*
G01X635172Y470355D02*
X635047Y470105D01*
X634964Y469813D01*
Y469480D01*
X635089Y469105D01*
X635297Y468813D01*
X635547Y468605D01*
X635964Y468438D01*
X636339Y468396D01*
X636714Y468480D01*
X636964Y468605D01*
X637214Y468855D01*
X637381Y469146D01*
X637464Y469438D01*
Y469730D01*
X637381Y470021D01*
X637256Y470271D01*
X637089Y470480D01*
G01X637464Y472538D02*
X634964D01*
X635464Y472038D01*
G01X637464D02*
Y473038D01*
G01Y475638D02*
X637422Y475930D01*
X637297Y476263D01*
X637089Y476471D01*
X636797Y476555D01*
X636506Y476471D01*
X636256Y476221D01*
X636131Y475846D01*
Y475430D01*
X636047Y475180D01*
X635839Y474971D01*
X635547Y474888D01*
X635256Y475013D01*
X635047Y475305D01*
X634964Y475638D01*
X635047Y475971D01*
X635256Y476263D01*
X635547Y476388D01*
X635839Y476305D01*
X636047Y476096D01*
X636131Y475846D01*
Y475430D01*
X636256Y475055D01*
X636506Y474805D01*
X636797Y474721D01*
X637089Y474805D01*
X637297Y475013D01*
X637422Y475346D01*
X637464Y475638D01*
G01Y478655D02*
X636922Y478738D01*
X636464Y478863D01*
X636047Y479030D01*
X635589Y479238D01*
X634964Y479571D01*
Y477905D01*
G01X640000Y489467D02*
X637500D01*
Y490467D01*
X637625Y490800D01*
X637917Y491050D01*
X638250Y491133D01*
X638583Y491050D01*
X638833Y490842D01*
X638958Y490467D01*
Y489467D01*
G01X640000Y492567D02*
X637500D01*
Y493608D01*
X637625Y493942D01*
X637792Y494150D01*
X638125Y494233D01*
X638458Y494150D01*
X638667Y493900D01*
X638792Y493608D01*
Y492567D01*
G01Y493608D02*
X640000Y494233D01*
G01Y496500D02*
X637500D01*
X638000Y496000D01*
G01X640000D02*
Y497000D01*
G01X638958Y498808D02*
X638667Y499100D01*
X638500Y499350D01*
X638417Y499683D01*
X638500Y499975D01*
X638667Y500183D01*
X638917Y500350D01*
X639208Y500392D01*
X639458Y500350D01*
X639708Y500183D01*
X639917Y499933D01*
X640000Y499642D01*
X639917Y499308D01*
X639667Y499017D01*
X639292Y498850D01*
X638875Y498808D01*
X638333Y498892D01*
X638042Y499017D01*
X637750Y499225D01*
X637542Y499517D01*
X637500Y499808D01*
X637583Y500100D01*
X637792Y500308D01*
G01X637917Y501908D02*
X637667Y502158D01*
X637542Y502450D01*
X637500Y502783D01*
X637583Y503200D01*
X637792Y503492D01*
X638042Y503575D01*
X638292Y503533D01*
X638500Y503367D01*
X638917Y502533D01*
X639208Y502158D01*
X639625Y501908D01*
X640000Y501825D01*
Y503575D01*
G01X638967Y506000D02*
Y508500D01*
X639967D01*
X640300Y508375D01*
X640550Y508083D01*
X640633Y507750D01*
X640550Y507417D01*
X640342Y507167D01*
X639967Y507042D01*
X638967D01*
G01X643817Y508292D02*
X643567Y508417D01*
X643275Y508500D01*
X642942D01*
X642567Y508375D01*
X642275Y508167D01*
X642067Y507917D01*
X641900Y507500D01*
X641858Y507125D01*
X641942Y506750D01*
X642067Y506500D01*
X642317Y506250D01*
X642608Y506083D01*
X642900Y506000D01*
X643192D01*
X643483Y506083D01*
X643733Y506208D01*
X643942Y506375D01*
G01X646000Y506000D02*
Y508500D01*
X645500Y508000D01*
G01Y506000D02*
X646500D01*
G01X648392Y506292D02*
X648683Y506083D01*
X649017Y506000D01*
X649350Y506083D01*
X649642Y506333D01*
X649850Y506708D01*
X649933Y507083D01*
Y507542D01*
X649850Y507917D01*
X649642Y508250D01*
X649392Y508417D01*
X649100Y508500D01*
X648767Y508417D01*
X648517Y508250D01*
X648350Y508000D01*
X648267Y507667D01*
X648350Y507375D01*
X648558Y507083D01*
X648808Y506917D01*
X649100Y506875D01*
X649433Y506958D01*
X649683Y507167D01*
X649933Y507542D01*
G01X652200Y508500D02*
X651867Y508417D01*
X651617Y508208D01*
X651450Y507958D01*
X651325Y507625D01*
X651283Y507250D01*
X651325Y506875D01*
X651450Y506542D01*
X651617Y506292D01*
X651867Y506083D01*
X652200Y506000D01*
X652533Y506083D01*
X652783Y506292D01*
X652950Y506542D01*
X653075Y506875D01*
X653117Y507250D01*
X653075Y507625D01*
X652950Y507958D01*
X652783Y508208D01*
X652533Y508417D01*
X652200Y508500D01*
G01X633700Y582000D02*
Y586000D01*
X626300D01*
G01X633700Y577000D02*
Y581000D01*
X626300D01*
G01X638975Y591333D02*
X639308Y591125D01*
X639683Y591000D01*
X640017D01*
X640350Y591125D01*
X640600Y591333D01*
X640725Y591625D01*
X640642Y591917D01*
X640433Y592167D01*
X640058Y592333D01*
X639558Y592417D01*
X639267Y592583D01*
X639142Y592875D01*
X639225Y593167D01*
X639433Y593375D01*
X639725Y593500D01*
X640017D01*
X640308Y593417D01*
X640558Y593208D01*
G01X642033Y593500D02*
Y591708D01*
X642200Y591333D01*
X642533Y591083D01*
X642950Y591000D01*
X643367Y591083D01*
X643700Y591333D01*
X643867Y591708D01*
Y593500D01*
G01X645258Y592042D02*
X645550Y592333D01*
X645800Y592500D01*
X646133Y592583D01*
X646425Y592500D01*
X646633Y592333D01*
X646800Y592083D01*
X646842Y591792D01*
X646800Y591542D01*
X646633Y591292D01*
X646383Y591083D01*
X646092Y591000D01*
X645758Y591083D01*
X645467Y591333D01*
X645300Y591708D01*
X645258Y592125D01*
X645342Y592667D01*
X645467Y592958D01*
X645675Y593250D01*
X645967Y593458D01*
X646258Y593500D01*
X646550Y593417D01*
X646758Y593208D01*
G01X648358Y593083D02*
X648608Y593333D01*
X648900Y593458D01*
X649233Y593500D01*
X649650Y593417D01*
X649942Y593208D01*
X650025Y592958D01*
X649983Y592708D01*
X649817Y592500D01*
X648983Y592083D01*
X648608Y591792D01*
X648358Y591375D01*
X648275Y591000D01*
X650025D01*
G01X633700Y586500D02*
Y590500D01*
X626300D01*
G01X636300Y615600D02*
Y604200D01*
G01D02*
X649700D01*
G01X633200Y604900D02*
Y608900D01*
X625800D01*
G01X633200Y610900D02*
Y614900D01*
X625800D01*
G01X637975Y618333D02*
X638308Y618125D01*
X638683Y618000D01*
X639017D01*
X639350Y618125D01*
X639600Y618333D01*
X639725Y618625D01*
X639642Y618917D01*
X639433Y619167D01*
X639058Y619333D01*
X638558Y619417D01*
X638267Y619583D01*
X638142Y619875D01*
X638225Y620167D01*
X638433Y620375D01*
X638725Y620500D01*
X639017D01*
X639308Y620417D01*
X639558Y620208D01*
G01X641033Y620500D02*
Y618708D01*
X641200Y618333D01*
X641533Y618083D01*
X641950Y618000D01*
X642367Y618083D01*
X642700Y618333D01*
X642867Y618708D01*
Y620500D01*
G01X644258Y619042D02*
X644550Y619333D01*
X644800Y619500D01*
X645133Y619583D01*
X645425Y619500D01*
X645633Y619333D01*
X645800Y619083D01*
X645842Y618792D01*
X645800Y618542D01*
X645633Y618292D01*
X645383Y618083D01*
X645092Y618000D01*
X644758Y618083D01*
X644467Y618333D01*
X644300Y618708D01*
X644258Y619125D01*
X644342Y619667D01*
X644467Y619958D01*
X644675Y620250D01*
X644967Y620458D01*
X645258Y620500D01*
X645550Y620417D01*
X645758Y620208D01*
G01X647233Y618500D02*
X647483Y618208D01*
X647817Y618042D01*
X648192Y618000D01*
X648525Y618042D01*
X648858Y618250D01*
X649067Y618500D01*
X649108Y618750D01*
X649025Y619042D01*
X648733Y619250D01*
X648442Y619333D01*
X648067D01*
G01X648442D02*
X648692Y619458D01*
X648900Y619667D01*
X648983Y619917D01*
X648900Y620167D01*
X648692Y620375D01*
X648317Y620500D01*
X647942Y620458D01*
X647567Y620292D01*
G01X649700Y615600D02*
X636300D01*
G01X653843Y100524D02*
Y103024D01*
X654884D01*
X655218Y102899D01*
X655426Y102732D01*
X655509Y102399D01*
X655426Y102066D01*
X655176Y101857D01*
X654884Y101732D01*
X653843D01*
G01X654884D02*
X655509Y100524D01*
G01X656859Y101024D02*
X657109Y100732D01*
X657443Y100566D01*
X657818Y100524D01*
X658151Y100566D01*
X658484Y100774D01*
X658693Y101024D01*
X658734Y101274D01*
X658651Y101566D01*
X658359Y101774D01*
X658068Y101857D01*
X657693D01*
G01X658068D02*
X658318Y101982D01*
X658526Y102191D01*
X658609Y102441D01*
X658526Y102691D01*
X658318Y102899D01*
X657943Y103024D01*
X657568Y102982D01*
X657193Y102816D01*
G01X660876Y100524D02*
X661168Y100566D01*
X661501Y100691D01*
X661709Y100899D01*
X661793Y101191D01*
X661709Y101482D01*
X661459Y101732D01*
X661084Y101857D01*
X660668D01*
X660418Y101941D01*
X660209Y102149D01*
X660126Y102441D01*
X660251Y102732D01*
X660543Y102941D01*
X660876Y103024D01*
X661209Y102941D01*
X661501Y102732D01*
X661626Y102441D01*
X661543Y102149D01*
X661334Y101941D01*
X661084Y101857D01*
X660668D01*
X660293Y101732D01*
X660043Y101482D01*
X659959Y101191D01*
X660043Y100899D01*
X660251Y100691D01*
X660584Y100566D01*
X660876Y100524D01*
G01X663976D02*
X664268Y100566D01*
X664601Y100691D01*
X664809Y100899D01*
X664893Y101191D01*
X664809Y101482D01*
X664559Y101732D01*
X664184Y101857D01*
X663768D01*
X663518Y101941D01*
X663309Y102149D01*
X663226Y102441D01*
X663351Y102732D01*
X663643Y102941D01*
X663976Y103024D01*
X664309Y102941D01*
X664601Y102732D01*
X664726Y102441D01*
X664643Y102149D01*
X664434Y101941D01*
X664184Y101857D01*
X663768D01*
X663393Y101732D01*
X663143Y101482D01*
X663059Y101191D01*
X663143Y100899D01*
X663351Y100691D01*
X663684Y100566D01*
X663976Y100524D01*
G01X653843Y105024D02*
Y107524D01*
X654884D01*
X655218Y107399D01*
X655426Y107232D01*
X655509Y106899D01*
X655426Y106566D01*
X655176Y106357D01*
X654884Y106232D01*
X653843D01*
G01X654884D02*
X655509Y105024D01*
G01X656859Y105524D02*
X657109Y105232D01*
X657443Y105066D01*
X657818Y105024D01*
X658151Y105066D01*
X658484Y105274D01*
X658693Y105524D01*
X658734Y105774D01*
X658651Y106066D01*
X658359Y106274D01*
X658068Y106357D01*
X657693D01*
G01X658068D02*
X658318Y106482D01*
X658526Y106691D01*
X658609Y106941D01*
X658526Y107191D01*
X658318Y107399D01*
X657943Y107524D01*
X657568Y107482D01*
X657193Y107316D01*
G01X660876Y105024D02*
X661168Y105066D01*
X661501Y105191D01*
X661709Y105399D01*
X661793Y105691D01*
X661709Y105982D01*
X661459Y106232D01*
X661084Y106357D01*
X660668D01*
X660418Y106441D01*
X660209Y106649D01*
X660126Y106941D01*
X660251Y107232D01*
X660543Y107441D01*
X660876Y107524D01*
X661209Y107441D01*
X661501Y107232D01*
X661626Y106941D01*
X661543Y106649D01*
X661334Y106441D01*
X661084Y106357D01*
X660668D01*
X660293Y106232D01*
X660043Y105982D01*
X659959Y105691D01*
X660043Y105399D01*
X660251Y105191D01*
X660584Y105066D01*
X660876Y105024D01*
G01X663268Y105316D02*
X663559Y105107D01*
X663893Y105024D01*
X664226Y105107D01*
X664518Y105357D01*
X664726Y105732D01*
X664809Y106107D01*
Y106566D01*
X664726Y106941D01*
X664518Y107274D01*
X664268Y107441D01*
X663976Y107524D01*
X663643Y107441D01*
X663393Y107274D01*
X663226Y107024D01*
X663143Y106691D01*
X663226Y106399D01*
X663434Y106107D01*
X663684Y105941D01*
X663976Y105899D01*
X664309Y105982D01*
X664559Y106191D01*
X664809Y106566D01*
G01X654876Y91514D02*
X658876D01*
Y98914D01*
G01X650376Y91514D02*
X654376D01*
Y98914D01*
G01X645876Y91514D02*
X649876D01*
Y98914D01*
G01X656722Y124609D02*
X654222D01*
Y125650D01*
X654347Y125984D01*
X654514Y126192D01*
X654847Y126275D01*
X655180Y126192D01*
X655389Y125942D01*
X655514Y125650D01*
Y124609D01*
G01Y125650D02*
X656722Y126275D01*
G01Y129042D02*
X654222D01*
X656014Y127500D01*
Y129584D01*
G01X654222Y131642D02*
X654305Y131309D01*
X654514Y131059D01*
X654764Y130892D01*
X655097Y130767D01*
X655472Y130725D01*
X655847Y130767D01*
X656180Y130892D01*
X656430Y131059D01*
X656639Y131309D01*
X656722Y131642D01*
X656639Y131975D01*
X656430Y132225D01*
X656180Y132392D01*
X655847Y132517D01*
X655472Y132559D01*
X655097Y132517D01*
X654764Y132392D01*
X654514Y132225D01*
X654305Y131975D01*
X654222Y131642D01*
G01X656722Y134742D02*
X654222D01*
X654722Y134242D01*
G01X656722D02*
Y135242D01*
G01X649956Y126267D02*
X649831Y126017D01*
X649748Y125725D01*
Y125392D01*
X649873Y125017D01*
X650081Y124725D01*
X650331Y124517D01*
X650748Y124350D01*
X651123Y124308D01*
X651498Y124392D01*
X651748Y124517D01*
X651998Y124767D01*
X652165Y125058D01*
X652248Y125350D01*
Y125642D01*
X652165Y125933D01*
X652040Y126183D01*
X651873Y126392D01*
G01X650165Y127658D02*
X649915Y127908D01*
X649790Y128200D01*
X649748Y128533D01*
X649831Y128950D01*
X650040Y129242D01*
X650290Y129325D01*
X650540Y129283D01*
X650748Y129117D01*
X651165Y128283D01*
X651456Y127908D01*
X651873Y127658D01*
X652248Y127575D01*
Y129325D01*
G01X651748Y130633D02*
X652040Y130883D01*
X652206Y131217D01*
X652248Y131592D01*
X652206Y131925D01*
X651998Y132258D01*
X651748Y132467D01*
X651498Y132508D01*
X651206Y132425D01*
X650998Y132133D01*
X650915Y131842D01*
Y131467D01*
G01Y131842D02*
X650790Y132092D01*
X650581Y132300D01*
X650331Y132383D01*
X650081Y132300D01*
X649873Y132092D01*
X649748Y131717D01*
X649790Y131342D01*
X649956Y130967D01*
G01X651206Y133858D02*
X650915Y134150D01*
X650748Y134400D01*
X650665Y134733D01*
X650748Y135025D01*
X650915Y135233D01*
X651165Y135400D01*
X651456Y135442D01*
X651706Y135400D01*
X651956Y135233D01*
X652165Y134983D01*
X652248Y134692D01*
X652165Y134358D01*
X651915Y134067D01*
X651540Y133900D01*
X651123Y133858D01*
X650581Y133942D01*
X650290Y134067D01*
X649998Y134275D01*
X649790Y134567D01*
X649748Y134858D01*
X649831Y135150D01*
X650040Y135358D01*
G01X644017Y368000D02*
Y370500D01*
X645017D01*
X645350Y370375D01*
X645600Y370083D01*
X645683Y369750D01*
X645600Y369417D01*
X645392Y369167D01*
X645017Y369042D01*
X644017D01*
G01X647950Y370500D02*
Y368000D01*
G01X646992Y370500D02*
X648908D01*
G01X651967Y370292D02*
X651717Y370417D01*
X651425Y370500D01*
X651092D01*
X650717Y370375D01*
X650425Y370167D01*
X650217Y369917D01*
X650050Y369500D01*
X650008Y369125D01*
X650092Y368750D01*
X650217Y368500D01*
X650467Y368250D01*
X650758Y368083D01*
X651050Y368000D01*
X651342D01*
X651633Y368083D01*
X651883Y368208D01*
X652092Y368375D01*
G01X654067Y368000D02*
X654150Y368542D01*
X654275Y369000D01*
X654442Y369417D01*
X654650Y369875D01*
X654983Y370500D01*
X653317D01*
G01X649500Y376967D02*
X647000D01*
Y377967D01*
X647125Y378300D01*
X647417Y378550D01*
X647750Y378633D01*
X648083Y378550D01*
X648333Y378342D01*
X648458Y377967D01*
Y376967D01*
G01X647208Y381817D02*
X647083Y381567D01*
X647000Y381275D01*
Y380942D01*
X647125Y380567D01*
X647333Y380275D01*
X647583Y380067D01*
X648000Y379900D01*
X648375Y379858D01*
X648750Y379942D01*
X649000Y380067D01*
X649250Y380317D01*
X649417Y380608D01*
X649500Y380900D01*
Y381192D01*
X649417Y381483D01*
X649292Y381733D01*
X649125Y381942D01*
G01X649500Y384000D02*
X647000D01*
X647500Y383500D01*
G01X649500D02*
Y384500D01*
G01Y387100D02*
X649458Y387392D01*
X649333Y387725D01*
X649125Y387933D01*
X648833Y388017D01*
X648542Y387933D01*
X648292Y387683D01*
X648167Y387308D01*
Y386892D01*
X648083Y386642D01*
X647875Y386433D01*
X647583Y386350D01*
X647292Y386475D01*
X647083Y386767D01*
X647000Y387100D01*
X647083Y387433D01*
X647292Y387725D01*
X647583Y387850D01*
X647875Y387767D01*
X648083Y387558D01*
X648167Y387308D01*
Y386892D01*
X648292Y386517D01*
X648542Y386267D01*
X648833Y386183D01*
X649125Y386267D01*
X649333Y386475D01*
X649458Y386808D01*
X649500Y387100D01*
G01X647000Y390200D02*
X647083Y389867D01*
X647292Y389617D01*
X647542Y389450D01*
X647875Y389325D01*
X648250Y389283D01*
X648625Y389325D01*
X648958Y389450D01*
X649208Y389617D01*
X649417Y389867D01*
X649500Y390200D01*
X649417Y390533D01*
X649208Y390783D01*
X648958Y390950D01*
X648625Y391075D01*
X648250Y391117D01*
X647875Y391075D01*
X647542Y390950D01*
X647292Y390783D01*
X647083Y390533D01*
X647000Y390200D01*
G01X658000Y376967D02*
X655500D01*
Y377967D01*
X655625Y378300D01*
X655917Y378550D01*
X656250Y378633D01*
X656583Y378550D01*
X656833Y378342D01*
X656958Y377967D01*
Y376967D01*
G01X655708Y381817D02*
X655583Y381567D01*
X655500Y381275D01*
Y380942D01*
X655625Y380567D01*
X655833Y380275D01*
X656083Y380067D01*
X656500Y379900D01*
X656875Y379858D01*
X657250Y379942D01*
X657500Y380067D01*
X657750Y380317D01*
X657917Y380608D01*
X658000Y380900D01*
Y381192D01*
X657917Y381483D01*
X657792Y381733D01*
X657625Y381942D01*
G01X658000Y384000D02*
X655500D01*
X656000Y383500D01*
G01X658000D02*
Y384500D01*
G01Y387100D02*
X657958Y387392D01*
X657833Y387725D01*
X657625Y387933D01*
X657333Y388017D01*
X657042Y387933D01*
X656792Y387683D01*
X656667Y387308D01*
Y386892D01*
X656583Y386642D01*
X656375Y386433D01*
X656083Y386350D01*
X655792Y386475D01*
X655583Y386767D01*
X655500Y387100D01*
X655583Y387433D01*
X655792Y387725D01*
X656083Y387850D01*
X656375Y387767D01*
X656583Y387558D01*
X656667Y387308D01*
Y386892D01*
X656792Y386517D01*
X657042Y386267D01*
X657333Y386183D01*
X657625Y386267D01*
X657833Y386475D01*
X657958Y386808D01*
X658000Y387100D01*
G01X657500Y389283D02*
X657792Y389533D01*
X657958Y389867D01*
X658000Y390242D01*
X657958Y390575D01*
X657750Y390908D01*
X657500Y391117D01*
X657250Y391158D01*
X656958Y391075D01*
X656750Y390783D01*
X656667Y390492D01*
Y390117D01*
G01Y390492D02*
X656542Y390742D01*
X656333Y390950D01*
X656083Y391033D01*
X655833Y390950D01*
X655625Y390742D01*
X655500Y390367D01*
X655542Y389992D01*
X655708Y389617D01*
G01X658164Y430538D02*
Y434538D01*
X650764D01*
G01X650200Y442500D02*
Y446500D01*
X642800D01*
G01X653700D02*
Y450500D01*
X646300D01*
G01X642800Y442000D02*
Y438000D01*
X650200D01*
G01X650764Y438538D02*
Y434538D01*
X658164D01*
G01X653964Y438838D02*
X657964D01*
Y446238D01*
G01X654500Y458500D02*
X658500D01*
Y448000D01*
G01X646300Y455000D02*
Y451000D01*
X653700D01*
G01X645517Y470000D02*
Y472500D01*
X646517D01*
X646850Y472375D01*
X647100Y472083D01*
X647183Y471750D01*
X647100Y471417D01*
X646892Y471167D01*
X646517Y471042D01*
X645517D01*
G01X648575Y470333D02*
X648908Y470125D01*
X649283Y470000D01*
X649617D01*
X649950Y470125D01*
X650200Y470333D01*
X650325Y470625D01*
X650242Y470917D01*
X650033Y471167D01*
X649658Y471333D01*
X649158Y471417D01*
X648867Y471583D01*
X648742Y471875D01*
X648825Y472167D01*
X649033Y472375D01*
X649325Y472500D01*
X649617D01*
X649908Y472417D01*
X650158Y472208D01*
G01X651717Y470000D02*
Y472500D01*
X652717D01*
X653050Y472375D01*
X653300Y472083D01*
X653383Y471750D01*
X653300Y471417D01*
X653092Y471167D01*
X652717Y471042D01*
X651717D01*
G01X654858Y472083D02*
X655108Y472333D01*
X655400Y472458D01*
X655733Y472500D01*
X656150Y472417D01*
X656442Y472208D01*
X656525Y471958D01*
X656483Y471708D01*
X656317Y471500D01*
X655483Y471083D01*
X655108Y470792D01*
X654858Y470375D01*
X654775Y470000D01*
X656525D01*
G01X652962Y478764D02*
X656962D01*
Y486164D01*
G01X661462D02*
X657462D01*
Y478764D01*
G01X644462Y489431D02*
X641962D01*
Y490431D01*
X642087Y490764D01*
X642379Y491014D01*
X642712Y491097D01*
X643045Y491014D01*
X643295Y490806D01*
X643420Y490431D01*
Y489431D01*
G01X644462Y492531D02*
X641962D01*
Y493572D01*
X642087Y493906D01*
X642254Y494114D01*
X642587Y494197D01*
X642920Y494114D01*
X643129Y493864D01*
X643254Y493572D01*
Y492531D01*
G01Y493572D02*
X644462Y494197D01*
G01Y496464D02*
X641962D01*
X642462Y495964D01*
G01X644462D02*
Y496964D01*
G01X644087Y498647D02*
X644295Y498897D01*
X644420Y499189D01*
X644462Y499564D01*
X644379Y499939D01*
X644212Y500231D01*
X643920Y500439D01*
X643587Y500481D01*
X643254Y500397D01*
X643045Y500189D01*
X642879Y499897D01*
X642837Y499606D01*
X642879Y499314D01*
X643045Y498939D01*
X641962Y499064D01*
Y500189D01*
G01X644462Y502664D02*
X644420Y502956D01*
X644295Y503289D01*
X644087Y503497D01*
X643795Y503581D01*
X643504Y503497D01*
X643254Y503247D01*
X643129Y502872D01*
Y502456D01*
X643045Y502206D01*
X642837Y501997D01*
X642545Y501914D01*
X642254Y502039D01*
X642045Y502331D01*
X641962Y502664D01*
X642045Y502997D01*
X642254Y503289D01*
X642545Y503414D01*
X642837Y503331D01*
X643045Y503122D01*
X643129Y502872D01*
Y502456D01*
X643254Y502081D01*
X643504Y501831D01*
X643795Y501747D01*
X644087Y501831D01*
X644295Y502039D01*
X644420Y502372D01*
X644462Y502664D01*
G01X653462Y489431D02*
X650962D01*
Y490431D01*
X651087Y490764D01*
X651379Y491014D01*
X651712Y491097D01*
X652045Y491014D01*
X652295Y490806D01*
X652420Y490431D01*
Y489431D01*
G01X653462Y492531D02*
X650962D01*
Y493572D01*
X651087Y493906D01*
X651254Y494114D01*
X651587Y494197D01*
X651920Y494114D01*
X652129Y493864D01*
X652254Y493572D01*
Y492531D01*
G01Y493572D02*
X653462Y494197D01*
G01Y496464D02*
X650962D01*
X651462Y495964D01*
G01X653462D02*
Y496964D01*
G01X652420Y498772D02*
X652129Y499064D01*
X651962Y499314D01*
X651879Y499647D01*
X651962Y499939D01*
X652129Y500147D01*
X652379Y500314D01*
X652670Y500356D01*
X652920Y500314D01*
X653170Y500147D01*
X653379Y499897D01*
X653462Y499606D01*
X653379Y499272D01*
X653129Y498981D01*
X652754Y498814D01*
X652337Y498772D01*
X651795Y498856D01*
X651504Y498981D01*
X651212Y499189D01*
X651004Y499481D01*
X650962Y499772D01*
X651045Y500064D01*
X651254Y500272D01*
G01X652962Y501747D02*
X653254Y501997D01*
X653420Y502331D01*
X653462Y502706D01*
X653420Y503039D01*
X653212Y503372D01*
X652962Y503581D01*
X652712Y503622D01*
X652420Y503539D01*
X652212Y503247D01*
X652129Y502956D01*
Y502581D01*
G01Y502956D02*
X652004Y503206D01*
X651795Y503414D01*
X651545Y503497D01*
X651295Y503414D01*
X651087Y503206D01*
X650962Y502831D01*
X651004Y502456D01*
X651170Y502081D01*
G01X648962Y489431D02*
X646462D01*
Y490431D01*
X646587Y490764D01*
X646879Y491014D01*
X647212Y491097D01*
X647545Y491014D01*
X647795Y490806D01*
X647920Y490431D01*
Y489431D01*
G01X648962Y492531D02*
X646462D01*
Y493572D01*
X646587Y493906D01*
X646754Y494114D01*
X647087Y494197D01*
X647420Y494114D01*
X647629Y493864D01*
X647754Y493572D01*
Y492531D01*
G01Y493572D02*
X648962Y494197D01*
G01Y496464D02*
X646462D01*
X646962Y495964D01*
G01X648962D02*
Y496964D01*
G01X647920Y498772D02*
X647629Y499064D01*
X647462Y499314D01*
X647379Y499647D01*
X647462Y499939D01*
X647629Y500147D01*
X647879Y500314D01*
X648170Y500356D01*
X648420Y500314D01*
X648670Y500147D01*
X648879Y499897D01*
X648962Y499606D01*
X648879Y499272D01*
X648629Y498981D01*
X648254Y498814D01*
X647837Y498772D01*
X647295Y498856D01*
X647004Y498981D01*
X646712Y499189D01*
X646504Y499481D01*
X646462Y499772D01*
X646545Y500064D01*
X646754Y500272D01*
G01X648962Y503164D02*
X646462D01*
X648254Y501622D01*
Y503706D01*
G01X648574Y585778D02*
Y575578D01*
G01X643974Y574878D02*
Y585778D01*
G01Y574878D02*
X655274D01*
G01X646274Y576078D02*
X645074Y574878D01*
G01X646274Y576078D02*
X647474Y574878D01*
G01X643974Y585778D02*
X648574D01*
G01X649700Y604200D02*
Y615600D01*
G01X652300Y608900D02*
Y604900D01*
X659700D01*
G01X652300Y615400D02*
Y611400D01*
X659700D01*
G01X668265Y48500D02*
Y51000D01*
X669306D01*
X669640Y50875D01*
X669848Y50708D01*
X669931Y50375D01*
X669848Y50042D01*
X669598Y49833D01*
X669306Y49708D01*
X668265D01*
G01X669306D02*
X669931Y48500D01*
G01X672698D02*
Y51000D01*
X671156Y49208D01*
X673240D01*
G01X674506Y50583D02*
X674756Y50833D01*
X675048Y50958D01*
X675381Y51000D01*
X675798Y50917D01*
X676090Y50708D01*
X676173Y50458D01*
X676131Y50208D01*
X675965Y50000D01*
X675131Y49583D01*
X674756Y49292D01*
X674506Y48875D01*
X674423Y48500D01*
X676173D01*
G01X678398Y51000D02*
X678065Y50917D01*
X677815Y50708D01*
X677648Y50458D01*
X677523Y50125D01*
X677481Y49750D01*
X677523Y49375D01*
X677648Y49042D01*
X677815Y48792D01*
X678065Y48583D01*
X678398Y48500D01*
X678731Y48583D01*
X678981Y48792D01*
X679148Y49042D01*
X679273Y49375D01*
X679315Y49750D01*
X679273Y50125D01*
X679148Y50458D01*
X678981Y50708D01*
X678731Y50917D01*
X678398Y51000D01*
G01X668265Y41500D02*
Y44000D01*
X669306D01*
X669640Y43875D01*
X669848Y43708D01*
X669931Y43375D01*
X669848Y43042D01*
X669598Y42833D01*
X669306Y42708D01*
X668265D01*
G01X669306D02*
X669931Y41500D01*
G01X672698D02*
Y44000D01*
X671156Y42208D01*
X673240D01*
G01X675298Y41500D02*
Y44000D01*
X674798Y43500D01*
G01Y41500D02*
X675798D01*
G01X677481Y41875D02*
X677731Y41667D01*
X678023Y41542D01*
X678398Y41500D01*
X678773Y41583D01*
X679065Y41750D01*
X679273Y42042D01*
X679315Y42375D01*
X679231Y42708D01*
X679023Y42917D01*
X678731Y43083D01*
X678440Y43125D01*
X678148Y43083D01*
X677773Y42917D01*
X677898Y44000D01*
X679023D01*
G01X675000Y71017D02*
X672500D01*
Y72058D01*
X672625Y72392D01*
X672792Y72600D01*
X673125Y72683D01*
X673458Y72600D01*
X673667Y72350D01*
X673792Y72058D01*
Y71017D01*
G01Y72058D02*
X675000Y72683D01*
G01Y75450D02*
X672500D01*
X674292Y73908D01*
Y75992D01*
G01X672500Y78050D02*
X672583Y77717D01*
X672792Y77467D01*
X673042Y77300D01*
X673375Y77175D01*
X673750Y77133D01*
X674125Y77175D01*
X674458Y77300D01*
X674708Y77467D01*
X674917Y77717D01*
X675000Y78050D01*
X674917Y78383D01*
X674708Y78633D01*
X674458Y78800D01*
X674125Y78925D01*
X673750Y78967D01*
X673375Y78925D01*
X673042Y78800D01*
X672792Y78633D01*
X672583Y78383D01*
X672500Y78050D01*
G01X674500Y80233D02*
X674792Y80483D01*
X674958Y80817D01*
X675000Y81192D01*
X674958Y81525D01*
X674750Y81858D01*
X674500Y82067D01*
X674250Y82108D01*
X673958Y82025D01*
X673750Y81733D01*
X673667Y81442D01*
Y81067D01*
G01Y81442D02*
X673542Y81692D01*
X673333Y81900D01*
X673083Y81983D01*
X672833Y81900D01*
X672625Y81692D01*
X672500Y81317D01*
X672542Y80942D01*
X672708Y80567D01*
G01X672666Y84844D02*
X676666D01*
Y92244D01*
G01X670000Y79017D02*
X667500D01*
Y80058D01*
X667625Y80392D01*
X667792Y80600D01*
X668125Y80683D01*
X668458Y80600D01*
X668667Y80350D01*
X668792Y80058D01*
Y79017D01*
G01Y80058D02*
X670000Y80683D01*
G01Y83450D02*
X667500D01*
X669292Y81908D01*
Y83992D01*
G01X667500Y86050D02*
X667583Y85717D01*
X667792Y85467D01*
X668042Y85300D01*
X668375Y85175D01*
X668750Y85133D01*
X669125Y85175D01*
X669458Y85300D01*
X669708Y85467D01*
X669917Y85717D01*
X670000Y86050D01*
X669917Y86383D01*
X669708Y86633D01*
X669458Y86800D01*
X669125Y86925D01*
X668750Y86967D01*
X668375Y86925D01*
X668042Y86800D01*
X667792Y86633D01*
X667583Y86383D01*
X667500Y86050D01*
G01X670000Y89650D02*
X667500D01*
X669292Y88108D01*
Y90192D01*
G01X666000Y79017D02*
X663500D01*
Y80058D01*
X663625Y80392D01*
X663792Y80600D01*
X664125Y80683D01*
X664458Y80600D01*
X664667Y80350D01*
X664792Y80058D01*
Y79017D01*
G01Y80058D02*
X666000Y80683D01*
G01Y83450D02*
X663500D01*
X665292Y81908D01*
Y83992D01*
G01X663500Y86050D02*
X663583Y85717D01*
X663792Y85467D01*
X664042Y85300D01*
X664375Y85175D01*
X664750Y85133D01*
X665125Y85175D01*
X665458Y85300D01*
X665708Y85467D01*
X665917Y85717D01*
X666000Y86050D01*
X665917Y86383D01*
X665708Y86633D01*
X665458Y86800D01*
X665125Y86925D01*
X664750Y86967D01*
X664375Y86925D01*
X664042Y86800D01*
X663792Y86633D01*
X663583Y86383D01*
X663500Y86050D01*
G01X664958Y88358D02*
X664667Y88650D01*
X664500Y88900D01*
X664417Y89233D01*
X664500Y89525D01*
X664667Y89733D01*
X664917Y89900D01*
X665208Y89942D01*
X665458Y89900D01*
X665708Y89733D01*
X665917Y89483D01*
X666000Y89192D01*
X665917Y88858D01*
X665667Y88567D01*
X665292Y88400D01*
X664875Y88358D01*
X664333Y88442D01*
X664042Y88567D01*
X663750Y88775D01*
X663542Y89067D01*
X663500Y89358D01*
X663583Y89650D01*
X663792Y89858D01*
G01X659376Y91514D02*
X663376D01*
Y98914D01*
G01X679366Y92544D02*
Y96544D01*
X671966D01*
G01X667208Y98267D02*
X667083Y98017D01*
X667000Y97725D01*
Y97392D01*
X667125Y97017D01*
X667333Y96725D01*
X667583Y96517D01*
X668000Y96350D01*
X668375Y96308D01*
X668750Y96392D01*
X669000Y96517D01*
X669250Y96767D01*
X669417Y97058D01*
X669500Y97350D01*
Y97642D01*
X669417Y97933D01*
X669292Y98183D01*
X669125Y98392D01*
G01X667417Y99658D02*
X667167Y99908D01*
X667042Y100200D01*
X667000Y100533D01*
X667083Y100950D01*
X667292Y101242D01*
X667542Y101325D01*
X667792Y101283D01*
X668000Y101117D01*
X668417Y100283D01*
X668708Y99908D01*
X669125Y99658D01*
X669500Y99575D01*
Y101325D01*
G01X669000Y102633D02*
X669292Y102883D01*
X669458Y103217D01*
X669500Y103592D01*
X669458Y103925D01*
X669250Y104258D01*
X669000Y104467D01*
X668750Y104508D01*
X668458Y104425D01*
X668250Y104133D01*
X668167Y103842D01*
Y103467D01*
G01Y103842D02*
X668042Y104092D01*
X667833Y104300D01*
X667583Y104383D01*
X667333Y104300D01*
X667125Y104092D01*
X667000Y103717D01*
X667042Y103342D01*
X667208Y102967D01*
G01X669125Y105733D02*
X669333Y105983D01*
X669458Y106275D01*
X669500Y106650D01*
X669417Y107025D01*
X669250Y107317D01*
X668958Y107525D01*
X668625Y107567D01*
X668292Y107483D01*
X668083Y107275D01*
X667917Y106983D01*
X667875Y106692D01*
X667917Y106400D01*
X668083Y106025D01*
X667000Y106150D01*
Y107275D01*
G01X661517Y114500D02*
Y117000D01*
X662558D01*
X662892Y116875D01*
X663100Y116708D01*
X663183Y116375D01*
X663100Y116042D01*
X662850Y115833D01*
X662558Y115708D01*
X661517D01*
G01X662558D02*
X663183Y114500D01*
G01X664533Y115000D02*
X664783Y114708D01*
X665117Y114542D01*
X665492Y114500D01*
X665825Y114542D01*
X666158Y114750D01*
X666367Y115000D01*
X666408Y115250D01*
X666325Y115542D01*
X666033Y115750D01*
X665742Y115833D01*
X665367D01*
G01X665742D02*
X665992Y115958D01*
X666200Y116167D01*
X666283Y116417D01*
X666200Y116667D01*
X665992Y116875D01*
X665617Y117000D01*
X665242Y116958D01*
X664867Y116792D01*
G01X667842Y114792D02*
X668133Y114583D01*
X668467Y114500D01*
X668800Y114583D01*
X669092Y114833D01*
X669300Y115208D01*
X669383Y115583D01*
Y116042D01*
X669300Y116417D01*
X669092Y116750D01*
X668842Y116917D01*
X668550Y117000D01*
X668217Y116917D01*
X667967Y116750D01*
X667800Y116500D01*
X667717Y116167D01*
X667800Y115875D01*
X668008Y115583D01*
X668258Y115417D01*
X668550Y115375D01*
X668883Y115458D01*
X669133Y115667D01*
X669383Y116042D01*
G01X671567Y114500D02*
X671650Y115042D01*
X671775Y115500D01*
X671942Y115917D01*
X672150Y116375D01*
X672483Y117000D01*
X670817D01*
G01X674686Y118464D02*
X679886D01*
G01X674686Y111464D02*
X682486D01*
G01X674686Y118464D02*
Y111464D01*
G01X660767Y111792D02*
X660517Y111917D01*
X660225Y112000D01*
X659892D01*
X659517Y111875D01*
X659225Y111667D01*
X659017Y111417D01*
X658850Y111000D01*
X658808Y110625D01*
X658892Y110250D01*
X659017Y110000D01*
X659267Y109750D01*
X659558Y109583D01*
X659850Y109500D01*
X660142D01*
X660433Y109583D01*
X660683Y109708D01*
X660892Y109875D01*
G01X662158Y111583D02*
X662408Y111833D01*
X662700Y111958D01*
X663033Y112000D01*
X663450Y111917D01*
X663742Y111708D01*
X663825Y111458D01*
X663783Y111208D01*
X663617Y111000D01*
X662783Y110583D01*
X662408Y110292D01*
X662158Y109875D01*
X662075Y109500D01*
X663825D01*
G01X665133Y110000D02*
X665383Y109708D01*
X665717Y109542D01*
X666092Y109500D01*
X666425Y109542D01*
X666758Y109750D01*
X666967Y110000D01*
X667008Y110250D01*
X666925Y110542D01*
X666633Y110750D01*
X666342Y110833D01*
X665967D01*
G01X666342D02*
X666592Y110958D01*
X666800Y111167D01*
X666883Y111417D01*
X666800Y111667D01*
X666592Y111875D01*
X666217Y112000D01*
X665842Y111958D01*
X665467Y111792D01*
G01X669067Y109500D02*
X669150Y110042D01*
X669275Y110500D01*
X669442Y110917D01*
X669650Y111375D01*
X669983Y112000D01*
X668317D01*
G01X663015Y122292D02*
X662765Y122417D01*
X662473Y122500D01*
X662140D01*
X661765Y122375D01*
X661473Y122167D01*
X661265Y121917D01*
X661098Y121500D01*
X661056Y121125D01*
X661140Y120750D01*
X661265Y120500D01*
X661515Y120250D01*
X661806Y120083D01*
X662098Y120000D01*
X662390D01*
X662681Y120083D01*
X662931Y120208D01*
X663140Y120375D01*
G01X664406Y122083D02*
X664656Y122333D01*
X664948Y122458D01*
X665281Y122500D01*
X665698Y122417D01*
X665990Y122208D01*
X666073Y121958D01*
X666031Y121708D01*
X665865Y121500D01*
X665031Y121083D01*
X664656Y120792D01*
X664406Y120375D01*
X664323Y120000D01*
X666073D01*
G01X667381Y120500D02*
X667631Y120208D01*
X667965Y120042D01*
X668340Y120000D01*
X668673Y120042D01*
X669006Y120250D01*
X669215Y120500D01*
X669256Y120750D01*
X669173Y121042D01*
X668881Y121250D01*
X668590Y121333D01*
X668215D01*
G01X668590D02*
X668840Y121458D01*
X669048Y121667D01*
X669131Y121917D01*
X669048Y122167D01*
X668840Y122375D01*
X668465Y122500D01*
X668090Y122458D01*
X667715Y122292D01*
G01X671898Y120000D02*
Y122500D01*
X670356Y120708D01*
X672440D01*
G01X660882Y124459D02*
X658382D01*
Y125500D01*
X658507Y125834D01*
X658674Y126042D01*
X659007Y126125D01*
X659340Y126042D01*
X659549Y125792D01*
X659674Y125500D01*
Y124459D01*
G01Y125500D02*
X660882Y126125D01*
G01X660382Y127475D02*
X660674Y127725D01*
X660840Y128059D01*
X660882Y128434D01*
X660840Y128767D01*
X660632Y129100D01*
X660382Y129309D01*
X660132Y129350D01*
X659840Y129267D01*
X659632Y128975D01*
X659549Y128684D01*
Y128309D01*
G01Y128684D02*
X659424Y128934D01*
X659215Y129142D01*
X658965Y129225D01*
X658715Y129142D01*
X658507Y128934D01*
X658382Y128559D01*
X658424Y128184D01*
X658590Y127809D01*
G01X660882Y131492D02*
X660840Y131784D01*
X660715Y132117D01*
X660507Y132325D01*
X660215Y132409D01*
X659924Y132325D01*
X659674Y132075D01*
X659549Y131700D01*
Y131284D01*
X659465Y131034D01*
X659257Y130825D01*
X658965Y130742D01*
X658674Y130867D01*
X658465Y131159D01*
X658382Y131492D01*
X658465Y131825D01*
X658674Y132117D01*
X658965Y132242D01*
X659257Y132159D01*
X659465Y131950D01*
X659549Y131700D01*
Y131284D01*
X659674Y130909D01*
X659924Y130659D01*
X660215Y130575D01*
X660507Y130659D01*
X660715Y130867D01*
X660840Y131200D01*
X660882Y131492D01*
G01X660507Y133675D02*
X660715Y133925D01*
X660840Y134217D01*
X660882Y134592D01*
X660799Y134967D01*
X660632Y135259D01*
X660340Y135467D01*
X660007Y135509D01*
X659674Y135425D01*
X659465Y135217D01*
X659299Y134925D01*
X659257Y134634D01*
X659299Y134342D01*
X659465Y133967D01*
X658382Y134092D01*
Y135217D01*
G01X664932Y124529D02*
X662432D01*
Y125570D01*
X662557Y125904D01*
X662724Y126112D01*
X663057Y126195D01*
X663390Y126112D01*
X663599Y125862D01*
X663724Y125570D01*
Y124529D01*
G01Y125570D02*
X664932Y126195D01*
G01X664432Y127545D02*
X664724Y127795D01*
X664890Y128129D01*
X664932Y128504D01*
X664890Y128837D01*
X664682Y129170D01*
X664432Y129379D01*
X664182Y129420D01*
X663890Y129337D01*
X663682Y129045D01*
X663599Y128754D01*
Y128379D01*
G01Y128754D02*
X663474Y129004D01*
X663265Y129212D01*
X663015Y129295D01*
X662765Y129212D01*
X662557Y129004D01*
X662432Y128629D01*
X662474Y128254D01*
X662640Y127879D01*
G01X664932Y131562D02*
X664890Y131854D01*
X664765Y132187D01*
X664557Y132395D01*
X664265Y132479D01*
X663974Y132395D01*
X663724Y132145D01*
X663599Y131770D01*
Y131354D01*
X663515Y131104D01*
X663307Y130895D01*
X663015Y130812D01*
X662724Y130937D01*
X662515Y131229D01*
X662432Y131562D01*
X662515Y131895D01*
X662724Y132187D01*
X663015Y132312D01*
X663307Y132229D01*
X663515Y132020D01*
X663599Y131770D01*
Y131354D01*
X663724Y130979D01*
X663974Y130729D01*
X664265Y130645D01*
X664557Y130729D01*
X664765Y130937D01*
X664890Y131270D01*
X664932Y131562D01*
G01X663890Y133870D02*
X663599Y134162D01*
X663432Y134412D01*
X663349Y134745D01*
X663432Y135037D01*
X663599Y135245D01*
X663849Y135412D01*
X664140Y135454D01*
X664390Y135412D01*
X664640Y135245D01*
X664849Y134995D01*
X664932Y134704D01*
X664849Y134370D01*
X664599Y134079D01*
X664224Y133912D01*
X663807Y133870D01*
X663265Y133954D01*
X662974Y134079D01*
X662682Y134287D01*
X662474Y134579D01*
X662432Y134870D01*
X662515Y135162D01*
X662724Y135370D01*
G01X674265Y138000D02*
Y140500D01*
X675306D01*
X675640Y140375D01*
X675848Y140208D01*
X675931Y139875D01*
X675848Y139542D01*
X675598Y139333D01*
X675306Y139208D01*
X674265D01*
G01X675306D02*
X675931Y138000D01*
G01X677281Y138500D02*
X677531Y138208D01*
X677865Y138042D01*
X678240Y138000D01*
X678573Y138042D01*
X678906Y138250D01*
X679115Y138500D01*
X679156Y138750D01*
X679073Y139042D01*
X678781Y139250D01*
X678490Y139333D01*
X678115D01*
G01X678490D02*
X678740Y139458D01*
X678948Y139667D01*
X679031Y139917D01*
X678948Y140167D01*
X678740Y140375D01*
X678365Y140500D01*
X677990Y140458D01*
X677615Y140292D01*
G01X681298Y138000D02*
X681590Y138042D01*
X681923Y138167D01*
X682131Y138375D01*
X682215Y138667D01*
X682131Y138958D01*
X681881Y139208D01*
X681506Y139333D01*
X681090D01*
X680840Y139417D01*
X680631Y139625D01*
X680548Y139917D01*
X680673Y140208D01*
X680965Y140417D01*
X681298Y140500D01*
X681631Y140417D01*
X681923Y140208D01*
X682048Y139917D01*
X681965Y139625D01*
X681756Y139417D01*
X681506Y139333D01*
X681090D01*
X680715Y139208D01*
X680465Y138958D01*
X680381Y138667D01*
X680465Y138375D01*
X680673Y138167D01*
X681006Y138042D01*
X681298Y138000D01*
G01X683606Y140083D02*
X683856Y140333D01*
X684148Y140458D01*
X684481Y140500D01*
X684898Y140417D01*
X685190Y140208D01*
X685273Y139958D01*
X685231Y139708D01*
X685065Y139500D01*
X684231Y139083D01*
X683856Y138792D01*
X683606Y138375D01*
X683523Y138000D01*
X685273D01*
G01X669012Y124469D02*
X666512D01*
Y125510D01*
X666637Y125844D01*
X666804Y126052D01*
X667137Y126135D01*
X667470Y126052D01*
X667679Y125802D01*
X667804Y125510D01*
Y124469D01*
G01Y125510D02*
X669012Y126135D01*
G01Y128902D02*
X666512D01*
X668304Y127360D01*
Y129444D01*
G01X666512Y131502D02*
X666595Y131169D01*
X666804Y130919D01*
X667054Y130752D01*
X667387Y130627D01*
X667762Y130585D01*
X668137Y130627D01*
X668470Y130752D01*
X668720Y130919D01*
X668929Y131169D01*
X669012Y131502D01*
X668929Y131835D01*
X668720Y132085D01*
X668470Y132252D01*
X668137Y132377D01*
X667762Y132419D01*
X667387Y132377D01*
X667054Y132252D01*
X666804Y132085D01*
X666595Y131835D01*
X666512Y131502D01*
G01X666929Y133810D02*
X666679Y134060D01*
X666554Y134352D01*
X666512Y134685D01*
X666595Y135102D01*
X666804Y135394D01*
X667054Y135477D01*
X667304Y135435D01*
X667512Y135269D01*
X667929Y134435D01*
X668220Y134060D01*
X668637Y133810D01*
X669012Y133727D01*
Y135477D01*
G01X673263Y248767D02*
X673138Y248517D01*
X673055Y248225D01*
Y247892D01*
X673180Y247517D01*
X673388Y247225D01*
X673638Y247017D01*
X674055Y246850D01*
X674430Y246808D01*
X674805Y246892D01*
X675055Y247017D01*
X675305Y247267D01*
X675472Y247558D01*
X675555Y247850D01*
Y248142D01*
X675472Y248433D01*
X675347Y248683D01*
X675180Y248892D01*
G01X673472Y250158D02*
X673222Y250408D01*
X673097Y250700D01*
X673055Y251033D01*
X673138Y251450D01*
X673347Y251742D01*
X673597Y251825D01*
X673847Y251783D01*
X674055Y251617D01*
X674472Y250783D01*
X674763Y250408D01*
X675180Y250158D01*
X675555Y250075D01*
Y251825D01*
G01X675263Y253342D02*
X675472Y253633D01*
X675555Y253967D01*
X675472Y254300D01*
X675222Y254592D01*
X674847Y254800D01*
X674472Y254883D01*
X674013D01*
X673638Y254800D01*
X673305Y254592D01*
X673138Y254342D01*
X673055Y254050D01*
X673138Y253717D01*
X673305Y253467D01*
X673555Y253300D01*
X673888Y253217D01*
X674180Y253300D01*
X674472Y253508D01*
X674638Y253758D01*
X674680Y254050D01*
X674597Y254383D01*
X674388Y254633D01*
X674013Y254883D01*
G01X675180Y256233D02*
X675388Y256483D01*
X675513Y256775D01*
X675555Y257150D01*
X675472Y257525D01*
X675305Y257817D01*
X675013Y258025D01*
X674680Y258067D01*
X674347Y257983D01*
X674138Y257775D01*
X673972Y257483D01*
X673930Y257192D01*
X673972Y256900D01*
X674138Y256525D01*
X673055Y256650D01*
Y257775D01*
G01X658500Y338000D02*
Y326800D01*
G01X665800Y339500D02*
X677000D01*
G01X665800Y357500D02*
Y339500D01*
G01X677000Y357500D02*
X665800D01*
G01X658500Y354000D02*
Y365200D01*
G01X665800Y360000D02*
X677000D01*
G01X665800Y378000D02*
Y360000D01*
G01X662150Y380900D02*
X694850D01*
Y428100D01*
X662150D01*
Y380900D01*
G01X677000Y378000D02*
X665800D01*
G01X660467Y430000D02*
Y432500D01*
X661467D01*
X661800Y432375D01*
X662050Y432083D01*
X662133Y431750D01*
X662050Y431417D01*
X661842Y431167D01*
X661467Y431042D01*
X660467D01*
G01X663567Y430000D02*
Y432500D01*
X664608D01*
X664942Y432375D01*
X665150Y432208D01*
X665233Y431875D01*
X665150Y431542D01*
X664900Y431333D01*
X664608Y431208D01*
X663567D01*
G01X664608D02*
X665233Y430000D01*
G01X667500D02*
Y432500D01*
X667000Y432000D01*
G01Y430000D02*
X668000D01*
G01X669808Y431042D02*
X670100Y431333D01*
X670350Y431500D01*
X670683Y431583D01*
X670975Y431500D01*
X671183Y431333D01*
X671350Y431083D01*
X671392Y430792D01*
X671350Y430542D01*
X671183Y430292D01*
X670933Y430083D01*
X670642Y430000D01*
X670308Y430083D01*
X670017Y430333D01*
X669850Y430708D01*
X669808Y431125D01*
X669892Y431667D01*
X670017Y431958D01*
X670225Y432250D01*
X670517Y432458D01*
X670808Y432500D01*
X671100Y432417D01*
X671308Y432208D01*
G01X673700Y432500D02*
X673367Y432417D01*
X673117Y432208D01*
X672950Y431958D01*
X672825Y431625D01*
X672783Y431250D01*
X672825Y430875D01*
X672950Y430542D01*
X673117Y430292D01*
X673367Y430083D01*
X673700Y430000D01*
X674033Y430083D01*
X674283Y430292D01*
X674450Y430542D01*
X674575Y430875D01*
X674617Y431250D01*
X674575Y431625D01*
X674450Y431958D01*
X674283Y432208D01*
X674033Y432417D01*
X673700Y432500D01*
G01X660517Y434500D02*
Y437000D01*
X661558D01*
X661892Y436875D01*
X662100Y436708D01*
X662183Y436375D01*
X662100Y436042D01*
X661850Y435833D01*
X661558Y435708D01*
X660517D01*
G01X661558D02*
X662183Y434500D01*
G01X663658Y435542D02*
X663950Y435833D01*
X664200Y436000D01*
X664533Y436083D01*
X664825Y436000D01*
X665033Y435833D01*
X665200Y435583D01*
X665242Y435292D01*
X665200Y435042D01*
X665033Y434792D01*
X664783Y434583D01*
X664492Y434500D01*
X664158Y434583D01*
X663867Y434833D01*
X663700Y435208D01*
X663658Y435625D01*
X663742Y436167D01*
X663867Y436458D01*
X664075Y436750D01*
X664367Y436958D01*
X664658Y437000D01*
X664950Y436917D01*
X665158Y436708D01*
G01X667550Y434500D02*
Y437000D01*
X667050Y436500D01*
G01Y434500D02*
X668050D01*
G01X670650Y437000D02*
X670317Y436917D01*
X670067Y436708D01*
X669900Y436458D01*
X669775Y436125D01*
X669733Y435750D01*
X669775Y435375D01*
X669900Y435042D01*
X670067Y434792D01*
X670317Y434583D01*
X670650Y434500D01*
X670983Y434583D01*
X671233Y434792D01*
X671400Y435042D01*
X671525Y435375D01*
X671567Y435750D01*
X671525Y436125D01*
X671400Y436458D01*
X671233Y436708D01*
X670983Y436917D01*
X670650Y437000D01*
G01X670993Y443621D02*
Y441621D01*
G01X663962Y470314D02*
X658962D01*
Y465314D01*
G01X667056Y469307D02*
Y472307D01*
G01X666462Y478764D02*
X670462D01*
Y486164D01*
G01X661962Y478764D02*
X665962D01*
Y486164D01*
G01X666400Y535300D02*
Y512700D01*
G01D02*
X676600D01*
G01X666400Y535300D02*
Y512700D01*
G01D02*
X676600D01*
G01X662500Y521067D02*
X660000D01*
Y522067D01*
X660125Y522400D01*
X660417Y522650D01*
X660750Y522733D01*
X661083Y522650D01*
X661333Y522442D01*
X661458Y522067D01*
Y521067D01*
G01X660000Y524167D02*
X662500D01*
Y525833D01*
G01Y528100D02*
X662458Y528392D01*
X662333Y528725D01*
X662125Y528933D01*
X661833Y529017D01*
X661542Y528933D01*
X661292Y528683D01*
X661167Y528308D01*
Y527892D01*
X661083Y527642D01*
X660875Y527433D01*
X660583Y527350D01*
X660292Y527475D01*
X660083Y527767D01*
X660000Y528100D01*
X660083Y528433D01*
X660292Y528725D01*
X660583Y528850D01*
X660875Y528767D01*
X661083Y528558D01*
X661167Y528308D01*
Y527892D01*
X661292Y527517D01*
X661542Y527267D01*
X661833Y527183D01*
X662125Y527267D01*
X662333Y527475D01*
X662458Y527808D01*
X662500Y528100D01*
G01X676600Y535300D02*
X666400D01*
G01X676600D02*
X666400D01*
G01X662425Y606233D02*
X662758Y606025D01*
X663133Y605900D01*
X663467D01*
X663800Y606025D01*
X664050Y606233D01*
X664175Y606525D01*
X664092Y606817D01*
X663883Y607067D01*
X663508Y607233D01*
X663008Y607317D01*
X662717Y607483D01*
X662592Y607775D01*
X662675Y608067D01*
X662883Y608275D01*
X663175Y608400D01*
X663467D01*
X663758Y608317D01*
X664008Y608108D01*
G01X665567Y605900D02*
Y608400D01*
X666608D01*
X666942Y608275D01*
X667150Y608108D01*
X667233Y607775D01*
X667150Y607442D01*
X666900Y607233D01*
X666608Y607108D01*
X665567D01*
G01X666608D02*
X667233Y605900D01*
G01X669417D02*
X669500Y606442D01*
X669625Y606900D01*
X669792Y607317D01*
X670000Y607775D01*
X670333Y608400D01*
X668667D01*
G01X671683Y606400D02*
X671933Y606108D01*
X672267Y605942D01*
X672642Y605900D01*
X672975Y605942D01*
X673308Y606150D01*
X673517Y606400D01*
X673558Y606650D01*
X673475Y606942D01*
X673183Y607150D01*
X672892Y607233D01*
X672517D01*
G01X672892D02*
X673142Y607358D01*
X673350Y607567D01*
X673433Y607817D01*
X673350Y608067D01*
X673142Y608275D01*
X672767Y608400D01*
X672392Y608358D01*
X672017Y608192D01*
G01X675700Y608400D02*
X675367Y608317D01*
X675117Y608108D01*
X674950Y607858D01*
X674825Y607525D01*
X674783Y607150D01*
X674825Y606775D01*
X674950Y606442D01*
X675117Y606192D01*
X675367Y605983D01*
X675700Y605900D01*
X676033Y605983D01*
X676283Y606192D01*
X676450Y606442D01*
X676575Y606775D01*
X676617Y607150D01*
X676575Y607525D01*
X676450Y607858D01*
X676283Y608108D01*
X676033Y608317D01*
X675700Y608400D01*
G01X662425Y612733D02*
X662758Y612525D01*
X663133Y612400D01*
X663467D01*
X663800Y612525D01*
X664050Y612733D01*
X664175Y613025D01*
X664092Y613317D01*
X663883Y613567D01*
X663508Y613733D01*
X663008Y613817D01*
X662717Y613983D01*
X662592Y614275D01*
X662675Y614567D01*
X662883Y614775D01*
X663175Y614900D01*
X663467D01*
X663758Y614817D01*
X664008Y614608D01*
G01X665567Y612400D02*
Y614900D01*
X666608D01*
X666942Y614775D01*
X667150Y614608D01*
X667233Y614275D01*
X667150Y613942D01*
X666900Y613733D01*
X666608Y613608D01*
X665567D01*
G01X666608D02*
X667233Y612400D01*
G01X669417D02*
X669500Y612942D01*
X669625Y613400D01*
X669792Y613817D01*
X670000Y614275D01*
X670333Y614900D01*
X668667D01*
G01X671808Y614483D02*
X672058Y614733D01*
X672350Y614858D01*
X672683Y614900D01*
X673100Y614817D01*
X673392Y614608D01*
X673475Y614358D01*
X673433Y614108D01*
X673267Y613900D01*
X672433Y613483D01*
X672058Y613192D01*
X671808Y612775D01*
X671725Y612400D01*
X673475D01*
G01X675700D02*
X675992Y612442D01*
X676325Y612567D01*
X676533Y612775D01*
X676617Y613067D01*
X676533Y613358D01*
X676283Y613608D01*
X675908Y613733D01*
X675492D01*
X675242Y613817D01*
X675033Y614025D01*
X674950Y614317D01*
X675075Y614608D01*
X675367Y614817D01*
X675700Y614900D01*
X676033Y614817D01*
X676325Y614608D01*
X676450Y614317D01*
X676367Y614025D01*
X676158Y613817D01*
X675908Y613733D01*
X675492D01*
X675117Y613608D01*
X674867Y613358D01*
X674783Y613067D01*
X674867Y612775D01*
X675075Y612567D01*
X675408Y612442D01*
X675700Y612400D01*
G01X671032Y764533D02*
X668532D01*
Y765574D01*
X668657Y765908D01*
X668824Y766116D01*
X669157Y766199D01*
X669490Y766116D01*
X669699Y765866D01*
X669824Y765574D01*
Y764533D01*
G01Y765574D02*
X671032Y766199D01*
G01Y768466D02*
X668532D01*
X669032Y767966D01*
G01X671032D02*
Y768966D01*
G01X670657Y770649D02*
X670865Y770899D01*
X670990Y771191D01*
X671032Y771566D01*
X670949Y771941D01*
X670782Y772233D01*
X670490Y772441D01*
X670157Y772483D01*
X669824Y772399D01*
X669615Y772191D01*
X669449Y771899D01*
X669407Y771608D01*
X669449Y771316D01*
X669615Y770941D01*
X668532Y771066D01*
Y772191D01*
G01X670532Y773749D02*
X670824Y773999D01*
X670990Y774333D01*
X671032Y774708D01*
X670990Y775041D01*
X670782Y775374D01*
X670532Y775583D01*
X670282Y775624D01*
X669990Y775541D01*
X669782Y775249D01*
X669699Y774958D01*
Y774583D01*
G01Y774958D02*
X669574Y775208D01*
X669365Y775416D01*
X669115Y775499D01*
X668865Y775416D01*
X668657Y775208D01*
X668532Y774833D01*
X668574Y774458D01*
X668740Y774083D01*
G01X672800Y770500D02*
Y766500D01*
X680200D01*
G01X667985Y796284D02*
Y798784D01*
X669026D01*
X669360Y798659D01*
X669568Y798492D01*
X669651Y798159D01*
X669568Y797826D01*
X669318Y797617D01*
X669026Y797492D01*
X667985D01*
G01X669026D02*
X669651Y796284D01*
G01X671918D02*
Y798784D01*
X671418Y798284D01*
G01Y796284D02*
X672418D01*
G01X674101Y796659D02*
X674351Y796451D01*
X674643Y796326D01*
X675018Y796284D01*
X675393Y796367D01*
X675685Y796534D01*
X675893Y796826D01*
X675935Y797159D01*
X675851Y797492D01*
X675643Y797701D01*
X675351Y797867D01*
X675060Y797909D01*
X674768Y797867D01*
X674393Y797701D01*
X674518Y798784D01*
X675643D01*
G01X678118Y796284D02*
Y798784D01*
X677618Y798284D01*
G01Y796284D02*
X678618D01*
G01X667985Y805984D02*
Y808484D01*
X669026D01*
X669360Y808359D01*
X669568Y808192D01*
X669651Y807859D01*
X669568Y807526D01*
X669318Y807317D01*
X669026Y807192D01*
X667985D01*
G01X669026D02*
X669651Y805984D01*
G01X672418D02*
Y808484D01*
X670876Y806692D01*
X672960D01*
G01X674226Y808067D02*
X674476Y808317D01*
X674768Y808442D01*
X675101Y808484D01*
X675518Y808401D01*
X675810Y808192D01*
X675893Y807942D01*
X675851Y807692D01*
X675685Y807484D01*
X674851Y807067D01*
X674476Y806776D01*
X674226Y806359D01*
X674143Y805984D01*
X675893D01*
G01X678618D02*
Y808484D01*
X677076Y806692D01*
X679160D01*
G01X667985Y800984D02*
Y803484D01*
X669026D01*
X669360Y803359D01*
X669568Y803192D01*
X669651Y802859D01*
X669568Y802526D01*
X669318Y802317D01*
X669026Y802192D01*
X667985D01*
G01X669026D02*
X669651Y800984D01*
G01X672418D02*
Y803484D01*
X670876Y801692D01*
X672960D01*
G01X674226Y803067D02*
X674476Y803317D01*
X674768Y803442D01*
X675101Y803484D01*
X675518Y803401D01*
X675810Y803192D01*
X675893Y802942D01*
X675851Y802692D01*
X675685Y802484D01*
X674851Y802067D01*
X674476Y801776D01*
X674226Y801359D01*
X674143Y800984D01*
X675893D01*
G01X677201Y801484D02*
X677451Y801192D01*
X677785Y801026D01*
X678160Y800984D01*
X678493Y801026D01*
X678826Y801234D01*
X679035Y801484D01*
X679076Y801734D01*
X678993Y802026D01*
X678701Y802234D01*
X678410Y802317D01*
X678035D01*
G01X678410D02*
X678660Y802442D01*
X678868Y802651D01*
X678951Y802901D01*
X678868Y803151D01*
X678660Y803359D01*
X678285Y803484D01*
X677910Y803442D01*
X677535Y803276D01*
G01X678265Y80500D02*
Y83000D01*
X679306D01*
X679640Y82875D01*
X679848Y82708D01*
X679931Y82375D01*
X679848Y82042D01*
X679598Y81833D01*
X679306Y81708D01*
X678265D01*
G01X679306D02*
X679931Y80500D01*
G01X681281Y81000D02*
X681531Y80708D01*
X681865Y80542D01*
X682240Y80500D01*
X682573Y80542D01*
X682906Y80750D01*
X683115Y81000D01*
X683156Y81250D01*
X683073Y81542D01*
X682781Y81750D01*
X682490Y81833D01*
X682115D01*
G01X682490D02*
X682740Y81958D01*
X682948Y82167D01*
X683031Y82417D01*
X682948Y82667D01*
X682740Y82875D01*
X682365Y83000D01*
X681990Y82958D01*
X681615Y82792D01*
G01X684590Y80792D02*
X684881Y80583D01*
X685215Y80500D01*
X685548Y80583D01*
X685840Y80833D01*
X686048Y81208D01*
X686131Y81583D01*
Y82042D01*
X686048Y82417D01*
X685840Y82750D01*
X685590Y82917D01*
X685298Y83000D01*
X684965Y82917D01*
X684715Y82750D01*
X684548Y82500D01*
X684465Y82167D01*
X684548Y81875D01*
X684756Y81583D01*
X685006Y81417D01*
X685298Y81375D01*
X685631Y81458D01*
X685881Y81667D01*
X686131Y82042D01*
G01X688398Y80500D02*
X688690Y80542D01*
X689023Y80667D01*
X689231Y80875D01*
X689315Y81167D01*
X689231Y81458D01*
X688981Y81708D01*
X688606Y81833D01*
X688190D01*
X687940Y81917D01*
X687731Y82125D01*
X687648Y82417D01*
X687773Y82708D01*
X688065Y82917D01*
X688398Y83000D01*
X688731Y82917D01*
X689023Y82708D01*
X689148Y82417D01*
X689065Y82125D01*
X688856Y81917D01*
X688606Y81833D01*
X688190D01*
X687815Y81708D01*
X687565Y81458D01*
X687481Y81167D01*
X687565Y80875D01*
X687773Y80667D01*
X688106Y80542D01*
X688398Y80500D01*
G01X677466Y85044D02*
X685266D01*
G01X677466Y92044D02*
Y85044D01*
G01X690866D02*
Y92044D01*
G01X684466Y85044D02*
X690866D01*
G01X677466Y92044D02*
X682666D01*
G01X690866D02*
X682166D01*
G01X676126Y101024D02*
Y97024D01*
X683526D01*
G01X676126Y105524D02*
Y101524D01*
X683526D01*
G01X679876Y96934D02*
Y92934D01*
X687276D01*
G01X679886Y109744D02*
Y105744D01*
X687286D01*
G01X688086Y118464D02*
X679386D01*
G01X688086Y111464D02*
Y118464D01*
G01X681686Y111464D02*
X688086D01*
G01X684382Y128142D02*
X680382D01*
Y120742D01*
G01X680222Y128292D02*
X676222D01*
Y120892D01*
G01X688432Y131712D02*
X684432D01*
Y124312D01*
G01X692512Y131652D02*
X688512D01*
Y124252D01*
G01X682548Y145000D02*
Y142500D01*
G01X681590Y145000D02*
X683506D01*
G01X684815Y142500D02*
Y145000D01*
X685815D01*
X686148Y144875D01*
X686398Y144583D01*
X686481Y144250D01*
X686398Y143917D01*
X686190Y143667D01*
X685815Y143542D01*
X684815D01*
G01X688748Y142500D02*
Y145000D01*
X688248Y144500D01*
G01Y142500D02*
X689248D01*
G01X691056Y144583D02*
X691306Y144833D01*
X691598Y144958D01*
X691931Y145000D01*
X692348Y144917D01*
X692640Y144708D01*
X692723Y144458D01*
X692681Y144208D01*
X692515Y144000D01*
X691681Y143583D01*
X691306Y143292D01*
X691056Y142875D01*
X690973Y142500D01*
X692723D01*
G01X694948D02*
X695240Y142542D01*
X695573Y142667D01*
X695781Y142875D01*
X695865Y143167D01*
X695781Y143458D01*
X695531Y143708D01*
X695156Y143833D01*
X694740D01*
X694490Y143917D01*
X694281Y144125D01*
X694198Y144417D01*
X694323Y144708D01*
X694615Y144917D01*
X694948Y145000D01*
X695281Y144917D01*
X695573Y144708D01*
X695698Y144417D01*
X695615Y144125D01*
X695406Y143917D01*
X695156Y143833D01*
X694740D01*
X694365Y143708D01*
X694115Y143458D01*
X694031Y143167D01*
X694115Y142875D01*
X694323Y142667D01*
X694656Y142542D01*
X694948Y142500D01*
G01X696416Y135784D02*
Y139784D01*
X689016D01*
G01X681263Y248767D02*
X681138Y248517D01*
X681055Y248225D01*
Y247892D01*
X681180Y247517D01*
X681388Y247225D01*
X681638Y247017D01*
X682055Y246850D01*
X682430Y246808D01*
X682805Y246892D01*
X683055Y247017D01*
X683305Y247267D01*
X683472Y247558D01*
X683555Y247850D01*
Y248142D01*
X683472Y248433D01*
X683347Y248683D01*
X683180Y248892D01*
G01X681472Y250158D02*
X681222Y250408D01*
X681097Y250700D01*
X681055Y251033D01*
X681138Y251450D01*
X681347Y251742D01*
X681597Y251825D01*
X681847Y251783D01*
X682055Y251617D01*
X682472Y250783D01*
X682763Y250408D01*
X683180Y250158D01*
X683555Y250075D01*
Y251825D01*
G01X683263Y253342D02*
X683472Y253633D01*
X683555Y253967D01*
X683472Y254300D01*
X683222Y254592D01*
X682847Y254800D01*
X682472Y254883D01*
X682013D01*
X681638Y254800D01*
X681305Y254592D01*
X681138Y254342D01*
X681055Y254050D01*
X681138Y253717D01*
X681305Y253467D01*
X681555Y253300D01*
X681888Y253217D01*
X682180Y253300D01*
X682472Y253508D01*
X682638Y253758D01*
X682680Y254050D01*
X682597Y254383D01*
X682388Y254633D01*
X682013Y254883D01*
G01X681472Y256358D02*
X681222Y256608D01*
X681097Y256900D01*
X681055Y257233D01*
X681138Y257650D01*
X681347Y257942D01*
X681597Y258025D01*
X681847Y257983D01*
X682055Y257817D01*
X682472Y256983D01*
X682763Y256608D01*
X683180Y256358D01*
X683555Y256275D01*
Y258025D01*
G01X685263Y248767D02*
X685138Y248517D01*
X685055Y248225D01*
Y247892D01*
X685180Y247517D01*
X685388Y247225D01*
X685638Y247017D01*
X686055Y246850D01*
X686430Y246808D01*
X686805Y246892D01*
X687055Y247017D01*
X687305Y247267D01*
X687472Y247558D01*
X687555Y247850D01*
Y248142D01*
X687472Y248433D01*
X687347Y248683D01*
X687180Y248892D01*
G01X685472Y250158D02*
X685222Y250408D01*
X685097Y250700D01*
X685055Y251033D01*
X685138Y251450D01*
X685347Y251742D01*
X685597Y251825D01*
X685847Y251783D01*
X686055Y251617D01*
X686472Y250783D01*
X686763Y250408D01*
X687180Y250158D01*
X687555Y250075D01*
Y251825D01*
G01X687263Y253342D02*
X687472Y253633D01*
X687555Y253967D01*
X687472Y254300D01*
X687222Y254592D01*
X686847Y254800D01*
X686472Y254883D01*
X686013D01*
X685638Y254800D01*
X685305Y254592D01*
X685138Y254342D01*
X685055Y254050D01*
X685138Y253717D01*
X685305Y253467D01*
X685555Y253300D01*
X685888Y253217D01*
X686180Y253300D01*
X686472Y253508D01*
X686638Y253758D01*
X686680Y254050D01*
X686597Y254383D01*
X686388Y254633D01*
X686013Y254883D01*
G01X687055Y256233D02*
X687347Y256483D01*
X687513Y256817D01*
X687555Y257192D01*
X687513Y257525D01*
X687305Y257858D01*
X687055Y258067D01*
X686805Y258108D01*
X686513Y258025D01*
X686305Y257733D01*
X686222Y257442D01*
Y257067D01*
G01Y257442D02*
X686097Y257692D01*
X685888Y257900D01*
X685638Y257983D01*
X685388Y257900D01*
X685180Y257692D01*
X685055Y257317D01*
X685097Y256942D01*
X685263Y256567D01*
G01X677263Y248767D02*
X677138Y248517D01*
X677055Y248225D01*
Y247892D01*
X677180Y247517D01*
X677388Y247225D01*
X677638Y247017D01*
X678055Y246850D01*
X678430Y246808D01*
X678805Y246892D01*
X679055Y247017D01*
X679305Y247267D01*
X679472Y247558D01*
X679555Y247850D01*
Y248142D01*
X679472Y248433D01*
X679347Y248683D01*
X679180Y248892D01*
G01X677472Y250158D02*
X677222Y250408D01*
X677097Y250700D01*
X677055Y251033D01*
X677138Y251450D01*
X677347Y251742D01*
X677597Y251825D01*
X677847Y251783D01*
X678055Y251617D01*
X678472Y250783D01*
X678763Y250408D01*
X679180Y250158D01*
X679555Y250075D01*
Y251825D01*
G01X679263Y253342D02*
X679472Y253633D01*
X679555Y253967D01*
X679472Y254300D01*
X679222Y254592D01*
X678847Y254800D01*
X678472Y254883D01*
X678013D01*
X677638Y254800D01*
X677305Y254592D01*
X677138Y254342D01*
X677055Y254050D01*
X677138Y253717D01*
X677305Y253467D01*
X677555Y253300D01*
X677888Y253217D01*
X678180Y253300D01*
X678472Y253508D01*
X678638Y253758D01*
X678680Y254050D01*
X678597Y254383D01*
X678388Y254633D01*
X678013Y254883D01*
G01X679555Y257650D02*
X677055D01*
X678847Y256108D01*
Y258192D01*
G01X691055Y271800D02*
X693555D01*
G01X691055Y270842D02*
Y272758D01*
G01X693555Y274067D02*
X691055D01*
Y275067D01*
X691180Y275400D01*
X691472Y275650D01*
X691805Y275733D01*
X692138Y275650D01*
X692388Y275442D01*
X692513Y275067D01*
Y274067D01*
G01X693555Y278000D02*
X691055D01*
X691555Y277500D01*
G01X693555D02*
Y278500D01*
G01X693180Y280183D02*
X693388Y280433D01*
X693513Y280725D01*
X693555Y281100D01*
X693472Y281475D01*
X693305Y281767D01*
X693013Y281975D01*
X692680Y282017D01*
X692347Y281933D01*
X692138Y281725D01*
X691972Y281433D01*
X691930Y281142D01*
X691972Y280850D01*
X692138Y280475D01*
X691055Y280600D01*
Y281725D01*
G01X693555Y284117D02*
X693013Y284200D01*
X692555Y284325D01*
X692138Y284492D01*
X691680Y284700D01*
X691055Y285033D01*
Y283367D01*
G01X682567Y430500D02*
Y433000D01*
X683567D01*
X683900Y432875D01*
X684150Y432583D01*
X684233Y432250D01*
X684150Y431917D01*
X683942Y431667D01*
X683567Y431542D01*
X682567D01*
G01X685667Y433000D02*
Y430500D01*
X687333D01*
G01X688892Y430792D02*
X689183Y430583D01*
X689517Y430500D01*
X689850Y430583D01*
X690142Y430833D01*
X690350Y431208D01*
X690433Y431583D01*
Y432042D01*
X690350Y432417D01*
X690142Y432750D01*
X689892Y432917D01*
X689600Y433000D01*
X689267Y432917D01*
X689017Y432750D01*
X688850Y432500D01*
X688767Y432167D01*
X688850Y431875D01*
X689058Y431583D01*
X689308Y431417D01*
X689600Y431375D01*
X689933Y431458D01*
X690183Y431667D01*
X690433Y432042D01*
G01X681962Y442614D02*
X686962D01*
Y447614D01*
G01X680836Y443621D02*
Y440621D01*
G01X689462Y439764D02*
Y444964D01*
G01Y439764D02*
X696462D01*
G01X689462Y453164D02*
Y444464D01*
G01X689517Y464500D02*
Y467000D01*
X690517D01*
X690850Y466875D01*
X691100Y466583D01*
X691183Y466250D01*
X691100Y465917D01*
X690892Y465667D01*
X690517Y465542D01*
X689517D01*
G01X692533Y467000D02*
Y465208D01*
X692700Y464833D01*
X693033Y464583D01*
X693450Y464500D01*
X693867Y464583D01*
X694200Y464833D01*
X694367Y465208D01*
Y467000D01*
G01X696550Y464500D02*
Y467000D01*
X696050Y466500D01*
G01Y464500D02*
X697050D01*
G01X698858Y466583D02*
X699108Y466833D01*
X699400Y466958D01*
X699733Y467000D01*
X700150Y466917D01*
X700442Y466708D01*
X700525Y466458D01*
X700483Y466208D01*
X700317Y466000D01*
X699483Y465583D01*
X699108Y465292D01*
X698858Y464875D01*
X698775Y464500D01*
X700525D01*
G01X686962Y465314D02*
Y470314D01*
X681962D01*
G01X696462Y453164D02*
X689462D01*
G01X676899Y469307D02*
Y471307D01*
G01X676600Y512700D02*
Y535300D01*
G01Y512700D02*
Y535300D01*
G01X689425Y575333D02*
X689758Y575125D01*
X690133Y575000D01*
X690467D01*
X690800Y575125D01*
X691050Y575333D01*
X691175Y575625D01*
X691092Y575917D01*
X690883Y576167D01*
X690508Y576333D01*
X690008Y576417D01*
X689717Y576583D01*
X689592Y576875D01*
X689675Y577167D01*
X689883Y577375D01*
X690175Y577500D01*
X690467D01*
X690758Y577417D01*
X691008Y577208D01*
G01X692567Y575000D02*
Y577500D01*
X693608D01*
X693942Y577375D01*
X694150Y577208D01*
X694233Y576875D01*
X694150Y576542D01*
X693900Y576333D01*
X693608Y576208D01*
X692567D01*
G01X693608D02*
X694233Y575000D01*
G01X695792Y575292D02*
X696083Y575083D01*
X696417Y575000D01*
X696750Y575083D01*
X697042Y575333D01*
X697250Y575708D01*
X697333Y576083D01*
Y576542D01*
X697250Y576917D01*
X697042Y577250D01*
X696792Y577417D01*
X696500Y577500D01*
X696167Y577417D01*
X695917Y577250D01*
X695750Y577000D01*
X695667Y576667D01*
X695750Y576375D01*
X695958Y576083D01*
X696208Y575917D01*
X696500Y575875D01*
X696833Y575958D01*
X697083Y576167D01*
X697333Y576542D01*
G01X699600Y575000D02*
Y577500D01*
X699100Y577000D01*
G01Y575000D02*
X700100D01*
G01X702617D02*
X702700Y575542D01*
X702825Y576000D01*
X702992Y576417D01*
X703200Y576875D01*
X703533Y577500D01*
X701867D01*
G01X689425Y580833D02*
X689758Y580625D01*
X690133Y580500D01*
X690467D01*
X690800Y580625D01*
X691050Y580833D01*
X691175Y581125D01*
X691092Y581417D01*
X690883Y581667D01*
X690508Y581833D01*
X690008Y581917D01*
X689717Y582083D01*
X689592Y582375D01*
X689675Y582667D01*
X689883Y582875D01*
X690175Y583000D01*
X690467D01*
X690758Y582917D01*
X691008Y582708D01*
G01X692567Y580500D02*
Y583000D01*
X693608D01*
X693942Y582875D01*
X694150Y582708D01*
X694233Y582375D01*
X694150Y582042D01*
X693900Y581833D01*
X693608Y581708D01*
X692567D01*
G01X693608D02*
X694233Y580500D01*
G01X695792Y580792D02*
X696083Y580583D01*
X696417Y580500D01*
X696750Y580583D01*
X697042Y580833D01*
X697250Y581208D01*
X697333Y581583D01*
Y582042D01*
X697250Y582417D01*
X697042Y582750D01*
X696792Y582917D01*
X696500Y583000D01*
X696167Y582917D01*
X695917Y582750D01*
X695750Y582500D01*
X695667Y582167D01*
X695750Y581875D01*
X695958Y581583D01*
X696208Y581417D01*
X696500Y581375D01*
X696833Y581458D01*
X697083Y581667D01*
X697333Y582042D01*
G01X699600Y580500D02*
Y583000D01*
X699100Y582500D01*
G01Y580500D02*
X700100D01*
G01X702700D02*
X702992Y580542D01*
X703325Y580667D01*
X703533Y580875D01*
X703617Y581167D01*
X703533Y581458D01*
X703283Y581708D01*
X702908Y581833D01*
X702492D01*
X702242Y581917D01*
X702033Y582125D01*
X701950Y582417D01*
X702075Y582708D01*
X702367Y582917D01*
X702700Y583000D01*
X703033Y582917D01*
X703325Y582708D01*
X703450Y582417D01*
X703367Y582125D01*
X703158Y581917D01*
X702908Y581833D01*
X702492D01*
X702117Y581708D01*
X701867Y581458D01*
X701783Y581167D01*
X701867Y580875D01*
X702075Y580667D01*
X702408Y580542D01*
X702700Y580500D01*
G01X689425Y570833D02*
X689758Y570625D01*
X690133Y570500D01*
X690467D01*
X690800Y570625D01*
X691050Y570833D01*
X691175Y571125D01*
X691092Y571417D01*
X690883Y571667D01*
X690508Y571833D01*
X690008Y571917D01*
X689717Y572083D01*
X689592Y572375D01*
X689675Y572667D01*
X689883Y572875D01*
X690175Y573000D01*
X690467D01*
X690758Y572917D01*
X691008Y572708D01*
G01X692567Y570500D02*
Y573000D01*
X693608D01*
X693942Y572875D01*
X694150Y572708D01*
X694233Y572375D01*
X694150Y572042D01*
X693900Y571833D01*
X693608Y571708D01*
X692567D01*
G01X693608D02*
X694233Y570500D01*
G01X695792Y570792D02*
X696083Y570583D01*
X696417Y570500D01*
X696750Y570583D01*
X697042Y570833D01*
X697250Y571208D01*
X697333Y571583D01*
Y572042D01*
X697250Y572417D01*
X697042Y572750D01*
X696792Y572917D01*
X696500Y573000D01*
X696167Y572917D01*
X695917Y572750D01*
X695750Y572500D01*
X695667Y572167D01*
X695750Y571875D01*
X695958Y571583D01*
X696208Y571417D01*
X696500Y571375D01*
X696833Y571458D01*
X697083Y571667D01*
X697333Y572042D01*
G01X699600Y570500D02*
Y573000D01*
X699100Y572500D01*
G01Y570500D02*
X700100D01*
G01X701992Y570792D02*
X702283Y570583D01*
X702617Y570500D01*
X702950Y570583D01*
X703242Y570833D01*
X703450Y571208D01*
X703533Y571583D01*
Y572042D01*
X703450Y572417D01*
X703242Y572750D01*
X702992Y572917D01*
X702700Y573000D01*
X702367Y572917D01*
X702117Y572750D01*
X701950Y572500D01*
X701867Y572167D01*
X701950Y571875D01*
X702158Y571583D01*
X702408Y571417D01*
X702700Y571375D01*
X703033Y571458D01*
X703283Y571667D01*
X703533Y572042D01*
G01X687875Y566833D02*
X688208Y566625D01*
X688583Y566500D01*
X688917D01*
X689250Y566625D01*
X689500Y566833D01*
X689625Y567125D01*
X689542Y567417D01*
X689333Y567667D01*
X688958Y567833D01*
X688458Y567917D01*
X688167Y568083D01*
X688042Y568375D01*
X688125Y568667D01*
X688333Y568875D01*
X688625Y569000D01*
X688917D01*
X689208Y568917D01*
X689458Y568708D01*
G01X692767Y568792D02*
X692517Y568917D01*
X692225Y569000D01*
X691892D01*
X691517Y568875D01*
X691225Y568667D01*
X691017Y568417D01*
X690850Y568000D01*
X690808Y567625D01*
X690892Y567250D01*
X691017Y567000D01*
X691267Y566750D01*
X691558Y566583D01*
X691850Y566500D01*
X692142D01*
X692433Y566583D01*
X692683Y566708D01*
X692892Y566875D01*
G01X694950Y566500D02*
Y569000D01*
X694450Y568500D01*
G01Y566500D02*
X695450D01*
G01X697258Y568583D02*
X697508Y568833D01*
X697800Y568958D01*
X698133Y569000D01*
X698550Y568917D01*
X698842Y568708D01*
X698925Y568458D01*
X698883Y568208D01*
X698717Y568000D01*
X697883Y567583D01*
X697508Y567292D01*
X697258Y566875D01*
X697175Y566500D01*
X698925D01*
G01X700442Y566792D02*
X700733Y566583D01*
X701067Y566500D01*
X701400Y566583D01*
X701692Y566833D01*
X701900Y567208D01*
X701983Y567583D01*
Y568042D01*
X701900Y568417D01*
X701692Y568750D01*
X701442Y568917D01*
X701150Y569000D01*
X700817Y568917D01*
X700567Y568750D01*
X700400Y568500D01*
X700317Y568167D01*
X700400Y567875D01*
X700608Y567583D01*
X700858Y567417D01*
X701150Y567375D01*
X701483Y567458D01*
X701733Y567667D01*
X701983Y568042D01*
G01X703333Y566875D02*
X703583Y566667D01*
X703875Y566542D01*
X704250Y566500D01*
X704625Y566583D01*
X704917Y566750D01*
X705125Y567042D01*
X705167Y567375D01*
X705083Y567708D01*
X704875Y567917D01*
X704583Y568083D01*
X704292Y568125D01*
X704000Y568083D01*
X703625Y567917D01*
X703750Y569000D01*
X704875D01*
G01X684500Y745517D02*
X682000D01*
Y746558D01*
X682125Y746892D01*
X682292Y747100D01*
X682625Y747183D01*
X682958Y747100D01*
X683167Y746850D01*
X683292Y746558D01*
Y745517D01*
G01Y746558D02*
X684500Y747183D01*
G01Y749950D02*
X682000D01*
X683792Y748408D01*
Y750492D01*
G01X682417Y751758D02*
X682167Y752008D01*
X682042Y752300D01*
X682000Y752633D01*
X682083Y753050D01*
X682292Y753342D01*
X682542Y753425D01*
X682792Y753383D01*
X683000Y753217D01*
X683417Y752383D01*
X683708Y752008D01*
X684125Y751758D01*
X684500Y751675D01*
Y753425D01*
G01Y755567D02*
X683958Y755650D01*
X683500Y755775D01*
X683083Y755942D01*
X682625Y756150D01*
X682000Y756483D01*
Y754817D01*
G01X686676Y747251D02*
X686551Y747001D01*
X686468Y746709D01*
Y746376D01*
X686593Y746001D01*
X686801Y745709D01*
X687051Y745501D01*
X687468Y745334D01*
X687843Y745292D01*
X688218Y745376D01*
X688468Y745501D01*
X688718Y745751D01*
X688885Y746042D01*
X688968Y746334D01*
Y746626D01*
X688885Y746917D01*
X688760Y747167D01*
X688593Y747376D01*
G01X686885Y748642D02*
X686635Y748892D01*
X686510Y749184D01*
X686468Y749517D01*
X686551Y749934D01*
X686760Y750226D01*
X687010Y750309D01*
X687260Y750267D01*
X687468Y750101D01*
X687885Y749267D01*
X688176Y748892D01*
X688593Y748642D01*
X688968Y748559D01*
Y750309D01*
G01Y753034D02*
X686468D01*
X688260Y751492D01*
Y753576D01*
G01X688593Y754717D02*
X688801Y754967D01*
X688926Y755259D01*
X688968Y755634D01*
X688885Y756009D01*
X688718Y756301D01*
X688426Y756509D01*
X688093Y756551D01*
X687760Y756467D01*
X687551Y756259D01*
X687385Y755967D01*
X687343Y755676D01*
X687385Y755384D01*
X687551Y755009D01*
X686468Y755134D01*
Y756259D01*
G01X680968Y760284D02*
X684968D01*
Y767684D01*
G01X677468Y777501D02*
X674968D01*
Y778542D01*
X675093Y778876D01*
X675260Y779084D01*
X675593Y779167D01*
X675926Y779084D01*
X676135Y778834D01*
X676260Y778542D01*
Y777501D01*
G01Y778542D02*
X677468Y779167D01*
G01Y781934D02*
X674968D01*
X676760Y780392D01*
Y782476D01*
G01X676968Y783617D02*
X677260Y783867D01*
X677426Y784201D01*
X677468Y784576D01*
X677426Y784909D01*
X677218Y785242D01*
X676968Y785451D01*
X676718Y785492D01*
X676426Y785409D01*
X676218Y785117D01*
X676135Y784826D01*
Y784451D01*
G01Y784826D02*
X676010Y785076D01*
X675801Y785284D01*
X675551Y785367D01*
X675301Y785284D01*
X675093Y785076D01*
X674968Y784701D01*
X675010Y784326D01*
X675176Y783951D01*
G01X677468Y787634D02*
X674968D01*
X675468Y787134D01*
G01X677468D02*
Y788134D01*
G01X680968Y768284D02*
X684968D01*
Y775684D01*
G01X679708Y779267D02*
X679583Y779017D01*
X679500Y778725D01*
Y778392D01*
X679625Y778017D01*
X679833Y777725D01*
X680083Y777517D01*
X680500Y777350D01*
X680875Y777308D01*
X681250Y777392D01*
X681500Y777517D01*
X681750Y777767D01*
X681917Y778058D01*
X682000Y778350D01*
Y778642D01*
X681917Y778933D01*
X681792Y779183D01*
X681625Y779392D01*
G01X679917Y780658D02*
X679667Y780908D01*
X679542Y781200D01*
X679500Y781533D01*
X679583Y781950D01*
X679792Y782242D01*
X680042Y782325D01*
X680292Y782283D01*
X680500Y782117D01*
X680917Y781283D01*
X681208Y780908D01*
X681625Y780658D01*
X682000Y780575D01*
Y782325D01*
G01Y785050D02*
X679500D01*
X681292Y783508D01*
Y785592D01*
G01X680958Y786858D02*
X680667Y787150D01*
X680500Y787400D01*
X680417Y787733D01*
X680500Y788025D01*
X680667Y788233D01*
X680917Y788400D01*
X681208Y788442D01*
X681458Y788400D01*
X681708Y788233D01*
X681917Y787983D01*
X682000Y787692D01*
X681917Y787358D01*
X681667Y787067D01*
X681292Y786900D01*
X680875Y786858D01*
X680333Y786942D01*
X680042Y787067D01*
X679750Y787275D01*
X679542Y787567D01*
X679500Y787858D01*
X679583Y788150D01*
X679792Y788358D01*
G01X681268Y799784D02*
Y795784D01*
X688668D01*
G01X681268Y809484D02*
Y805484D01*
X688668D01*
G01X681268Y804484D02*
Y800484D01*
X688668D01*
G01X687967Y857500D02*
Y860000D01*
X689008D01*
X689342Y859875D01*
X689550Y859708D01*
X689633Y859375D01*
X689550Y859042D01*
X689300Y858833D01*
X689008Y858708D01*
X687967D01*
G01X689008D02*
X689633Y857500D01*
G01X691900D02*
Y860000D01*
X691400Y859500D01*
G01Y857500D02*
X692400D01*
G01X694083Y857875D02*
X694333Y857667D01*
X694625Y857542D01*
X695000Y857500D01*
X695375Y857583D01*
X695667Y857750D01*
X695875Y858042D01*
X695917Y858375D01*
X695833Y858708D01*
X695625Y858917D01*
X695333Y859083D01*
X695042Y859125D01*
X694750Y859083D01*
X694375Y858917D01*
X694500Y860000D01*
X695625D01*
G01X698017Y857500D02*
X698100Y858042D01*
X698225Y858500D01*
X698392Y858917D01*
X698600Y859375D01*
X698933Y860000D01*
X697267D01*
G01X700492Y857792D02*
X700783Y857583D01*
X701117Y857500D01*
X701450Y857583D01*
X701742Y857833D01*
X701950Y858208D01*
X702033Y858583D01*
Y859042D01*
X701950Y859417D01*
X701742Y859750D01*
X701492Y859917D01*
X701200Y860000D01*
X700867Y859917D01*
X700617Y859750D01*
X700450Y859500D01*
X700367Y859167D01*
X700450Y858875D01*
X700658Y858583D01*
X700908Y858417D01*
X701200Y858375D01*
X701533Y858458D01*
X701783Y858667D01*
X702033Y859042D01*
G01X697017Y36500D02*
Y39000D01*
X698058D01*
X698392Y38875D01*
X698600Y38708D01*
X698683Y38375D01*
X698600Y38042D01*
X698350Y37833D01*
X698058Y37708D01*
X697017D01*
G01X698058D02*
X698683Y36500D01*
G01X700158Y38583D02*
X700408Y38833D01*
X700700Y38958D01*
X701033Y39000D01*
X701450Y38917D01*
X701742Y38708D01*
X701825Y38458D01*
X701783Y38208D01*
X701617Y38000D01*
X700783Y37583D01*
X700408Y37292D01*
X700158Y36875D01*
X700075Y36500D01*
X701825D01*
G01X704050Y39000D02*
X703717Y38917D01*
X703467Y38708D01*
X703300Y38458D01*
X703175Y38125D01*
X703133Y37750D01*
X703175Y37375D01*
X703300Y37042D01*
X703467Y36792D01*
X703717Y36583D01*
X704050Y36500D01*
X704383Y36583D01*
X704633Y36792D01*
X704800Y37042D01*
X704925Y37375D01*
X704967Y37750D01*
X704925Y38125D01*
X704800Y38458D01*
X704633Y38708D01*
X704383Y38917D01*
X704050Y39000D01*
G01X706233Y37000D02*
X706483Y36708D01*
X706817Y36542D01*
X707192Y36500D01*
X707525Y36542D01*
X707858Y36750D01*
X708067Y37000D01*
X708108Y37250D01*
X708025Y37542D01*
X707733Y37750D01*
X707442Y37833D01*
X707067D01*
G01X707442D02*
X707692Y37958D01*
X707900Y38167D01*
X707983Y38417D01*
X707900Y38667D01*
X707692Y38875D01*
X707317Y39000D01*
X706942Y38958D01*
X706567Y38792D01*
G01X697017Y40500D02*
Y43000D01*
X698058D01*
X698392Y42875D01*
X698600Y42708D01*
X698683Y42375D01*
X698600Y42042D01*
X698350Y41833D01*
X698058Y41708D01*
X697017D01*
G01X698058D02*
X698683Y40500D01*
G01X700158Y42583D02*
X700408Y42833D01*
X700700Y42958D01*
X701033Y43000D01*
X701450Y42917D01*
X701742Y42708D01*
X701825Y42458D01*
X701783Y42208D01*
X701617Y42000D01*
X700783Y41583D01*
X700408Y41292D01*
X700158Y40875D01*
X700075Y40500D01*
X701825D01*
G01X704050Y43000D02*
X703717Y42917D01*
X703467Y42708D01*
X703300Y42458D01*
X703175Y42125D01*
X703133Y41750D01*
X703175Y41375D01*
X703300Y41042D01*
X703467Y40792D01*
X703717Y40583D01*
X704050Y40500D01*
X704383Y40583D01*
X704633Y40792D01*
X704800Y41042D01*
X704925Y41375D01*
X704967Y41750D01*
X704925Y42125D01*
X704800Y42458D01*
X704633Y42708D01*
X704383Y42917D01*
X704050Y43000D01*
G01X707650Y40500D02*
Y43000D01*
X706108Y41208D01*
X708192D01*
G01X697017Y49500D02*
Y52000D01*
X698058D01*
X698392Y51875D01*
X698600Y51708D01*
X698683Y51375D01*
X698600Y51042D01*
X698350Y50833D01*
X698058Y50708D01*
X697017D01*
G01X698058D02*
X698683Y49500D01*
G01X700158Y51583D02*
X700408Y51833D01*
X700700Y51958D01*
X701033Y52000D01*
X701450Y51917D01*
X701742Y51708D01*
X701825Y51458D01*
X701783Y51208D01*
X701617Y51000D01*
X700783Y50583D01*
X700408Y50292D01*
X700158Y49875D01*
X700075Y49500D01*
X701825D01*
G01X704050Y52000D02*
X703717Y51917D01*
X703467Y51708D01*
X703300Y51458D01*
X703175Y51125D01*
X703133Y50750D01*
X703175Y50375D01*
X703300Y50042D01*
X703467Y49792D01*
X703717Y49583D01*
X704050Y49500D01*
X704383Y49583D01*
X704633Y49792D01*
X704800Y50042D01*
X704925Y50375D01*
X704967Y50750D01*
X704925Y51125D01*
X704800Y51458D01*
X704633Y51708D01*
X704383Y51917D01*
X704050Y52000D01*
G01X707150Y49500D02*
Y52000D01*
X706650Y51500D01*
G01Y49500D02*
X707650D01*
G01X697017Y45000D02*
Y47500D01*
X698058D01*
X698392Y47375D01*
X698600Y47208D01*
X698683Y46875D01*
X698600Y46542D01*
X698350Y46333D01*
X698058Y46208D01*
X697017D01*
G01X698058D02*
X698683Y45000D01*
G01X700158Y47083D02*
X700408Y47333D01*
X700700Y47458D01*
X701033Y47500D01*
X701450Y47417D01*
X701742Y47208D01*
X701825Y46958D01*
X701783Y46708D01*
X701617Y46500D01*
X700783Y46083D01*
X700408Y45792D01*
X700158Y45375D01*
X700075Y45000D01*
X701825D01*
G01X704050Y47500D02*
X703717Y47417D01*
X703467Y47208D01*
X703300Y46958D01*
X703175Y46625D01*
X703133Y46250D01*
X703175Y45875D01*
X703300Y45542D01*
X703467Y45292D01*
X703717Y45083D01*
X704050Y45000D01*
X704383Y45083D01*
X704633Y45292D01*
X704800Y45542D01*
X704925Y45875D01*
X704967Y46250D01*
X704925Y46625D01*
X704800Y46958D01*
X704633Y47208D01*
X704383Y47417D01*
X704050Y47500D01*
G01X706358Y47083D02*
X706608Y47333D01*
X706900Y47458D01*
X707233Y47500D01*
X707650Y47417D01*
X707942Y47208D01*
X708025Y46958D01*
X707983Y46708D01*
X707817Y46500D01*
X706983Y46083D01*
X706608Y45792D01*
X706358Y45375D01*
X706275Y45000D01*
X708025D01*
G01X702300Y61500D02*
Y57500D01*
X709700D01*
G01Y61500D02*
Y65500D01*
X702300D01*
G01Y74500D02*
Y70500D01*
X709700D01*
G01X702300Y70000D02*
Y66000D01*
X709700D01*
G01X706017Y80500D02*
Y83000D01*
X707058D01*
X707392Y82875D01*
X707600Y82708D01*
X707683Y82375D01*
X707600Y82042D01*
X707350Y81833D01*
X707058Y81708D01*
X706017D01*
G01X707058D02*
X707683Y80500D01*
G01X709033Y81000D02*
X709283Y80708D01*
X709617Y80542D01*
X709992Y80500D01*
X710325Y80542D01*
X710658Y80750D01*
X710867Y81000D01*
X710908Y81250D01*
X710825Y81542D01*
X710533Y81750D01*
X710242Y81833D01*
X709867D01*
G01X710242D02*
X710492Y81958D01*
X710700Y82167D01*
X710783Y82417D01*
X710700Y82667D01*
X710492Y82875D01*
X710117Y83000D01*
X709742Y82958D01*
X709367Y82792D01*
G01X712342Y80792D02*
X712633Y80583D01*
X712967Y80500D01*
X713300Y80583D01*
X713592Y80833D01*
X713800Y81208D01*
X713883Y81583D01*
Y82042D01*
X713800Y82417D01*
X713592Y82750D01*
X713342Y82917D01*
X713050Y83000D01*
X712717Y82917D01*
X712467Y82750D01*
X712300Y82500D01*
X712217Y82167D01*
X712300Y81875D01*
X712508Y81583D01*
X712758Y81417D01*
X713050Y81375D01*
X713383Y81458D01*
X713633Y81667D01*
X713883Y82042D01*
G01X715358Y81542D02*
X715650Y81833D01*
X715900Y82000D01*
X716233Y82083D01*
X716525Y82000D01*
X716733Y81833D01*
X716900Y81583D01*
X716942Y81292D01*
X716900Y81042D01*
X716733Y80792D01*
X716483Y80583D01*
X716192Y80500D01*
X715858Y80583D01*
X715567Y80833D01*
X715400Y81208D01*
X715358Y81625D01*
X715442Y82167D01*
X715567Y82458D01*
X715775Y82750D01*
X716067Y82958D01*
X716358Y83000D01*
X716650Y82917D01*
X716858Y82708D01*
G01X701517Y76500D02*
Y79000D01*
X702558D01*
X702892Y78875D01*
X703100Y78708D01*
X703183Y78375D01*
X703100Y78042D01*
X702850Y77833D01*
X702558Y77708D01*
X701517D01*
G01X702558D02*
X703183Y76500D01*
G01X704533Y77000D02*
X704783Y76708D01*
X705117Y76542D01*
X705492Y76500D01*
X705825Y76542D01*
X706158Y76750D01*
X706367Y77000D01*
X706408Y77250D01*
X706325Y77542D01*
X706033Y77750D01*
X705742Y77833D01*
X705367D01*
G01X705742D02*
X705992Y77958D01*
X706200Y78167D01*
X706283Y78417D01*
X706200Y78667D01*
X705992Y78875D01*
X705617Y79000D01*
X705242Y78958D01*
X704867Y78792D01*
G01X708550Y76500D02*
X708842Y76542D01*
X709175Y76667D01*
X709383Y76875D01*
X709467Y77167D01*
X709383Y77458D01*
X709133Y77708D01*
X708758Y77833D01*
X708342D01*
X708092Y77917D01*
X707883Y78125D01*
X707800Y78417D01*
X707925Y78708D01*
X708217Y78917D01*
X708550Y79000D01*
X708883Y78917D01*
X709175Y78708D01*
X709300Y78417D01*
X709217Y78125D01*
X709008Y77917D01*
X708758Y77833D01*
X708342D01*
X707967Y77708D01*
X707717Y77458D01*
X707633Y77167D01*
X707717Y76875D01*
X707925Y76667D01*
X708258Y76542D01*
X708550Y76500D01*
G01X711567D02*
X711650Y77042D01*
X711775Y77500D01*
X711942Y77917D01*
X712150Y78375D01*
X712483Y79000D01*
X710817D01*
G01X695500Y75517D02*
X693000D01*
Y76558D01*
X693125Y76892D01*
X693292Y77100D01*
X693625Y77183D01*
X693958Y77100D01*
X694167Y76850D01*
X694292Y76558D01*
Y75517D01*
G01Y76558D02*
X695500Y77183D01*
G01X695000Y78533D02*
X695292Y78783D01*
X695458Y79117D01*
X695500Y79492D01*
X695458Y79825D01*
X695250Y80158D01*
X695000Y80367D01*
X694750Y80408D01*
X694458Y80325D01*
X694250Y80033D01*
X694167Y79742D01*
Y79367D01*
G01Y79742D02*
X694042Y79992D01*
X693833Y80200D01*
X693583Y80283D01*
X693333Y80200D01*
X693125Y79992D01*
X693000Y79617D01*
X693042Y79242D01*
X693208Y78867D01*
G01X695500Y82550D02*
X695458Y82842D01*
X695333Y83175D01*
X695125Y83383D01*
X694833Y83467D01*
X694542Y83383D01*
X694292Y83133D01*
X694167Y82758D01*
Y82342D01*
X694083Y82092D01*
X693875Y81883D01*
X693583Y81800D01*
X693292Y81925D01*
X693083Y82217D01*
X693000Y82550D01*
X693083Y82883D01*
X693292Y83175D01*
X693583Y83300D01*
X693875Y83217D01*
X694083Y83008D01*
X694167Y82758D01*
Y82342D01*
X694292Y81967D01*
X694542Y81717D01*
X694833Y81633D01*
X695125Y81717D01*
X695333Y81925D01*
X695458Y82258D01*
X695500Y82550D01*
G01X695000Y84733D02*
X695292Y84983D01*
X695458Y85317D01*
X695500Y85692D01*
X695458Y86025D01*
X695250Y86358D01*
X695000Y86567D01*
X694750Y86608D01*
X694458Y86525D01*
X694250Y86233D01*
X694167Y85942D01*
Y85567D01*
G01Y85942D02*
X694042Y86192D01*
X693833Y86400D01*
X693583Y86483D01*
X693333Y86400D01*
X693125Y86192D01*
X693000Y85817D01*
X693042Y85442D01*
X693208Y85067D01*
G01X704716Y85084D02*
X708716D01*
Y92484D01*
G01X703916Y108484D02*
Y103484D01*
X708916D01*
G01X697500Y91300D02*
X700000D01*
G01X697500Y90342D02*
Y92258D01*
G01X700000Y93567D02*
X697500D01*
Y94567D01*
X697625Y94900D01*
X697917Y95150D01*
X698250Y95233D01*
X698583Y95150D01*
X698833Y94942D01*
X698958Y94567D01*
Y93567D01*
G01X700000Y97500D02*
X697500D01*
X698000Y97000D01*
G01X700000D02*
Y98000D01*
G01X699500Y99683D02*
X699792Y99933D01*
X699958Y100267D01*
X700000Y100642D01*
X699958Y100975D01*
X699750Y101308D01*
X699500Y101517D01*
X699250Y101558D01*
X698958Y101475D01*
X698750Y101183D01*
X698667Y100892D01*
Y100517D01*
G01Y100892D02*
X698542Y101142D01*
X698333Y101350D01*
X698083Y101433D01*
X697833Y101350D01*
X697625Y101142D01*
X697500Y100767D01*
X697542Y100392D01*
X697708Y100017D01*
G01X697917Y102908D02*
X697667Y103158D01*
X697542Y103450D01*
X697500Y103783D01*
X697583Y104200D01*
X697792Y104492D01*
X698042Y104575D01*
X698292Y104533D01*
X698500Y104367D01*
X698917Y103533D01*
X699208Y103158D01*
X699625Y102908D01*
X700000Y102825D01*
Y104575D01*
G01X693000Y91300D02*
X695500D01*
G01X693000Y90342D02*
Y92258D01*
G01X695500Y93567D02*
X693000D01*
Y94567D01*
X693125Y94900D01*
X693417Y95150D01*
X693750Y95233D01*
X694083Y95150D01*
X694333Y94942D01*
X694458Y94567D01*
Y93567D01*
G01X695500Y97500D02*
X693000D01*
X693500Y97000D01*
G01X695500D02*
Y98000D01*
G01X695000Y99683D02*
X695292Y99933D01*
X695458Y100267D01*
X695500Y100642D01*
X695458Y100975D01*
X695250Y101308D01*
X695000Y101517D01*
X694750Y101558D01*
X694458Y101475D01*
X694250Y101183D01*
X694167Y100892D01*
Y100517D01*
G01Y100892D02*
X694042Y101142D01*
X693833Y101350D01*
X693583Y101433D01*
X693333Y101350D01*
X693125Y101142D01*
X693000Y100767D01*
X693042Y100392D01*
X693208Y100017D01*
G01X695500Y103700D02*
X693000D01*
X693500Y103200D01*
G01X695500D02*
Y104200D01*
G01X694731Y124500D02*
Y122708D01*
X694898Y122333D01*
X695231Y122083D01*
X695648Y122000D01*
X696065Y122083D01*
X696398Y122333D01*
X696565Y122708D01*
Y124500D01*
G01X697956Y124083D02*
X698206Y124333D01*
X698498Y124458D01*
X698831Y124500D01*
X699248Y124417D01*
X699540Y124208D01*
X699623Y123958D01*
X699581Y123708D01*
X699415Y123500D01*
X698581Y123083D01*
X698206Y122792D01*
X697956Y122375D01*
X697873Y122000D01*
X699623D01*
G01X701848Y124500D02*
X701515Y124417D01*
X701265Y124208D01*
X701098Y123958D01*
X700973Y123625D01*
X700931Y123250D01*
X700973Y122875D01*
X701098Y122542D01*
X701265Y122292D01*
X701515Y122083D01*
X701848Y122000D01*
X702181Y122083D01*
X702431Y122292D01*
X702598Y122542D01*
X702723Y122875D01*
X702765Y123250D01*
X702723Y123625D01*
X702598Y123958D01*
X702431Y124208D01*
X702181Y124417D01*
X701848Y124500D01*
G01X704816Y118332D02*
X701816D01*
G01X695500Y107017D02*
X693000D01*
Y108058D01*
X693125Y108392D01*
X693292Y108600D01*
X693625Y108683D01*
X693958Y108600D01*
X694167Y108350D01*
X694292Y108058D01*
Y107017D01*
G01Y108058D02*
X695500Y108683D01*
G01Y111450D02*
X693000D01*
X694792Y109908D01*
Y111992D01*
G01X693000Y114050D02*
X693083Y113717D01*
X693292Y113467D01*
X693542Y113300D01*
X693875Y113175D01*
X694250Y113133D01*
X694625Y113175D01*
X694958Y113300D01*
X695208Y113467D01*
X695417Y113717D01*
X695500Y114050D01*
X695417Y114383D01*
X695208Y114633D01*
X694958Y114800D01*
X694625Y114925D01*
X694250Y114967D01*
X693875Y114925D01*
X693542Y114800D01*
X693292Y114633D01*
X693083Y114383D01*
X693000Y114050D01*
G01X695125Y116233D02*
X695333Y116483D01*
X695458Y116775D01*
X695500Y117150D01*
X695417Y117525D01*
X695250Y117817D01*
X694958Y118025D01*
X694625Y118067D01*
X694292Y117983D01*
X694083Y117775D01*
X693917Y117483D01*
X693875Y117192D01*
X693917Y116900D01*
X694083Y116525D01*
X693000Y116650D01*
Y117775D01*
G01X708916Y139084D02*
X703916D01*
Y134084D01*
G01X704816Y128172D02*
X702816D01*
G01X698216Y146584D02*
X702216D01*
Y153984D01*
G01X707216Y146584D02*
X711216D01*
Y153984D01*
G01X706716D02*
X702716D01*
Y146584D01*
G01X699716Y155801D02*
X697216D01*
Y156842D01*
X697341Y157176D01*
X697508Y157384D01*
X697841Y157467D01*
X698174Y157384D01*
X698383Y157134D01*
X698508Y156842D01*
Y155801D01*
G01Y156842D02*
X699716Y157467D01*
G01X699216Y158817D02*
X699508Y159067D01*
X699674Y159401D01*
X699716Y159776D01*
X699674Y160109D01*
X699466Y160442D01*
X699216Y160651D01*
X698966Y160692D01*
X698674Y160609D01*
X698466Y160317D01*
X698383Y160026D01*
Y159651D01*
G01Y160026D02*
X698258Y160276D01*
X698049Y160484D01*
X697799Y160567D01*
X697549Y160484D01*
X697341Y160276D01*
X697216Y159901D01*
X697258Y159526D01*
X697424Y159151D01*
G01X699424Y162126D02*
X699633Y162417D01*
X699716Y162751D01*
X699633Y163084D01*
X699383Y163376D01*
X699008Y163584D01*
X698633Y163667D01*
X698174D01*
X697799Y163584D01*
X697466Y163376D01*
X697299Y163126D01*
X697216Y162834D01*
X697299Y162501D01*
X697466Y162251D01*
X697716Y162084D01*
X698049Y162001D01*
X698341Y162084D01*
X698633Y162292D01*
X698799Y162542D01*
X698841Y162834D01*
X698758Y163167D01*
X698549Y163417D01*
X698174Y163667D01*
G01X699341Y165017D02*
X699549Y165267D01*
X699674Y165559D01*
X699716Y165934D01*
X699633Y166309D01*
X699466Y166601D01*
X699174Y166809D01*
X698841Y166851D01*
X698508Y166767D01*
X698299Y166559D01*
X698133Y166267D01*
X698091Y165976D01*
X698133Y165684D01*
X698299Y165309D01*
X697216Y165434D01*
Y166559D01*
G01X708716Y155801D02*
X706216D01*
Y156842D01*
X706341Y157176D01*
X706508Y157384D01*
X706841Y157467D01*
X707174Y157384D01*
X707383Y157134D01*
X707508Y156842D01*
Y155801D01*
G01Y156842D02*
X708716Y157467D01*
G01X708216Y158817D02*
X708508Y159067D01*
X708674Y159401D01*
X708716Y159776D01*
X708674Y160109D01*
X708466Y160442D01*
X708216Y160651D01*
X707966Y160692D01*
X707674Y160609D01*
X707466Y160317D01*
X707383Y160026D01*
Y159651D01*
G01Y160026D02*
X707258Y160276D01*
X707049Y160484D01*
X706799Y160567D01*
X706549Y160484D01*
X706341Y160276D01*
X706216Y159901D01*
X706258Y159526D01*
X706424Y159151D01*
G01X708424Y162126D02*
X708633Y162417D01*
X708716Y162751D01*
X708633Y163084D01*
X708383Y163376D01*
X708008Y163584D01*
X707633Y163667D01*
X707174D01*
X706799Y163584D01*
X706466Y163376D01*
X706299Y163126D01*
X706216Y162834D01*
X706299Y162501D01*
X706466Y162251D01*
X706716Y162084D01*
X707049Y162001D01*
X707341Y162084D01*
X707633Y162292D01*
X707799Y162542D01*
X707841Y162834D01*
X707758Y163167D01*
X707549Y163417D01*
X707174Y163667D01*
G01X708216Y165017D02*
X708508Y165267D01*
X708674Y165601D01*
X708716Y165976D01*
X708674Y166309D01*
X708466Y166642D01*
X708216Y166851D01*
X707966Y166892D01*
X707674Y166809D01*
X707466Y166517D01*
X707383Y166226D01*
Y165851D01*
G01Y166226D02*
X707258Y166476D01*
X707049Y166684D01*
X706799Y166767D01*
X706549Y166684D01*
X706341Y166476D01*
X706216Y166101D01*
X706258Y165726D01*
X706424Y165351D01*
G01X704216Y155801D02*
X701716D01*
Y156842D01*
X701841Y157176D01*
X702008Y157384D01*
X702341Y157467D01*
X702674Y157384D01*
X702883Y157134D01*
X703008Y156842D01*
Y155801D01*
G01Y156842D02*
X704216Y157467D01*
G01X703716Y158817D02*
X704008Y159067D01*
X704174Y159401D01*
X704216Y159776D01*
X704174Y160109D01*
X703966Y160442D01*
X703716Y160651D01*
X703466Y160692D01*
X703174Y160609D01*
X702966Y160317D01*
X702883Y160026D01*
Y159651D01*
G01Y160026D02*
X702758Y160276D01*
X702549Y160484D01*
X702299Y160567D01*
X702049Y160484D01*
X701841Y160276D01*
X701716Y159901D01*
X701758Y159526D01*
X701924Y159151D01*
G01X704216Y162751D02*
X703674Y162834D01*
X703216Y162959D01*
X702799Y163126D01*
X702341Y163334D01*
X701716Y163667D01*
Y162001D01*
G01X704216Y165934D02*
X704174Y166226D01*
X704049Y166559D01*
X703841Y166767D01*
X703549Y166851D01*
X703258Y166767D01*
X703008Y166517D01*
X702883Y166142D01*
Y165726D01*
X702799Y165476D01*
X702591Y165267D01*
X702299Y165184D01*
X702008Y165309D01*
X701799Y165601D01*
X701716Y165934D01*
X701799Y166267D01*
X702008Y166559D01*
X702299Y166684D01*
X702591Y166601D01*
X702799Y166392D01*
X702883Y166142D01*
Y165726D01*
X703008Y165351D01*
X703258Y165101D01*
X703549Y165017D01*
X703841Y165101D01*
X704049Y165309D01*
X704174Y165642D01*
X704216Y165934D01*
G01X705567Y196500D02*
Y199000D01*
X706608D01*
X706942Y198875D01*
X707150Y198708D01*
X707233Y198375D01*
X707150Y198042D01*
X706900Y197833D01*
X706608Y197708D01*
X705567D01*
G01X706608D02*
X707233Y196500D01*
G01X710000D02*
Y199000D01*
X708458Y197208D01*
X710542D01*
G01X711683Y196875D02*
X711933Y196667D01*
X712225Y196542D01*
X712600Y196500D01*
X712975Y196583D01*
X713267Y196750D01*
X713475Y197042D01*
X713517Y197375D01*
X713433Y197708D01*
X713225Y197917D01*
X712933Y198083D01*
X712642Y198125D01*
X712350Y198083D01*
X711975Y197917D01*
X712100Y199000D01*
X713225D01*
G01X704017Y192500D02*
Y195000D01*
X705058D01*
X705392Y194875D01*
X705600Y194708D01*
X705683Y194375D01*
X705600Y194042D01*
X705350Y193833D01*
X705058Y193708D01*
X704017D01*
G01X705058D02*
X705683Y192500D01*
G01X708450D02*
Y195000D01*
X706908Y193208D01*
X708992D01*
G01X710342Y192792D02*
X710633Y192583D01*
X710967Y192500D01*
X711300Y192583D01*
X711592Y192833D01*
X711800Y193208D01*
X711883Y193583D01*
Y194042D01*
X711800Y194417D01*
X711592Y194750D01*
X711342Y194917D01*
X711050Y195000D01*
X710717Y194917D01*
X710467Y194750D01*
X710300Y194500D01*
X710217Y194167D01*
X710300Y193875D01*
X710508Y193583D01*
X710758Y193417D01*
X711050Y193375D01*
X711383Y193458D01*
X711633Y193667D01*
X711883Y194042D01*
G01X714150Y195000D02*
X713817Y194917D01*
X713567Y194708D01*
X713400Y194458D01*
X713275Y194125D01*
X713233Y193750D01*
X713275Y193375D01*
X713400Y193042D01*
X713567Y192792D01*
X713817Y192583D01*
X714150Y192500D01*
X714483Y192583D01*
X714733Y192792D01*
X714900Y193042D01*
X715025Y193375D01*
X715067Y193750D01*
X715025Y194125D01*
X714900Y194458D01*
X714733Y194708D01*
X714483Y194917D01*
X714150Y195000D01*
G01X705267Y204392D02*
X705017Y204517D01*
X704725Y204600D01*
X704392D01*
X704017Y204475D01*
X703725Y204267D01*
X703517Y204017D01*
X703350Y203600D01*
X703308Y203225D01*
X703392Y202850D01*
X703517Y202600D01*
X703767Y202350D01*
X704058Y202183D01*
X704350Y202100D01*
X704642D01*
X704933Y202183D01*
X705183Y202308D01*
X705392Y202475D01*
G01X706533Y202600D02*
X706783Y202308D01*
X707117Y202142D01*
X707492Y202100D01*
X707825Y202142D01*
X708158Y202350D01*
X708367Y202600D01*
X708408Y202850D01*
X708325Y203142D01*
X708033Y203350D01*
X707742Y203433D01*
X707367D01*
G01X707742D02*
X707992Y203558D01*
X708200Y203767D01*
X708283Y204017D01*
X708200Y204267D01*
X707992Y204475D01*
X707617Y204600D01*
X707242Y204558D01*
X706867Y204392D01*
G01X710550Y202100D02*
Y204600D01*
X710050Y204100D01*
G01Y202100D02*
X711050D01*
G01X712858Y204183D02*
X713108Y204433D01*
X713400Y204558D01*
X713733Y204600D01*
X714150Y204517D01*
X714442Y204308D01*
X714525Y204058D01*
X714483Y203808D01*
X714317Y203600D01*
X713483Y203183D01*
X713108Y202892D01*
X712858Y202475D01*
X712775Y202100D01*
X714525D01*
G01X691555Y244800D02*
X694055D01*
G01X691555Y243842D02*
Y245758D01*
G01X694055Y247067D02*
X691555D01*
Y248067D01*
X691680Y248400D01*
X691972Y248650D01*
X692305Y248733D01*
X692638Y248650D01*
X692888Y248442D01*
X693013Y248067D01*
Y247067D01*
G01X694055Y251000D02*
X691555D01*
X692055Y250500D01*
G01X694055D02*
Y251500D01*
G01Y254600D02*
X691555D01*
X693347Y253058D01*
Y255142D01*
G01X693763Y256492D02*
X693972Y256783D01*
X694055Y257117D01*
X693972Y257450D01*
X693722Y257742D01*
X693347Y257950D01*
X692972Y258033D01*
X692513D01*
X692138Y257950D01*
X691805Y257742D01*
X691638Y257492D01*
X691555Y257200D01*
X691638Y256867D01*
X691805Y256617D01*
X692055Y256450D01*
X692388Y256367D01*
X692680Y256450D01*
X692972Y256658D01*
X693138Y256908D01*
X693180Y257200D01*
X693097Y257533D01*
X692888Y257783D01*
X692513Y258033D01*
G01X704263Y249767D02*
X704138Y249517D01*
X704055Y249225D01*
Y248892D01*
X704180Y248517D01*
X704388Y248225D01*
X704638Y248017D01*
X705055Y247850D01*
X705430Y247808D01*
X705805Y247892D01*
X706055Y248017D01*
X706305Y248267D01*
X706472Y248558D01*
X706555Y248850D01*
Y249142D01*
X706472Y249433D01*
X706347Y249683D01*
X706180Y249892D01*
G01X704472Y251158D02*
X704222Y251408D01*
X704097Y251700D01*
X704055Y252033D01*
X704138Y252450D01*
X704347Y252742D01*
X704597Y252825D01*
X704847Y252783D01*
X705055Y252617D01*
X705472Y251783D01*
X705763Y251408D01*
X706180Y251158D01*
X706555Y251075D01*
Y252825D01*
G01Y255050D02*
X706513Y255342D01*
X706388Y255675D01*
X706180Y255883D01*
X705888Y255967D01*
X705597Y255883D01*
X705347Y255633D01*
X705222Y255258D01*
Y254842D01*
X705138Y254592D01*
X704930Y254383D01*
X704638Y254300D01*
X704347Y254425D01*
X704138Y254717D01*
X704055Y255050D01*
X704138Y255383D01*
X704347Y255675D01*
X704638Y255800D01*
X704930Y255717D01*
X705138Y255508D01*
X705222Y255258D01*
Y254842D01*
X705347Y254467D01*
X705597Y254217D01*
X705888Y254133D01*
X706180Y254217D01*
X706388Y254425D01*
X706513Y254758D01*
X706555Y255050D01*
G01X706263Y257442D02*
X706472Y257733D01*
X706555Y258067D01*
X706472Y258400D01*
X706222Y258692D01*
X705847Y258900D01*
X705472Y258983D01*
X705013D01*
X704638Y258900D01*
X704305Y258692D01*
X704138Y258442D01*
X704055Y258150D01*
X704138Y257817D01*
X704305Y257567D01*
X704555Y257400D01*
X704888Y257317D01*
X705180Y257400D01*
X705472Y257608D01*
X705638Y257858D01*
X705680Y258150D01*
X705597Y258483D01*
X705388Y258733D01*
X705013Y258983D01*
G01X710000Y342017D02*
X707500D01*
Y343017D01*
X707625Y343350D01*
X707917Y343600D01*
X708250Y343683D01*
X708583Y343600D01*
X708833Y343392D01*
X708958Y343017D01*
Y342017D01*
G01X707500Y345950D02*
X710000D01*
G01X707500Y344992D02*
Y346908D01*
G01X707708Y349967D02*
X707583Y349717D01*
X707500Y349425D01*
Y349092D01*
X707625Y348717D01*
X707833Y348425D01*
X708083Y348217D01*
X708500Y348050D01*
X708875Y348008D01*
X709250Y348092D01*
X709500Y348217D01*
X709750Y348467D01*
X709917Y348758D01*
X710000Y349050D01*
Y349342D01*
X709917Y349633D01*
X709792Y349883D01*
X709625Y350092D01*
G01Y351233D02*
X709833Y351483D01*
X709958Y351775D01*
X710000Y352150D01*
X709917Y352525D01*
X709750Y352817D01*
X709458Y353025D01*
X709125Y353067D01*
X708792Y352983D01*
X708583Y352775D01*
X708417Y352483D01*
X708375Y352192D01*
X708417Y351900D01*
X708583Y351525D01*
X707500Y351650D01*
Y352775D01*
G01X704200Y339500D02*
X693000D01*
G01X704200Y357500D02*
Y339500D01*
G01X693000Y357500D02*
X704200D01*
G01X710000Y363517D02*
X707500D01*
Y364517D01*
X707625Y364850D01*
X707917Y365100D01*
X708250Y365183D01*
X708583Y365100D01*
X708833Y364892D01*
X708958Y364517D01*
Y363517D01*
G01X707500Y367450D02*
X710000D01*
G01X707500Y366492D02*
Y368408D01*
G01X707708Y371467D02*
X707583Y371217D01*
X707500Y370925D01*
Y370592D01*
X707625Y370217D01*
X707833Y369925D01*
X708083Y369717D01*
X708500Y369550D01*
X708875Y369508D01*
X709250Y369592D01*
X709500Y369717D01*
X709750Y369967D01*
X709917Y370258D01*
X710000Y370550D01*
Y370842D01*
X709917Y371133D01*
X709792Y371383D01*
X709625Y371592D01*
G01X710000Y374150D02*
X707500D01*
X709292Y372608D01*
Y374692D01*
G01X704200Y360000D02*
X693000D01*
G01X704200Y378000D02*
Y360000D01*
G01X693000Y378000D02*
X704200D01*
G01X703000Y434467D02*
X700500D01*
Y435467D01*
X700625Y435800D01*
X700917Y436050D01*
X701250Y436133D01*
X701583Y436050D01*
X701833Y435842D01*
X701958Y435467D01*
Y434467D01*
G01X703000Y437567D02*
X700500D01*
Y438608D01*
X700625Y438942D01*
X700792Y439150D01*
X701125Y439233D01*
X701458Y439150D01*
X701667Y438900D01*
X701792Y438608D01*
Y437567D01*
G01Y438608D02*
X703000Y439233D01*
G01Y441500D02*
X700500D01*
X701000Y441000D01*
G01X703000D02*
Y442000D01*
G01X702625Y443683D02*
X702833Y443933D01*
X702958Y444225D01*
X703000Y444600D01*
X702917Y444975D01*
X702750Y445267D01*
X702458Y445475D01*
X702125Y445517D01*
X701792Y445433D01*
X701583Y445225D01*
X701417Y444933D01*
X701375Y444642D01*
X701417Y444350D01*
X701583Y443975D01*
X700500Y444100D01*
Y445225D01*
G01X703000Y448200D02*
X700500D01*
X702292Y446658D01*
Y448742D01*
G01X696462Y439764D02*
Y447564D01*
G01Y446764D02*
Y453164D01*
G01X698967Y454000D02*
Y456500D01*
X699967D01*
X700300Y456375D01*
X700550Y456083D01*
X700633Y455750D01*
X700550Y455417D01*
X700342Y455167D01*
X699967Y455042D01*
X698967D01*
G01X703817Y456292D02*
X703567Y456417D01*
X703275Y456500D01*
X702942D01*
X702567Y456375D01*
X702275Y456167D01*
X702067Y455917D01*
X701900Y455500D01*
X701858Y455125D01*
X701942Y454750D01*
X702067Y454500D01*
X702317Y454250D01*
X702608Y454083D01*
X702900Y454000D01*
X703192D01*
X703483Y454083D01*
X703733Y454208D01*
X703942Y454375D01*
G01X706000Y454000D02*
Y456500D01*
X705500Y456000D01*
G01Y454000D02*
X706500D01*
G01X709100D02*
X709392Y454042D01*
X709725Y454167D01*
X709933Y454375D01*
X710017Y454667D01*
X709933Y454958D01*
X709683Y455208D01*
X709308Y455333D01*
X708892D01*
X708642Y455417D01*
X708433Y455625D01*
X708350Y455917D01*
X708475Y456208D01*
X708767Y456417D01*
X709100Y456500D01*
X709433Y456417D01*
X709725Y456208D01*
X709850Y455917D01*
X709767Y455625D01*
X709558Y455417D01*
X709308Y455333D01*
X708892D01*
X708517Y455208D01*
X708267Y454958D01*
X708183Y454667D01*
X708267Y454375D01*
X708475Y454167D01*
X708808Y454042D01*
X709100Y454000D01*
G01X712200D02*
X712492Y454042D01*
X712825Y454167D01*
X713033Y454375D01*
X713117Y454667D01*
X713033Y454958D01*
X712783Y455208D01*
X712408Y455333D01*
X711992D01*
X711742Y455417D01*
X711533Y455625D01*
X711450Y455917D01*
X711575Y456208D01*
X711867Y456417D01*
X712200Y456500D01*
X712533Y456417D01*
X712825Y456208D01*
X712950Y455917D01*
X712867Y455625D01*
X712658Y455417D01*
X712408Y455333D01*
X711992D01*
X711617Y455208D01*
X711367Y454958D01*
X711283Y454667D01*
X711367Y454375D01*
X711575Y454167D01*
X711908Y454042D01*
X712200Y454000D01*
G01X694967Y491000D02*
Y493500D01*
X695967D01*
X696300Y493375D01*
X696550Y493083D01*
X696633Y492750D01*
X696550Y492417D01*
X696342Y492167D01*
X695967Y492042D01*
X694967D01*
G01X699817Y493292D02*
X699567Y493417D01*
X699275Y493500D01*
X698942D01*
X698567Y493375D01*
X698275Y493167D01*
X698067Y492917D01*
X697900Y492500D01*
X697858Y492125D01*
X697942Y491750D01*
X698067Y491500D01*
X698317Y491250D01*
X698608Y491083D01*
X698900Y491000D01*
X699192D01*
X699483Y491083D01*
X699733Y491208D01*
X699942Y491375D01*
G01X702000Y491000D02*
Y493500D01*
X701500Y493000D01*
G01Y491000D02*
X702500D01*
G01X704308Y492042D02*
X704600Y492333D01*
X704850Y492500D01*
X705183Y492583D01*
X705475Y492500D01*
X705683Y492333D01*
X705850Y492083D01*
X705892Y491792D01*
X705850Y491542D01*
X705683Y491292D01*
X705433Y491083D01*
X705142Y491000D01*
X704808Y491083D01*
X704517Y491333D01*
X704350Y491708D01*
X704308Y492125D01*
X704392Y492667D01*
X704517Y492958D01*
X704725Y493250D01*
X705017Y493458D01*
X705308Y493500D01*
X705600Y493417D01*
X705808Y493208D01*
G01X707492Y491292D02*
X707783Y491083D01*
X708117Y491000D01*
X708450Y491083D01*
X708742Y491333D01*
X708950Y491708D01*
X709033Y492083D01*
Y492542D01*
X708950Y492917D01*
X708742Y493250D01*
X708492Y493417D01*
X708200Y493500D01*
X707867Y493417D01*
X707617Y493250D01*
X707450Y493000D01*
X707367Y492667D01*
X707450Y492375D01*
X707658Y492083D01*
X707908Y491917D01*
X708200Y491875D01*
X708533Y491958D01*
X708783Y492167D01*
X709033Y492542D01*
G01X694929Y495464D02*
Y497964D01*
X695929D01*
X696262Y497839D01*
X696512Y497547D01*
X696595Y497214D01*
X696512Y496881D01*
X696304Y496631D01*
X695929Y496506D01*
X694929D01*
G01X699779Y497756D02*
X699529Y497881D01*
X699237Y497964D01*
X698904D01*
X698529Y497839D01*
X698237Y497631D01*
X698029Y497381D01*
X697862Y496964D01*
X697820Y496589D01*
X697904Y496214D01*
X698029Y495964D01*
X698279Y495714D01*
X698570Y495547D01*
X698862Y495464D01*
X699154D01*
X699445Y495547D01*
X699695Y495672D01*
X699904Y495839D01*
G01X701962Y495464D02*
Y497964D01*
X701462Y497464D01*
G01Y495464D02*
X702462D01*
G01X704979D02*
X705062Y496006D01*
X705187Y496464D01*
X705354Y496881D01*
X705562Y497339D01*
X705895Y497964D01*
X704229D01*
G01X708162D02*
X707829Y497881D01*
X707579Y497672D01*
X707412Y497422D01*
X707287Y497089D01*
X707245Y496714D01*
X707287Y496339D01*
X707412Y496006D01*
X707579Y495756D01*
X707829Y495547D01*
X708162Y495464D01*
X708495Y495547D01*
X708745Y495756D01*
X708912Y496006D01*
X709037Y496339D01*
X709079Y496714D01*
X709037Y497089D01*
X708912Y497422D01*
X708745Y497672D01*
X708495Y497881D01*
X708162Y497964D01*
G01X694929Y499964D02*
Y502464D01*
X695929D01*
X696262Y502339D01*
X696512Y502047D01*
X696595Y501714D01*
X696512Y501381D01*
X696304Y501131D01*
X695929Y501006D01*
X694929D01*
G01X699779Y502256D02*
X699529Y502381D01*
X699237Y502464D01*
X698904D01*
X698529Y502339D01*
X698237Y502131D01*
X698029Y501881D01*
X697862Y501464D01*
X697820Y501089D01*
X697904Y500714D01*
X698029Y500464D01*
X698279Y500214D01*
X698570Y500047D01*
X698862Y499964D01*
X699154D01*
X699445Y500047D01*
X699695Y500172D01*
X699904Y500339D01*
G01X701962Y499964D02*
Y502464D01*
X701462Y501964D01*
G01Y499964D02*
X702462D01*
G01X704979D02*
X705062Y500506D01*
X705187Y500964D01*
X705354Y501381D01*
X705562Y501839D01*
X705895Y502464D01*
X704229D01*
G01X708162Y499964D02*
Y502464D01*
X707662Y501964D01*
G01Y499964D02*
X708662D01*
G01X694967Y486500D02*
Y489000D01*
X695967D01*
X696300Y488875D01*
X696550Y488583D01*
X696633Y488250D01*
X696550Y487917D01*
X696342Y487667D01*
X695967Y487542D01*
X694967D01*
G01X699817Y488792D02*
X699567Y488917D01*
X699275Y489000D01*
X698942D01*
X698567Y488875D01*
X698275Y488667D01*
X698067Y488417D01*
X697900Y488000D01*
X697858Y487625D01*
X697942Y487250D01*
X698067Y487000D01*
X698317Y486750D01*
X698608Y486583D01*
X698900Y486500D01*
X699192D01*
X699483Y486583D01*
X699733Y486708D01*
X699942Y486875D01*
G01X702000Y486500D02*
Y489000D01*
X701500Y488500D01*
G01Y486500D02*
X702500D01*
G01X705017D02*
X705100Y487042D01*
X705225Y487500D01*
X705392Y487917D01*
X705600Y488375D01*
X705933Y489000D01*
X704267D01*
G01X707408Y488583D02*
X707658Y488833D01*
X707950Y488958D01*
X708283Y489000D01*
X708700Y488917D01*
X708992Y488708D01*
X709075Y488458D01*
X709033Y488208D01*
X708867Y488000D01*
X708033Y487583D01*
X707658Y487292D01*
X707408Y486875D01*
X707325Y486500D01*
X709075D01*
G01X694967Y512000D02*
Y514500D01*
X695967D01*
X696300Y514375D01*
X696550Y514083D01*
X696633Y513750D01*
X696550Y513417D01*
X696342Y513167D01*
X695967Y513042D01*
X694967D01*
G01X699817Y514292D02*
X699567Y514417D01*
X699275Y514500D01*
X698942D01*
X698567Y514375D01*
X698275Y514167D01*
X698067Y513917D01*
X697900Y513500D01*
X697858Y513125D01*
X697942Y512750D01*
X698067Y512500D01*
X698317Y512250D01*
X698608Y512083D01*
X698900Y512000D01*
X699192D01*
X699483Y512083D01*
X699733Y512208D01*
X699942Y512375D01*
G01X702000Y512000D02*
Y514500D01*
X701500Y514000D01*
G01Y512000D02*
X702500D01*
G01X705017D02*
X705100Y512542D01*
X705225Y513000D01*
X705392Y513417D01*
X705600Y513875D01*
X705933Y514500D01*
X704267D01*
G01X707283Y512500D02*
X707533Y512208D01*
X707867Y512042D01*
X708242Y512000D01*
X708575Y512042D01*
X708908Y512250D01*
X709117Y512500D01*
X709158Y512750D01*
X709075Y513042D01*
X708783Y513250D01*
X708492Y513333D01*
X708117D01*
G01X708492D02*
X708742Y513458D01*
X708950Y513667D01*
X709033Y513917D01*
X708950Y514167D01*
X708742Y514375D01*
X708367Y514500D01*
X707992Y514458D01*
X707617Y514292D01*
G01X694929Y503964D02*
Y506464D01*
X695929D01*
X696262Y506339D01*
X696512Y506047D01*
X696595Y505714D01*
X696512Y505381D01*
X696304Y505131D01*
X695929Y505006D01*
X694929D01*
G01X699779Y506256D02*
X699529Y506381D01*
X699237Y506464D01*
X698904D01*
X698529Y506339D01*
X698237Y506131D01*
X698029Y505881D01*
X697862Y505464D01*
X697820Y505089D01*
X697904Y504714D01*
X698029Y504464D01*
X698279Y504214D01*
X698570Y504047D01*
X698862Y503964D01*
X699154D01*
X699445Y504047D01*
X699695Y504172D01*
X699904Y504339D01*
G01X701962Y503964D02*
Y506464D01*
X701462Y505964D01*
G01Y503964D02*
X702462D01*
G01X704979D02*
X705062Y504506D01*
X705187Y504964D01*
X705354Y505381D01*
X705562Y505839D01*
X705895Y506464D01*
X704229D01*
G01X708662Y503964D02*
Y506464D01*
X707120Y504672D01*
X709204D01*
G01X694967Y520000D02*
Y522500D01*
X695967D01*
X696300Y522375D01*
X696550Y522083D01*
X696633Y521750D01*
X696550Y521417D01*
X696342Y521167D01*
X695967Y521042D01*
X694967D01*
G01X699817Y522292D02*
X699567Y522417D01*
X699275Y522500D01*
X698942D01*
X698567Y522375D01*
X698275Y522167D01*
X698067Y521917D01*
X697900Y521500D01*
X697858Y521125D01*
X697942Y520750D01*
X698067Y520500D01*
X698317Y520250D01*
X698608Y520083D01*
X698900Y520000D01*
X699192D01*
X699483Y520083D01*
X699733Y520208D01*
X699942Y520375D01*
G01X702000Y520000D02*
Y522500D01*
X701500Y522000D01*
G01Y520000D02*
X702500D01*
G01X705017D02*
X705100Y520542D01*
X705225Y521000D01*
X705392Y521417D01*
X705600Y521875D01*
X705933Y522500D01*
X704267D01*
G01X707283Y520375D02*
X707533Y520167D01*
X707825Y520042D01*
X708200Y520000D01*
X708575Y520083D01*
X708867Y520250D01*
X709075Y520542D01*
X709117Y520875D01*
X709033Y521208D01*
X708825Y521417D01*
X708533Y521583D01*
X708242Y521625D01*
X707950Y521583D01*
X707575Y521417D01*
X707700Y522500D01*
X708825D01*
G01X697517Y752000D02*
Y754500D01*
X698558D01*
X698892Y754375D01*
X699100Y754208D01*
X699183Y753875D01*
X699100Y753542D01*
X698850Y753333D01*
X698558Y753208D01*
X697517D01*
G01X698558D02*
X699183Y752000D01*
G01X701950D02*
Y754500D01*
X700408Y752708D01*
X702492D01*
G01X703633Y752500D02*
X703883Y752208D01*
X704217Y752042D01*
X704592Y752000D01*
X704925Y752042D01*
X705258Y752250D01*
X705467Y752500D01*
X705508Y752750D01*
X705425Y753042D01*
X705133Y753250D01*
X704842Y753333D01*
X704467D01*
G01X704842D02*
X705092Y753458D01*
X705300Y753667D01*
X705383Y753917D01*
X705300Y754167D01*
X705092Y754375D01*
X704717Y754500D01*
X704342Y754458D01*
X703967Y754292D01*
G01X707650Y754500D02*
X707317Y754417D01*
X707067Y754208D01*
X706900Y753958D01*
X706775Y753625D01*
X706733Y753250D01*
X706775Y752875D01*
X706900Y752542D01*
X707067Y752292D01*
X707317Y752083D01*
X707650Y752000D01*
X707983Y752083D01*
X708233Y752292D01*
X708400Y752542D01*
X708525Y752875D01*
X708567Y753250D01*
X708525Y753625D01*
X708400Y753958D01*
X708233Y754208D01*
X707983Y754417D01*
X707650Y754500D01*
G01X702968Y764184D02*
Y776084D01*
G01X710968Y764184D02*
X702968D01*
G01Y776084D02*
X710968D01*
G01X706968Y774484D02*
X708568Y776084D01*
G01X706968Y774484D02*
X705368Y776084D01*
G01X706000Y779017D02*
X703500D01*
Y780058D01*
X703625Y780392D01*
X703792Y780600D01*
X704125Y780683D01*
X704458Y780600D01*
X704667Y780350D01*
X704792Y780058D01*
Y779017D01*
G01Y780058D02*
X706000Y780683D01*
G01Y783450D02*
X703500D01*
X705292Y781908D01*
Y783992D01*
G01X703917Y785258D02*
X703667Y785508D01*
X703542Y785800D01*
X703500Y786133D01*
X703583Y786550D01*
X703792Y786842D01*
X704042Y786925D01*
X704292Y786883D01*
X704500Y786717D01*
X704917Y785883D01*
X705208Y785508D01*
X705625Y785258D01*
X706000Y785175D01*
Y786925D01*
G01Y789150D02*
X705958Y789442D01*
X705833Y789775D01*
X705625Y789983D01*
X705333Y790067D01*
X705042Y789983D01*
X704792Y789733D01*
X704667Y789358D01*
Y788942D01*
X704583Y788692D01*
X704375Y788483D01*
X704083Y788400D01*
X703792Y788525D01*
X703583Y788817D01*
X703500Y789150D01*
X703583Y789483D01*
X703792Y789775D01*
X704083Y789900D01*
X704375Y789817D01*
X704583Y789608D01*
X704667Y789358D01*
Y788942D01*
X704792Y788567D01*
X705042Y788317D01*
X705333Y788233D01*
X705625Y788317D01*
X705833Y788525D01*
X705958Y788858D01*
X706000Y789150D01*
G01X700968Y784684D02*
X696968D01*
Y777284D01*
G01X700968Y799684D02*
Y811584D01*
G01X708968Y799684D02*
X700968D01*
G01Y811584D02*
X708968D01*
G01X704968Y809984D02*
X706568Y811584D01*
G01X704968Y809984D02*
X703368Y811584D01*
G01X700483Y817500D02*
Y815708D01*
X700650Y815333D01*
X700983Y815083D01*
X701400Y815000D01*
X701817Y815083D01*
X702150Y815333D01*
X702317Y815708D01*
Y817500D01*
G01X703708Y817083D02*
X703958Y817333D01*
X704250Y817458D01*
X704583Y817500D01*
X705000Y817417D01*
X705292Y817208D01*
X705375Y816958D01*
X705333Y816708D01*
X705167Y816500D01*
X704333Y816083D01*
X703958Y815792D01*
X703708Y815375D01*
X703625Y815000D01*
X705375D01*
G01X706683Y815500D02*
X706933Y815208D01*
X707267Y815042D01*
X707642Y815000D01*
X707975Y815042D01*
X708308Y815250D01*
X708517Y815500D01*
X708558Y815750D01*
X708475Y816042D01*
X708183Y816250D01*
X707892Y816333D01*
X707517D01*
G01X707892D02*
X708142Y816458D01*
X708350Y816667D01*
X708433Y816917D01*
X708350Y817167D01*
X708142Y817375D01*
X707767Y817500D01*
X707392Y817458D01*
X707017Y817292D01*
G01X704317Y855792D02*
X704067Y855917D01*
X703775Y856000D01*
X703442D01*
X703067Y855875D01*
X702775Y855667D01*
X702567Y855417D01*
X702400Y855000D01*
X702358Y854625D01*
X702442Y854250D01*
X702567Y854000D01*
X702817Y853750D01*
X703108Y853583D01*
X703400Y853500D01*
X703692D01*
X703983Y853583D01*
X704233Y853708D01*
X704442Y853875D01*
G01X707000Y853500D02*
Y856000D01*
X705458Y854208D01*
X707542D01*
G01X709600Y853500D02*
Y856000D01*
X709100Y855500D01*
G01Y853500D02*
X710100D01*
G01X693000Y869433D02*
X694792D01*
X695167Y869600D01*
X695417Y869933D01*
X695500Y870350D01*
X695417Y870767D01*
X695167Y871100D01*
X694792Y871267D01*
X693000D01*
G01X695500Y873450D02*
X693000D01*
X693500Y872950D01*
G01X695500D02*
Y873950D01*
G01Y876467D02*
X694958Y876550D01*
X694500Y876675D01*
X694083Y876842D01*
X693625Y877050D01*
X693000Y877383D01*
Y875717D01*
G01X693417Y878858D02*
X693167Y879108D01*
X693042Y879400D01*
X693000Y879733D01*
X693083Y880150D01*
X693292Y880442D01*
X693542Y880525D01*
X693792Y880483D01*
X694000Y880317D01*
X694417Y879483D01*
X694708Y879108D01*
X695125Y878858D01*
X695500Y878775D01*
Y880525D01*
G01X699000Y866800D02*
Y880200D01*
G01X709000Y866800D02*
X699000D01*
G01X704200Y861500D02*
Y865500D01*
X696800D01*
G01X699000Y880200D02*
X709000D01*
G01X710000Y883517D02*
X707500D01*
Y884558D01*
X707625Y884892D01*
X707792Y885100D01*
X708125Y885183D01*
X708458Y885100D01*
X708667Y884850D01*
X708792Y884558D01*
Y883517D01*
G01Y884558D02*
X710000Y885183D01*
G01X709500Y886533D02*
X709792Y886783D01*
X709958Y887117D01*
X710000Y887492D01*
X709958Y887825D01*
X709750Y888158D01*
X709500Y888367D01*
X709250Y888408D01*
X708958Y888325D01*
X708750Y888033D01*
X708667Y887742D01*
Y887367D01*
G01Y887742D02*
X708542Y887992D01*
X708333Y888200D01*
X708083Y888283D01*
X707833Y888200D01*
X707625Y887992D01*
X707500Y887617D01*
X707542Y887242D01*
X707708Y886867D01*
G01X707917Y889758D02*
X707667Y890008D01*
X707542Y890300D01*
X707500Y890633D01*
X707583Y891050D01*
X707792Y891342D01*
X708042Y891425D01*
X708292Y891383D01*
X708500Y891217D01*
X708917Y890383D01*
X709208Y890008D01*
X709625Y889758D01*
X710000Y889675D01*
Y891425D01*
G01X709625Y892733D02*
X709833Y892983D01*
X709958Y893275D01*
X710000Y893650D01*
X709917Y894025D01*
X709750Y894317D01*
X709458Y894525D01*
X709125Y894567D01*
X708792Y894483D01*
X708583Y894275D01*
X708417Y893983D01*
X708375Y893692D01*
X708417Y893400D01*
X708583Y893025D01*
X707500Y893150D01*
Y894275D01*
G01X706000Y890200D02*
X702000D01*
Y882800D01*
G01X721032Y25233D02*
X718532D01*
Y26274D01*
X718657Y26608D01*
X718824Y26816D01*
X719157Y26899D01*
X719490Y26816D01*
X719699Y26566D01*
X719824Y26274D01*
Y25233D01*
G01Y26274D02*
X721032Y26899D01*
G01Y29166D02*
X718532D01*
X719032Y28666D01*
G01X721032D02*
Y29666D01*
G01Y32266D02*
X720990Y32558D01*
X720865Y32891D01*
X720657Y33099D01*
X720365Y33183D01*
X720074Y33099D01*
X719824Y32849D01*
X719699Y32474D01*
Y32058D01*
X719615Y31808D01*
X719407Y31599D01*
X719115Y31516D01*
X718824Y31641D01*
X718615Y31933D01*
X718532Y32266D01*
X718615Y32599D01*
X718824Y32891D01*
X719115Y33016D01*
X719407Y32933D01*
X719615Y32724D01*
X719699Y32474D01*
Y32058D01*
X719824Y31683D01*
X720074Y31433D01*
X720365Y31349D01*
X720657Y31433D01*
X720865Y31641D01*
X720990Y31974D01*
X721032Y32266D01*
G01Y35366D02*
X720990Y35658D01*
X720865Y35991D01*
X720657Y36199D01*
X720365Y36283D01*
X720074Y36199D01*
X719824Y35949D01*
X719699Y35574D01*
Y35158D01*
X719615Y34908D01*
X719407Y34699D01*
X719115Y34616D01*
X718824Y34741D01*
X718615Y35033D01*
X718532Y35366D01*
X718615Y35699D01*
X718824Y35991D01*
X719115Y36116D01*
X719407Y36033D01*
X719615Y35824D01*
X719699Y35574D01*
Y35158D01*
X719824Y34783D01*
X720074Y34533D01*
X720365Y34449D01*
X720657Y34533D01*
X720865Y34741D01*
X720990Y35074D01*
X721032Y35366D01*
G01Y38233D02*
X718532D01*
Y39274D01*
X718657Y39608D01*
X718824Y39816D01*
X719157Y39899D01*
X719490Y39816D01*
X719699Y39566D01*
X719824Y39274D01*
Y38233D01*
G01Y39274D02*
X721032Y39899D01*
G01Y42166D02*
X718532D01*
X719032Y41666D01*
G01X721032D02*
Y42666D01*
G01Y45266D02*
X720990Y45558D01*
X720865Y45891D01*
X720657Y46099D01*
X720365Y46183D01*
X720074Y46099D01*
X719824Y45849D01*
X719699Y45474D01*
Y45058D01*
X719615Y44808D01*
X719407Y44599D01*
X719115Y44516D01*
X718824Y44641D01*
X718615Y44933D01*
X718532Y45266D01*
X718615Y45599D01*
X718824Y45891D01*
X719115Y46016D01*
X719407Y45933D01*
X719615Y45724D01*
X719699Y45474D01*
Y45058D01*
X719824Y44683D01*
X720074Y44433D01*
X720365Y44349D01*
X720657Y44433D01*
X720865Y44641D01*
X720990Y44974D01*
X721032Y45266D01*
G01X720740Y47658D02*
X720949Y47949D01*
X721032Y48283D01*
X720949Y48616D01*
X720699Y48908D01*
X720324Y49116D01*
X719949Y49199D01*
X719490D01*
X719115Y49116D01*
X718782Y48908D01*
X718615Y48658D01*
X718532Y48366D01*
X718615Y48033D01*
X718782Y47783D01*
X719032Y47616D01*
X719365Y47533D01*
X719657Y47616D01*
X719949Y47824D01*
X720115Y48074D01*
X720157Y48366D01*
X720074Y48699D01*
X719865Y48949D01*
X719490Y49199D01*
G01X725532Y25233D02*
X723032D01*
Y26274D01*
X723157Y26608D01*
X723324Y26816D01*
X723657Y26899D01*
X723990Y26816D01*
X724199Y26566D01*
X724324Y26274D01*
Y25233D01*
G01Y26274D02*
X725532Y26899D01*
G01Y29166D02*
X723032D01*
X723532Y28666D01*
G01X725532D02*
Y29666D01*
G01X725240Y31558D02*
X725449Y31849D01*
X725532Y32183D01*
X725449Y32516D01*
X725199Y32808D01*
X724824Y33016D01*
X724449Y33099D01*
X723990D01*
X723615Y33016D01*
X723282Y32808D01*
X723115Y32558D01*
X723032Y32266D01*
X723115Y31933D01*
X723282Y31683D01*
X723532Y31516D01*
X723865Y31433D01*
X724157Y31516D01*
X724449Y31724D01*
X724615Y31974D01*
X724657Y32266D01*
X724574Y32599D01*
X724365Y32849D01*
X723990Y33099D01*
G01X725157Y34449D02*
X725365Y34699D01*
X725490Y34991D01*
X725532Y35366D01*
X725449Y35741D01*
X725282Y36033D01*
X724990Y36241D01*
X724657Y36283D01*
X724324Y36199D01*
X724115Y35991D01*
X723949Y35699D01*
X723907Y35408D01*
X723949Y35116D01*
X724115Y34741D01*
X723032Y34866D01*
Y35991D01*
G01X725532Y38233D02*
X723032D01*
Y39274D01*
X723157Y39608D01*
X723324Y39816D01*
X723657Y39899D01*
X723990Y39816D01*
X724199Y39566D01*
X724324Y39274D01*
Y38233D01*
G01Y39274D02*
X725532Y39899D01*
G01Y42166D02*
X723032D01*
X723532Y41666D01*
G01X725532D02*
Y42666D01*
G01X725240Y44558D02*
X725449Y44849D01*
X725532Y45183D01*
X725449Y45516D01*
X725199Y45808D01*
X724824Y46016D01*
X724449Y46099D01*
X723990D01*
X723615Y46016D01*
X723282Y45808D01*
X723115Y45558D01*
X723032Y45266D01*
X723115Y44933D01*
X723282Y44683D01*
X723532Y44516D01*
X723865Y44433D01*
X724157Y44516D01*
X724449Y44724D01*
X724615Y44974D01*
X724657Y45266D01*
X724574Y45599D01*
X724365Y45849D01*
X723990Y46099D01*
G01X724490Y47574D02*
X724199Y47866D01*
X724032Y48116D01*
X723949Y48449D01*
X724032Y48741D01*
X724199Y48949D01*
X724449Y49116D01*
X724740Y49158D01*
X724990Y49116D01*
X725240Y48949D01*
X725449Y48699D01*
X725532Y48408D01*
X725449Y48074D01*
X725199Y47783D01*
X724824Y47616D01*
X724407Y47574D01*
X723865Y47658D01*
X723574Y47783D01*
X723282Y47991D01*
X723074Y48283D01*
X723032Y48574D01*
X723115Y48866D01*
X723324Y49074D01*
G01X710208Y42267D02*
X710083Y42017D01*
X710000Y41725D01*
Y41392D01*
X710125Y41017D01*
X710333Y40725D01*
X710583Y40517D01*
X711000Y40350D01*
X711375Y40308D01*
X711750Y40392D01*
X712000Y40517D01*
X712250Y40767D01*
X712417Y41058D01*
X712500Y41350D01*
Y41642D01*
X712417Y41933D01*
X712292Y42183D01*
X712125Y42392D01*
G01X712500Y44450D02*
X710000D01*
X710500Y43950D01*
G01X712500D02*
Y44950D01*
G01X712125Y46633D02*
X712333Y46883D01*
X712458Y47175D01*
X712500Y47550D01*
X712417Y47925D01*
X712250Y48217D01*
X711958Y48425D01*
X711625Y48467D01*
X711292Y48383D01*
X711083Y48175D01*
X710917Y47883D01*
X710875Y47592D01*
X710917Y47300D01*
X711083Y46925D01*
X710000Y47050D01*
Y48175D01*
G01X712000Y49733D02*
X712292Y49983D01*
X712458Y50317D01*
X712500Y50692D01*
X712458Y51025D01*
X712250Y51358D01*
X712000Y51567D01*
X711750Y51608D01*
X711458Y51525D01*
X711250Y51233D01*
X711167Y50942D01*
Y50567D01*
G01Y50942D02*
X711042Y51192D01*
X710833Y51400D01*
X710583Y51483D01*
X710333Y51400D01*
X710125Y51192D01*
X710000Y50817D01*
X710042Y50442D01*
X710208Y50067D01*
G01X718032Y52016D02*
X722032D01*
Y59416D01*
G01X726532D02*
X722532D01*
Y52016D01*
G01X723500Y74300D02*
X726000D01*
G01X723500Y73342D02*
Y75258D01*
G01X726000Y76567D02*
X723500D01*
Y77567D01*
X723625Y77900D01*
X723917Y78150D01*
X724250Y78233D01*
X724583Y78150D01*
X724833Y77942D01*
X724958Y77567D01*
Y76567D01*
G01X726000Y80500D02*
X723500D01*
X724000Y80000D01*
G01X726000D02*
Y81000D01*
G01X723917Y82808D02*
X723667Y83058D01*
X723542Y83350D01*
X723500Y83683D01*
X723583Y84100D01*
X723792Y84392D01*
X724042Y84475D01*
X724292Y84433D01*
X724500Y84267D01*
X724917Y83433D01*
X725208Y83058D01*
X725625Y82808D01*
X726000Y82725D01*
Y84475D01*
G01X725708Y85992D02*
X725917Y86283D01*
X726000Y86617D01*
X725917Y86950D01*
X725667Y87242D01*
X725292Y87450D01*
X724917Y87533D01*
X724458D01*
X724083Y87450D01*
X723750Y87242D01*
X723583Y86992D01*
X723500Y86700D01*
X723583Y86367D01*
X723750Y86117D01*
X724000Y85950D01*
X724333Y85867D01*
X724625Y85950D01*
X724917Y86158D01*
X725083Y86408D01*
X725125Y86700D01*
X725042Y87033D01*
X724833Y87283D01*
X724458Y87533D01*
G01X722032Y67416D02*
X718032D01*
Y60016D01*
G01X722532D02*
X726532D01*
Y67416D01*
G01X721500Y72017D02*
X719000D01*
Y73058D01*
X719125Y73392D01*
X719292Y73600D01*
X719625Y73683D01*
X719958Y73600D01*
X720167Y73350D01*
X720292Y73058D01*
Y72017D01*
G01Y73058D02*
X721500Y73683D01*
G01X721000Y75033D02*
X721292Y75283D01*
X721458Y75617D01*
X721500Y75992D01*
X721458Y76325D01*
X721250Y76658D01*
X721000Y76867D01*
X720750Y76908D01*
X720458Y76825D01*
X720250Y76533D01*
X720167Y76242D01*
Y75867D01*
G01Y76242D02*
X720042Y76492D01*
X719833Y76700D01*
X719583Y76783D01*
X719333Y76700D01*
X719125Y76492D01*
X719000Y76117D01*
X719042Y75742D01*
X719208Y75367D01*
G01X721500Y79050D02*
X721458Y79342D01*
X721333Y79675D01*
X721125Y79883D01*
X720833Y79967D01*
X720542Y79883D01*
X720292Y79633D01*
X720167Y79258D01*
Y78842D01*
X720083Y78592D01*
X719875Y78383D01*
X719583Y78300D01*
X719292Y78425D01*
X719083Y78717D01*
X719000Y79050D01*
X719083Y79383D01*
X719292Y79675D01*
X719583Y79800D01*
X719875Y79717D01*
X720083Y79508D01*
X720167Y79258D01*
Y78842D01*
X720292Y78467D01*
X720542Y78217D01*
X720833Y78133D01*
X721125Y78217D01*
X721333Y78425D01*
X721458Y78758D01*
X721500Y79050D01*
G01Y82650D02*
X719000D01*
X720792Y81108D01*
Y83192D01*
G01X717716Y92484D02*
X713716D01*
Y85084D01*
G01X709216D02*
X713216D01*
Y92484D01*
G01X718216Y85084D02*
X722216D01*
Y92484D01*
G01X720732Y104384D02*
Y101384D01*
G01X710892Y104384D02*
Y102384D01*
G01X728232Y98532D02*
Y102532D01*
X720832D01*
G01X714828Y138184D02*
Y141184D01*
G01X711716Y146584D02*
X715716D01*
Y153984D01*
G01X716216Y146584D02*
X720216D01*
Y153984D01*
G01X720716Y146584D02*
X724716D01*
Y153984D01*
G01X713216Y155801D02*
X710716D01*
Y156842D01*
X710841Y157176D01*
X711008Y157384D01*
X711341Y157467D01*
X711674Y157384D01*
X711883Y157134D01*
X712008Y156842D01*
Y155801D01*
G01Y156842D02*
X713216Y157467D01*
G01X712716Y158817D02*
X713008Y159067D01*
X713174Y159401D01*
X713216Y159776D01*
X713174Y160109D01*
X712966Y160442D01*
X712716Y160651D01*
X712466Y160692D01*
X712174Y160609D01*
X711966Y160317D01*
X711883Y160026D01*
Y159651D01*
G01Y160026D02*
X711758Y160276D01*
X711549Y160484D01*
X711299Y160567D01*
X711049Y160484D01*
X710841Y160276D01*
X710716Y159901D01*
X710758Y159526D01*
X710924Y159151D01*
G01X712924Y162126D02*
X713133Y162417D01*
X713216Y162751D01*
X713133Y163084D01*
X712883Y163376D01*
X712508Y163584D01*
X712133Y163667D01*
X711674D01*
X711299Y163584D01*
X710966Y163376D01*
X710799Y163126D01*
X710716Y162834D01*
X710799Y162501D01*
X710966Y162251D01*
X711216Y162084D01*
X711549Y162001D01*
X711841Y162084D01*
X712133Y162292D01*
X712299Y162542D01*
X712341Y162834D01*
X712258Y163167D01*
X712049Y163417D01*
X711674Y163667D01*
G01X711133Y165142D02*
X710883Y165392D01*
X710758Y165684D01*
X710716Y166017D01*
X710799Y166434D01*
X711008Y166726D01*
X711258Y166809D01*
X711508Y166767D01*
X711716Y166601D01*
X712133Y165767D01*
X712424Y165392D01*
X712841Y165142D01*
X713216Y165059D01*
Y166809D01*
G01X717716Y155801D02*
X715216D01*
Y156842D01*
X715341Y157176D01*
X715508Y157384D01*
X715841Y157467D01*
X716174Y157384D01*
X716383Y157134D01*
X716508Y156842D01*
Y155801D01*
G01Y156842D02*
X717716Y157467D01*
G01X717216Y158817D02*
X717508Y159067D01*
X717674Y159401D01*
X717716Y159776D01*
X717674Y160109D01*
X717466Y160442D01*
X717216Y160651D01*
X716966Y160692D01*
X716674Y160609D01*
X716466Y160317D01*
X716383Y160026D01*
Y159651D01*
G01Y160026D02*
X716258Y160276D01*
X716049Y160484D01*
X715799Y160567D01*
X715549Y160484D01*
X715341Y160276D01*
X715216Y159901D01*
X715258Y159526D01*
X715424Y159151D01*
G01X717424Y162126D02*
X717633Y162417D01*
X717716Y162751D01*
X717633Y163084D01*
X717383Y163376D01*
X717008Y163584D01*
X716633Y163667D01*
X716174D01*
X715799Y163584D01*
X715466Y163376D01*
X715299Y163126D01*
X715216Y162834D01*
X715299Y162501D01*
X715466Y162251D01*
X715716Y162084D01*
X716049Y162001D01*
X716341Y162084D01*
X716633Y162292D01*
X716799Y162542D01*
X716841Y162834D01*
X716758Y163167D01*
X716549Y163417D01*
X716174Y163667D01*
G01X717716Y165934D02*
X715216D01*
X715716Y165434D01*
G01X717716D02*
Y166434D01*
G01X722216Y155801D02*
X719716D01*
Y156842D01*
X719841Y157176D01*
X720008Y157384D01*
X720341Y157467D01*
X720674Y157384D01*
X720883Y157134D01*
X721008Y156842D01*
Y155801D01*
G01Y156842D02*
X722216Y157467D01*
G01X721716Y158817D02*
X722008Y159067D01*
X722174Y159401D01*
X722216Y159776D01*
X722174Y160109D01*
X721966Y160442D01*
X721716Y160651D01*
X721466Y160692D01*
X721174Y160609D01*
X720966Y160317D01*
X720883Y160026D01*
Y159651D01*
G01Y160026D02*
X720758Y160276D01*
X720549Y160484D01*
X720299Y160567D01*
X720049Y160484D01*
X719841Y160276D01*
X719716Y159901D01*
X719758Y159526D01*
X719924Y159151D01*
G01X721924Y162126D02*
X722133Y162417D01*
X722216Y162751D01*
X722133Y163084D01*
X721883Y163376D01*
X721508Y163584D01*
X721133Y163667D01*
X720674D01*
X720299Y163584D01*
X719966Y163376D01*
X719799Y163126D01*
X719716Y162834D01*
X719799Y162501D01*
X719966Y162251D01*
X720216Y162084D01*
X720549Y162001D01*
X720841Y162084D01*
X721133Y162292D01*
X721299Y162542D01*
X721341Y162834D01*
X721258Y163167D01*
X721049Y163417D01*
X720674Y163667D01*
G01X719716Y165934D02*
X719799Y165601D01*
X720008Y165351D01*
X720258Y165184D01*
X720591Y165059D01*
X720966Y165017D01*
X721341Y165059D01*
X721674Y165184D01*
X721924Y165351D01*
X722133Y165601D01*
X722216Y165934D01*
X722133Y166267D01*
X721924Y166517D01*
X721674Y166684D01*
X721341Y166809D01*
X720966Y166851D01*
X720591Y166809D01*
X720258Y166684D01*
X720008Y166517D01*
X719799Y166267D01*
X719716Y165934D01*
G01X716748Y176017D02*
X714248D01*
Y177058D01*
X714373Y177392D01*
X714540Y177600D01*
X714873Y177683D01*
X715206Y177600D01*
X715415Y177350D01*
X715540Y177058D01*
Y176017D01*
G01Y177058D02*
X716748Y177683D01*
G01X716373Y179033D02*
X716581Y179283D01*
X716706Y179575D01*
X716748Y179950D01*
X716665Y180325D01*
X716498Y180617D01*
X716206Y180825D01*
X715873Y180867D01*
X715540Y180783D01*
X715331Y180575D01*
X715165Y180283D01*
X715123Y179992D01*
X715165Y179700D01*
X715331Y179325D01*
X714248Y179450D01*
Y180575D01*
G01X714665Y182258D02*
X714415Y182508D01*
X714290Y182800D01*
X714248Y183133D01*
X714331Y183550D01*
X714540Y183842D01*
X714790Y183925D01*
X715040Y183883D01*
X715248Y183717D01*
X715665Y182883D01*
X715956Y182508D01*
X716373Y182258D01*
X716748Y182175D01*
Y183925D01*
G01X716373Y185233D02*
X716581Y185483D01*
X716706Y185775D01*
X716748Y186150D01*
X716665Y186525D01*
X716498Y186817D01*
X716206Y187025D01*
X715873Y187067D01*
X715540Y186983D01*
X715331Y186775D01*
X715165Y186483D01*
X715123Y186192D01*
X715165Y185900D01*
X715331Y185525D01*
X714248Y185650D01*
Y186775D01*
G01X727748Y186200D02*
X723748D01*
Y178800D01*
G01X718456Y177767D02*
X718331Y177517D01*
X718248Y177225D01*
Y176892D01*
X718373Y176517D01*
X718581Y176225D01*
X718831Y176017D01*
X719248Y175850D01*
X719623Y175808D01*
X719998Y175892D01*
X720248Y176017D01*
X720498Y176267D01*
X720665Y176558D01*
X720748Y176850D01*
Y177142D01*
X720665Y177433D01*
X720540Y177683D01*
X720373Y177892D01*
G01X718665Y179158D02*
X718415Y179408D01*
X718290Y179700D01*
X718248Y180033D01*
X718331Y180450D01*
X718540Y180742D01*
X718790Y180825D01*
X719040Y180783D01*
X719248Y180617D01*
X719665Y179783D01*
X719956Y179408D01*
X720373Y179158D01*
X720748Y179075D01*
Y180825D01*
G01Y182967D02*
X720206Y183050D01*
X719748Y183175D01*
X719331Y183342D01*
X718873Y183550D01*
X718248Y183883D01*
Y182217D01*
G01X720748Y186150D02*
X718248D01*
X718748Y185650D01*
G01X720748D02*
Y186650D01*
G01X717300Y199500D02*
Y195500D01*
X724700D01*
G01X717300D02*
Y191500D01*
X724700D01*
G01X708267Y208000D02*
Y210500D01*
X709308D01*
X709642Y210375D01*
X709850Y210208D01*
X709933Y209875D01*
X709850Y209542D01*
X709600Y209333D01*
X709308Y209208D01*
X708267D01*
G01X709308D02*
X709933Y208000D01*
G01X711408Y210083D02*
X711658Y210333D01*
X711950Y210458D01*
X712283Y210500D01*
X712700Y210417D01*
X712992Y210208D01*
X713075Y209958D01*
X713033Y209708D01*
X712867Y209500D01*
X712033Y209083D01*
X711658Y208792D01*
X711408Y208375D01*
X711325Y208000D01*
X713075D01*
G01X714508Y210083D02*
X714758Y210333D01*
X715050Y210458D01*
X715383Y210500D01*
X715800Y210417D01*
X716092Y210208D01*
X716175Y209958D01*
X716133Y209708D01*
X715967Y209500D01*
X715133Y209083D01*
X714758Y208792D01*
X714508Y208375D01*
X714425Y208000D01*
X716175D01*
G01X720000Y211000D02*
Y207000D01*
X727400D01*
G01X708263Y249767D02*
X708138Y249517D01*
X708055Y249225D01*
Y248892D01*
X708180Y248517D01*
X708388Y248225D01*
X708638Y248017D01*
X709055Y247850D01*
X709430Y247808D01*
X709805Y247892D01*
X710055Y248017D01*
X710305Y248267D01*
X710472Y248558D01*
X710555Y248850D01*
Y249142D01*
X710472Y249433D01*
X710347Y249683D01*
X710180Y249892D01*
G01X708472Y251158D02*
X708222Y251408D01*
X708097Y251700D01*
X708055Y252033D01*
X708138Y252450D01*
X708347Y252742D01*
X708597Y252825D01*
X708847Y252783D01*
X709055Y252617D01*
X709472Y251783D01*
X709763Y251408D01*
X710180Y251158D01*
X710555Y251075D01*
Y252825D01*
G01Y254967D02*
X710013Y255050D01*
X709555Y255175D01*
X709138Y255342D01*
X708680Y255550D01*
X708055Y255883D01*
Y254217D01*
G01X710180Y257233D02*
X710388Y257483D01*
X710513Y257775D01*
X710555Y258150D01*
X710472Y258525D01*
X710305Y258817D01*
X710013Y259025D01*
X709680Y259067D01*
X709347Y258983D01*
X709138Y258775D01*
X708972Y258483D01*
X708930Y258192D01*
X708972Y257900D01*
X709138Y257525D01*
X708055Y257650D01*
Y258775D01*
G01X712263Y249767D02*
X712138Y249517D01*
X712055Y249225D01*
Y248892D01*
X712180Y248517D01*
X712388Y248225D01*
X712638Y248017D01*
X713055Y247850D01*
X713430Y247808D01*
X713805Y247892D01*
X714055Y248017D01*
X714305Y248267D01*
X714472Y248558D01*
X714555Y248850D01*
Y249142D01*
X714472Y249433D01*
X714347Y249683D01*
X714180Y249892D01*
G01X712472Y251158D02*
X712222Y251408D01*
X712097Y251700D01*
X712055Y252033D01*
X712138Y252450D01*
X712347Y252742D01*
X712597Y252825D01*
X712847Y252783D01*
X713055Y252617D01*
X713472Y251783D01*
X713763Y251408D01*
X714180Y251158D01*
X714555Y251075D01*
Y252825D01*
G01X714263Y254342D02*
X714472Y254633D01*
X714555Y254967D01*
X714472Y255300D01*
X714222Y255592D01*
X713847Y255800D01*
X713472Y255883D01*
X713013D01*
X712638Y255800D01*
X712305Y255592D01*
X712138Y255342D01*
X712055Y255050D01*
X712138Y254717D01*
X712305Y254467D01*
X712555Y254300D01*
X712888Y254217D01*
X713180Y254300D01*
X713472Y254508D01*
X713638Y254758D01*
X713680Y255050D01*
X713597Y255383D01*
X713388Y255633D01*
X713013Y255883D01*
G01X712055Y258150D02*
X712138Y257817D01*
X712347Y257567D01*
X712597Y257400D01*
X712930Y257275D01*
X713305Y257233D01*
X713680Y257275D01*
X714013Y257400D01*
X714263Y257567D01*
X714472Y257817D01*
X714555Y258150D01*
X714472Y258483D01*
X714263Y258733D01*
X714013Y258900D01*
X713680Y259025D01*
X713305Y259067D01*
X712930Y259025D01*
X712597Y258900D01*
X712347Y258733D01*
X712138Y258483D01*
X712055Y258150D01*
G01X716263Y249767D02*
X716138Y249517D01*
X716055Y249225D01*
Y248892D01*
X716180Y248517D01*
X716388Y248225D01*
X716638Y248017D01*
X717055Y247850D01*
X717430Y247808D01*
X717805Y247892D01*
X718055Y248017D01*
X718305Y248267D01*
X718472Y248558D01*
X718555Y248850D01*
Y249142D01*
X718472Y249433D01*
X718347Y249683D01*
X718180Y249892D01*
G01X716472Y251158D02*
X716222Y251408D01*
X716097Y251700D01*
X716055Y252033D01*
X716138Y252450D01*
X716347Y252742D01*
X716597Y252825D01*
X716847Y252783D01*
X717055Y252617D01*
X717472Y251783D01*
X717763Y251408D01*
X718180Y251158D01*
X718555Y251075D01*
Y252825D01*
G01X718263Y254342D02*
X718472Y254633D01*
X718555Y254967D01*
X718472Y255300D01*
X718222Y255592D01*
X717847Y255800D01*
X717472Y255883D01*
X717013D01*
X716638Y255800D01*
X716305Y255592D01*
X716138Y255342D01*
X716055Y255050D01*
X716138Y254717D01*
X716305Y254467D01*
X716555Y254300D01*
X716888Y254217D01*
X717180Y254300D01*
X717472Y254508D01*
X717638Y254758D01*
X717680Y255050D01*
X717597Y255383D01*
X717388Y255633D01*
X717013Y255883D01*
G01X718555Y258150D02*
X716055D01*
X716555Y257650D01*
G01X718555D02*
Y258650D01*
G01X720517Y449000D02*
Y451500D01*
X721558D01*
X721892Y451375D01*
X722100Y451208D01*
X722183Y450875D01*
X722100Y450542D01*
X721850Y450333D01*
X721558Y450208D01*
X720517D01*
G01X721558D02*
X722183Y449000D01*
G01X723533Y449375D02*
X723783Y449167D01*
X724075Y449042D01*
X724450Y449000D01*
X724825Y449083D01*
X725117Y449250D01*
X725325Y449542D01*
X725367Y449875D01*
X725283Y450208D01*
X725075Y450417D01*
X724783Y450583D01*
X724492Y450625D01*
X724200Y450583D01*
X723825Y450417D01*
X723950Y451500D01*
X725075D01*
G01X726758Y451083D02*
X727008Y451333D01*
X727300Y451458D01*
X727633Y451500D01*
X728050Y451417D01*
X728342Y451208D01*
X728425Y450958D01*
X728383Y450708D01*
X728217Y450500D01*
X727383Y450083D01*
X727008Y449792D01*
X726758Y449375D01*
X726675Y449000D01*
X728425D01*
G01X731150D02*
Y451500D01*
X729608Y449708D01*
X731692D01*
G01X717500Y463483D02*
X719292D01*
X719667Y463650D01*
X719917Y463983D01*
X720000Y464400D01*
X719917Y464817D01*
X719667Y465150D01*
X719292Y465317D01*
X717500D01*
G01X719500Y466583D02*
X719792Y466833D01*
X719958Y467167D01*
X720000Y467542D01*
X719958Y467875D01*
X719750Y468208D01*
X719500Y468417D01*
X719250Y468458D01*
X718958Y468375D01*
X718750Y468083D01*
X718667Y467792D01*
Y467417D01*
G01Y467792D02*
X718542Y468042D01*
X718333Y468250D01*
X718083Y468333D01*
X717833Y468250D01*
X717625Y468042D01*
X717500Y467667D01*
X717542Y467292D01*
X717708Y466917D01*
G01X717917Y469808D02*
X717667Y470058D01*
X717542Y470350D01*
X717500Y470683D01*
X717583Y471100D01*
X717792Y471392D01*
X718042Y471475D01*
X718292Y471433D01*
X718500Y471267D01*
X718917Y470433D01*
X719208Y470058D01*
X719625Y469808D01*
X720000Y469725D01*
Y471475D01*
G01X722500Y461122D02*
Y474522D01*
G01X732500Y461122D02*
X722500D01*
G01X730200Y453500D02*
Y457500D01*
X722800D01*
G01X722500Y474522D02*
X732500D01*
G01X721481Y557538D02*
Y560038D01*
X722522D01*
X722856Y559913D01*
X723064Y559746D01*
X723147Y559413D01*
X723064Y559080D01*
X722814Y558871D01*
X722522Y558746D01*
X721481D01*
G01X722522D02*
X723147Y557538D01*
G01X724622Y558580D02*
X724914Y558871D01*
X725164Y559038D01*
X725497Y559121D01*
X725789Y559038D01*
X725997Y558871D01*
X726164Y558621D01*
X726206Y558330D01*
X726164Y558080D01*
X725997Y557830D01*
X725747Y557621D01*
X725456Y557538D01*
X725122Y557621D01*
X724831Y557871D01*
X724664Y558246D01*
X724622Y558663D01*
X724706Y559205D01*
X724831Y559496D01*
X725039Y559788D01*
X725331Y559996D01*
X725622Y560038D01*
X725914Y559955D01*
X726122Y559746D01*
G01X728514Y560038D02*
X728181Y559955D01*
X727931Y559746D01*
X727764Y559496D01*
X727639Y559163D01*
X727597Y558788D01*
X727639Y558413D01*
X727764Y558080D01*
X727931Y557830D01*
X728181Y557621D01*
X728514Y557538D01*
X728847Y557621D01*
X729097Y557830D01*
X729264Y558080D01*
X729389Y558413D01*
X729431Y558788D01*
X729389Y559163D01*
X729264Y559496D01*
X729097Y559746D01*
X728847Y559955D01*
X728514Y560038D01*
G01X731614Y557538D02*
X731906Y557580D01*
X732239Y557705D01*
X732447Y557913D01*
X732531Y558205D01*
X732447Y558496D01*
X732197Y558746D01*
X731822Y558871D01*
X731406D01*
X731156Y558955D01*
X730947Y559163D01*
X730864Y559455D01*
X730989Y559746D01*
X731281Y559955D01*
X731614Y560038D01*
X731947Y559955D01*
X732239Y559746D01*
X732364Y559455D01*
X732281Y559163D01*
X732072Y558955D01*
X731822Y558871D01*
X731406D01*
X731031Y558746D01*
X730781Y558496D01*
X730697Y558205D01*
X730781Y557913D01*
X730989Y557705D01*
X731322Y557580D01*
X731614Y557538D01*
G01X721517Y561500D02*
Y564000D01*
X722558D01*
X722892Y563875D01*
X723100Y563708D01*
X723183Y563375D01*
X723100Y563042D01*
X722850Y562833D01*
X722558Y562708D01*
X721517D01*
G01X722558D02*
X723183Y561500D01*
G01X724658Y562542D02*
X724950Y562833D01*
X725200Y563000D01*
X725533Y563083D01*
X725825Y563000D01*
X726033Y562833D01*
X726200Y562583D01*
X726242Y562292D01*
X726200Y562042D01*
X726033Y561792D01*
X725783Y561583D01*
X725492Y561500D01*
X725158Y561583D01*
X724867Y561833D01*
X724700Y562208D01*
X724658Y562625D01*
X724742Y563167D01*
X724867Y563458D01*
X725075Y563750D01*
X725367Y563958D01*
X725658Y564000D01*
X725950Y563917D01*
X726158Y563708D01*
G01X728550Y564000D02*
X728217Y563917D01*
X727967Y563708D01*
X727800Y563458D01*
X727675Y563125D01*
X727633Y562750D01*
X727675Y562375D01*
X727800Y562042D01*
X727967Y561792D01*
X728217Y561583D01*
X728550Y561500D01*
X728883Y561583D01*
X729133Y561792D01*
X729300Y562042D01*
X729425Y562375D01*
X729467Y562750D01*
X729425Y563125D01*
X729300Y563458D01*
X729133Y563708D01*
X728883Y563917D01*
X728550Y564000D01*
G01X730942Y561792D02*
X731233Y561583D01*
X731567Y561500D01*
X731900Y561583D01*
X732192Y561833D01*
X732400Y562208D01*
X732483Y562583D01*
Y563042D01*
X732400Y563417D01*
X732192Y563750D01*
X731942Y563917D01*
X731650Y564000D01*
X731317Y563917D01*
X731067Y563750D01*
X730900Y563500D01*
X730817Y563167D01*
X730900Y562875D01*
X731108Y562583D01*
X731358Y562417D01*
X731650Y562375D01*
X731983Y562458D01*
X732233Y562667D01*
X732483Y563042D01*
G01X719425Y553333D02*
X719758Y553125D01*
X720133Y553000D01*
X720467D01*
X720800Y553125D01*
X721050Y553333D01*
X721175Y553625D01*
X721092Y553917D01*
X720883Y554167D01*
X720508Y554333D01*
X720008Y554417D01*
X719717Y554583D01*
X719592Y554875D01*
X719675Y555167D01*
X719883Y555375D01*
X720175Y555500D01*
X720467D01*
X720758Y555417D01*
X721008Y555208D01*
G01X722567Y553000D02*
Y555500D01*
X723608D01*
X723942Y555375D01*
X724150Y555208D01*
X724233Y554875D01*
X724150Y554542D01*
X723900Y554333D01*
X723608Y554208D01*
X722567D01*
G01X723608D02*
X724233Y553000D01*
G01X726417D02*
X726500Y553542D01*
X726625Y554000D01*
X726792Y554417D01*
X727000Y554875D01*
X727333Y555500D01*
X725667D01*
G01X728808Y554042D02*
X729100Y554333D01*
X729350Y554500D01*
X729683Y554583D01*
X729975Y554500D01*
X730183Y554333D01*
X730350Y554083D01*
X730392Y553792D01*
X730350Y553542D01*
X730183Y553292D01*
X729933Y553083D01*
X729642Y553000D01*
X729308Y553083D01*
X729017Y553333D01*
X728850Y553708D01*
X728808Y554125D01*
X728892Y554667D01*
X729017Y554958D01*
X729225Y555250D01*
X729517Y555458D01*
X729808Y555500D01*
X730100Y555417D01*
X730308Y555208D01*
G01X733200Y553000D02*
Y555500D01*
X731658Y553708D01*
X733742D01*
G01X715200Y574500D02*
Y578500D01*
X707800D01*
G01X715200Y580000D02*
Y584000D01*
X707800D01*
G01X715200Y570000D02*
Y574000D01*
X707800D01*
G01X722475Y586833D02*
X722808Y586625D01*
X723183Y586500D01*
X723517D01*
X723850Y586625D01*
X724100Y586833D01*
X724225Y587125D01*
X724142Y587417D01*
X723933Y587667D01*
X723558Y587833D01*
X723058Y587917D01*
X722767Y588083D01*
X722642Y588375D01*
X722725Y588667D01*
X722933Y588875D01*
X723225Y589000D01*
X723517D01*
X723808Y588917D01*
X724058Y588708D01*
G01X725533Y589000D02*
Y587208D01*
X725700Y586833D01*
X726033Y586583D01*
X726450Y586500D01*
X726867Y586583D01*
X727200Y586833D01*
X727367Y587208D01*
Y589000D01*
G01X729467Y586500D02*
X729550Y587042D01*
X729675Y587500D01*
X729842Y587917D01*
X730050Y588375D01*
X730383Y589000D01*
X728717D01*
G01X732650Y586500D02*
X732942Y586542D01*
X733275Y586667D01*
X733483Y586875D01*
X733567Y587167D01*
X733483Y587458D01*
X733233Y587708D01*
X732858Y587833D01*
X732442D01*
X732192Y587917D01*
X731983Y588125D01*
X731900Y588417D01*
X732025Y588708D01*
X732317Y588917D01*
X732650Y589000D01*
X732983Y588917D01*
X733275Y588708D01*
X733400Y588417D01*
X733317Y588125D01*
X733108Y587917D01*
X732858Y587833D01*
X732442D01*
X732067Y587708D01*
X731817Y587458D01*
X731733Y587167D01*
X731817Y586875D01*
X732025Y586667D01*
X732358Y586542D01*
X732650Y586500D01*
G01X717468Y760184D02*
X713468D01*
Y752784D01*
G01X721208Y753767D02*
X721083Y753517D01*
X721000Y753225D01*
Y752892D01*
X721125Y752517D01*
X721333Y752225D01*
X721583Y752017D01*
X722000Y751850D01*
X722375Y751808D01*
X722750Y751892D01*
X723000Y752017D01*
X723250Y752267D01*
X723417Y752558D01*
X723500Y752850D01*
Y753142D01*
X723417Y753433D01*
X723292Y753683D01*
X723125Y753892D01*
G01X721417Y755158D02*
X721167Y755408D01*
X721042Y755700D01*
X721000Y756033D01*
X721083Y756450D01*
X721292Y756742D01*
X721542Y756825D01*
X721792Y756783D01*
X722000Y756617D01*
X722417Y755783D01*
X722708Y755408D01*
X723125Y755158D01*
X723500Y755075D01*
Y756825D01*
G01Y759550D02*
X721000D01*
X722792Y758008D01*
Y760092D01*
G01X723500Y762150D02*
X723458Y762442D01*
X723333Y762775D01*
X723125Y762983D01*
X722833Y763067D01*
X722542Y762983D01*
X722292Y762733D01*
X722167Y762358D01*
Y761942D01*
X722083Y761692D01*
X721875Y761483D01*
X721583Y761400D01*
X721292Y761525D01*
X721083Y761817D01*
X721000Y762150D01*
X721083Y762483D01*
X721292Y762775D01*
X721583Y762900D01*
X721875Y762817D01*
X722083Y762608D01*
X722167Y762358D01*
Y761942D01*
X722292Y761567D01*
X722542Y761317D01*
X722833Y761233D01*
X723125Y761317D01*
X723333Y761525D01*
X723458Y761858D01*
X723500Y762150D01*
G01X708983Y782000D02*
Y780208D01*
X709150Y779833D01*
X709483Y779583D01*
X709900Y779500D01*
X710317Y779583D01*
X710650Y779833D01*
X710817Y780208D01*
Y782000D01*
G01X712208Y781583D02*
X712458Y781833D01*
X712750Y781958D01*
X713083Y782000D01*
X713500Y781917D01*
X713792Y781708D01*
X713875Y781458D01*
X713833Y781208D01*
X713667Y781000D01*
X712833Y780583D01*
X712458Y780292D01*
X712208Y779875D01*
X712125Y779500D01*
X713875D01*
G01X716600D02*
Y782000D01*
X715058Y780208D01*
X717142D01*
G01X710968Y776084D02*
Y764184D01*
G01X721208Y773767D02*
X721083Y773517D01*
X721000Y773225D01*
Y772892D01*
X721125Y772517D01*
X721333Y772225D01*
X721583Y772017D01*
X722000Y771850D01*
X722375Y771808D01*
X722750Y771892D01*
X723000Y772017D01*
X723250Y772267D01*
X723417Y772558D01*
X723500Y772850D01*
Y773142D01*
X723417Y773433D01*
X723292Y773683D01*
X723125Y773892D01*
G01X721417Y775158D02*
X721167Y775408D01*
X721042Y775700D01*
X721000Y776033D01*
X721083Y776450D01*
X721292Y776742D01*
X721542Y776825D01*
X721792Y776783D01*
X722000Y776617D01*
X722417Y775783D01*
X722708Y775408D01*
X723125Y775158D01*
X723500Y775075D01*
Y776825D01*
G01Y779550D02*
X721000D01*
X722792Y778008D01*
Y780092D01*
G01X723500Y782067D02*
X722958Y782150D01*
X722500Y782275D01*
X722083Y782442D01*
X721625Y782650D01*
X721000Y782983D01*
Y781317D01*
G01X708968Y811584D02*
Y799684D01*
G01X731168Y804284D02*
Y808284D01*
X723768D01*
G01Y799484D02*
Y795484D01*
X731168D01*
G01Y799984D02*
Y803984D01*
X723768D01*
G01X723967Y857500D02*
Y860000D01*
X725008D01*
X725342Y859875D01*
X725550Y859708D01*
X725633Y859375D01*
X725550Y859042D01*
X725300Y858833D01*
X725008Y858708D01*
X723967D01*
G01X725008D02*
X725633Y857500D01*
G01X727108Y859583D02*
X727358Y859833D01*
X727650Y859958D01*
X727983Y860000D01*
X728400Y859917D01*
X728692Y859708D01*
X728775Y859458D01*
X728733Y859208D01*
X728567Y859000D01*
X727733Y858583D01*
X727358Y858292D01*
X727108Y857875D01*
X727025Y857500D01*
X728775D01*
G01X731000Y860000D02*
X730667Y859917D01*
X730417Y859708D01*
X730250Y859458D01*
X730125Y859125D01*
X730083Y858750D01*
X730125Y858375D01*
X730250Y858042D01*
X730417Y857792D01*
X730667Y857583D01*
X731000Y857500D01*
X731333Y857583D01*
X731583Y857792D01*
X731750Y858042D01*
X731875Y858375D01*
X731917Y858750D01*
X731875Y859125D01*
X731750Y859458D01*
X731583Y859708D01*
X731333Y859917D01*
X731000Y860000D01*
G01X733183Y857875D02*
X733433Y857667D01*
X733725Y857542D01*
X734100Y857500D01*
X734475Y857583D01*
X734767Y857750D01*
X734975Y858042D01*
X735017Y858375D01*
X734933Y858708D01*
X734725Y858917D01*
X734433Y859083D01*
X734142Y859125D01*
X733850Y859083D01*
X733475Y858917D01*
X733600Y860000D01*
X734725D01*
G01X737700Y857500D02*
Y860000D01*
X736158Y858208D01*
X738242D01*
G01X714317Y860292D02*
X714067Y860417D01*
X713775Y860500D01*
X713442D01*
X713067Y860375D01*
X712775Y860167D01*
X712567Y859917D01*
X712400Y859500D01*
X712358Y859125D01*
X712442Y858750D01*
X712567Y858500D01*
X712817Y858250D01*
X713108Y858083D01*
X713400Y858000D01*
X713692D01*
X713983Y858083D01*
X714233Y858208D01*
X714442Y858375D01*
G01X716500Y858000D02*
X716792Y858042D01*
X717125Y858167D01*
X717333Y858375D01*
X717417Y858667D01*
X717333Y858958D01*
X717083Y859208D01*
X716708Y859333D01*
X716292D01*
X716042Y859417D01*
X715833Y859625D01*
X715750Y859917D01*
X715875Y860208D01*
X716167Y860417D01*
X716500Y860500D01*
X716833Y860417D01*
X717125Y860208D01*
X717250Y859917D01*
X717167Y859625D01*
X716958Y859417D01*
X716708Y859333D01*
X716292D01*
X715917Y859208D01*
X715667Y858958D01*
X715583Y858667D01*
X715667Y858375D01*
X715875Y858167D01*
X716208Y858042D01*
X716500Y858000D01*
G01X719600D02*
Y860500D01*
X719100Y860000D01*
G01Y858000D02*
X720100D01*
G01X717800Y868000D02*
Y878000D01*
G01X731200Y868000D02*
X717800D01*
G01X709000Y880200D02*
Y866800D01*
G01X712000Y869300D02*
X716000D01*
Y876700D01*
G01X729700Y862000D02*
Y866000D01*
X722300D01*
G01X717800Y878000D02*
X731200D01*
G01X722300Y889000D02*
Y885000D01*
X729700D01*
G01X722300Y884500D02*
Y880500D01*
X729700D01*
G01X716000Y882517D02*
X713500D01*
Y883558D01*
X713625Y883892D01*
X713792Y884100D01*
X714125Y884183D01*
X714458Y884100D01*
X714667Y883850D01*
X714792Y883558D01*
Y882517D01*
G01Y883558D02*
X716000Y884183D01*
G01X713917Y885658D02*
X713667Y885908D01*
X713542Y886200D01*
X713500Y886533D01*
X713583Y886950D01*
X713792Y887242D01*
X714042Y887325D01*
X714292Y887283D01*
X714500Y887117D01*
X714917Y886283D01*
X715208Y885908D01*
X715625Y885658D01*
X716000Y885575D01*
Y887325D01*
G01Y889550D02*
X713500D01*
X714000Y889050D01*
G01X716000D02*
Y890050D01*
G01X715708Y891942D02*
X715917Y892233D01*
X716000Y892567D01*
X715917Y892900D01*
X715667Y893192D01*
X715292Y893400D01*
X714917Y893483D01*
X714458D01*
X714083Y893400D01*
X713750Y893192D01*
X713583Y892942D01*
X713500Y892650D01*
X713583Y892317D01*
X713750Y892067D01*
X714000Y891900D01*
X714333Y891817D01*
X714625Y891900D01*
X714917Y892108D01*
X715083Y892358D01*
X715125Y892650D01*
X715042Y892983D01*
X714833Y893233D01*
X714458Y893483D01*
G01X719467Y907000D02*
Y909500D01*
X720508D01*
X720842Y909375D01*
X721050Y909208D01*
X721133Y908875D01*
X721050Y908542D01*
X720800Y908333D01*
X720508Y908208D01*
X719467D01*
G01X720508D02*
X721133Y907000D01*
G01X723400D02*
Y909500D01*
X722900Y909000D01*
G01Y907000D02*
X723900D01*
G01X725583Y907375D02*
X725833Y907167D01*
X726125Y907042D01*
X726500Y907000D01*
X726875Y907083D01*
X727167Y907250D01*
X727375Y907542D01*
X727417Y907875D01*
X727333Y908208D01*
X727125Y908417D01*
X726833Y908583D01*
X726542Y908625D01*
X726250Y908583D01*
X725875Y908417D01*
X726000Y909500D01*
X727125D01*
G01X729600Y907000D02*
X729892Y907042D01*
X730225Y907167D01*
X730433Y907375D01*
X730517Y907667D01*
X730433Y907958D01*
X730183Y908208D01*
X729808Y908333D01*
X729392D01*
X729142Y908417D01*
X728933Y908625D01*
X728850Y908917D01*
X728975Y909208D01*
X729267Y909417D01*
X729600Y909500D01*
X729933Y909417D01*
X730225Y909208D01*
X730350Y908917D01*
X730267Y908625D01*
X730058Y908417D01*
X729808Y908333D01*
X729392D01*
X729017Y908208D01*
X728767Y907958D01*
X728683Y907667D01*
X728767Y907375D01*
X728975Y907167D01*
X729308Y907042D01*
X729600Y907000D01*
G01X731783Y907500D02*
X732033Y907208D01*
X732367Y907042D01*
X732742Y907000D01*
X733075Y907042D01*
X733408Y907250D01*
X733617Y907500D01*
X733658Y907750D01*
X733575Y908042D01*
X733283Y908250D01*
X732992Y908333D01*
X732617D01*
G01X732992D02*
X733242Y908458D01*
X733450Y908667D01*
X733533Y908917D01*
X733450Y909167D01*
X733242Y909375D01*
X732867Y909500D01*
X732492Y909458D01*
X732117Y909292D01*
G01X719467Y902500D02*
Y905000D01*
X720508D01*
X720842Y904875D01*
X721050Y904708D01*
X721133Y904375D01*
X721050Y904042D01*
X720800Y903833D01*
X720508Y903708D01*
X719467D01*
G01X720508D02*
X721133Y902500D01*
G01X723400D02*
Y905000D01*
X722900Y904500D01*
G01Y902500D02*
X723900D01*
G01X725583Y902875D02*
X725833Y902667D01*
X726125Y902542D01*
X726500Y902500D01*
X726875Y902583D01*
X727167Y902750D01*
X727375Y903042D01*
X727417Y903375D01*
X727333Y903708D01*
X727125Y903917D01*
X726833Y904083D01*
X726542Y904125D01*
X726250Y904083D01*
X725875Y903917D01*
X726000Y905000D01*
X727125D01*
G01X729517Y902500D02*
X729600Y903042D01*
X729725Y903500D01*
X729892Y903917D01*
X730100Y904375D01*
X730433Y905000D01*
X728767D01*
G01X732700Y902500D02*
X732992Y902542D01*
X733325Y902667D01*
X733533Y902875D01*
X733617Y903167D01*
X733533Y903458D01*
X733283Y903708D01*
X732908Y903833D01*
X732492D01*
X732242Y903917D01*
X732033Y904125D01*
X731950Y904417D01*
X732075Y904708D01*
X732367Y904917D01*
X732700Y905000D01*
X733033Y904917D01*
X733325Y904708D01*
X733450Y904417D01*
X733367Y904125D01*
X733158Y903917D01*
X732908Y903833D01*
X732492D01*
X732117Y903708D01*
X731867Y903458D01*
X731783Y903167D01*
X731867Y902875D01*
X732075Y902667D01*
X732408Y902542D01*
X732700Y902500D01*
G01X722300Y901000D02*
Y897000D01*
X729700D01*
G01X719467Y911000D02*
Y913500D01*
X720508D01*
X720842Y913375D01*
X721050Y913208D01*
X721133Y912875D01*
X721050Y912542D01*
X720800Y912333D01*
X720508Y912208D01*
X719467D01*
G01X720508D02*
X721133Y911000D01*
G01X723400D02*
Y913500D01*
X722900Y913000D01*
G01Y911000D02*
X723900D01*
G01X725583Y911375D02*
X725833Y911167D01*
X726125Y911042D01*
X726500Y911000D01*
X726875Y911083D01*
X727167Y911250D01*
X727375Y911542D01*
X727417Y911875D01*
X727333Y912208D01*
X727125Y912417D01*
X726833Y912583D01*
X726542Y912625D01*
X726250Y912583D01*
X725875Y912417D01*
X726000Y913500D01*
X727125D01*
G01X729600Y911000D02*
X729892Y911042D01*
X730225Y911167D01*
X730433Y911375D01*
X730517Y911667D01*
X730433Y911958D01*
X730183Y912208D01*
X729808Y912333D01*
X729392D01*
X729142Y912417D01*
X728933Y912625D01*
X728850Y912917D01*
X728975Y913208D01*
X729267Y913417D01*
X729600Y913500D01*
X729933Y913417D01*
X730225Y913208D01*
X730350Y912917D01*
X730267Y912625D01*
X730058Y912417D01*
X729808Y912333D01*
X729392D01*
X729017Y912208D01*
X728767Y911958D01*
X728683Y911667D01*
X728767Y911375D01*
X728975Y911167D01*
X729308Y911042D01*
X729600Y911000D01*
G01X732700D02*
Y913500D01*
X732200Y913000D01*
G01Y911000D02*
X733200D01*
G01X719467Y915500D02*
Y918000D01*
X720508D01*
X720842Y917875D01*
X721050Y917708D01*
X721133Y917375D01*
X721050Y917042D01*
X720800Y916833D01*
X720508Y916708D01*
X719467D01*
G01X720508D02*
X721133Y915500D01*
G01X723400D02*
Y918000D01*
X722900Y917500D01*
G01Y915500D02*
X723900D01*
G01X725583Y915875D02*
X725833Y915667D01*
X726125Y915542D01*
X726500Y915500D01*
X726875Y915583D01*
X727167Y915750D01*
X727375Y916042D01*
X727417Y916375D01*
X727333Y916708D01*
X727125Y916917D01*
X726833Y917083D01*
X726542Y917125D01*
X726250Y917083D01*
X725875Y916917D01*
X726000Y918000D01*
X727125D01*
G01X729600Y915500D02*
X729892Y915542D01*
X730225Y915667D01*
X730433Y915875D01*
X730517Y916167D01*
X730433Y916458D01*
X730183Y916708D01*
X729808Y916833D01*
X729392D01*
X729142Y916917D01*
X728933Y917125D01*
X728850Y917417D01*
X728975Y917708D01*
X729267Y917917D01*
X729600Y918000D01*
X729933Y917917D01*
X730225Y917708D01*
X730350Y917417D01*
X730267Y917125D01*
X730058Y916917D01*
X729808Y916833D01*
X729392D01*
X729017Y916708D01*
X728767Y916458D01*
X728683Y916167D01*
X728767Y915875D01*
X728975Y915667D01*
X729308Y915542D01*
X729600Y915500D01*
G01X732700Y918000D02*
X732367Y917917D01*
X732117Y917708D01*
X731950Y917458D01*
X731825Y917125D01*
X731783Y916750D01*
X731825Y916375D01*
X731950Y916042D01*
X732117Y915792D01*
X732367Y915583D01*
X732700Y915500D01*
X733033Y915583D01*
X733283Y915792D01*
X733450Y916042D01*
X733575Y916375D01*
X733617Y916750D01*
X733575Y917125D01*
X733450Y917458D01*
X733283Y917708D01*
X733033Y917917D01*
X732700Y918000D01*
G01X738483Y47500D02*
Y45708D01*
X738650Y45333D01*
X738983Y45083D01*
X739400Y45000D01*
X739817Y45083D01*
X740150Y45333D01*
X740317Y45708D01*
Y47500D01*
G01X742500Y45000D02*
Y47500D01*
X742000Y47000D01*
G01Y45000D02*
X743000D01*
G01X744683Y45375D02*
X744933Y45167D01*
X745225Y45042D01*
X745600Y45000D01*
X745975Y45083D01*
X746267Y45250D01*
X746475Y45542D01*
X746517Y45875D01*
X746433Y46208D01*
X746225Y46417D01*
X745933Y46583D01*
X745642Y46625D01*
X745350Y46583D01*
X744975Y46417D01*
X745100Y47500D01*
X746225D01*
G01X740300Y52600D02*
Y67400D01*
G01X744700Y52600D02*
X740300D01*
G01Y67400D02*
X744700D01*
G01X734000Y73300D02*
X736500D01*
G01X734000Y72342D02*
Y74258D01*
G01X736500Y75567D02*
X734000D01*
Y76567D01*
X734125Y76900D01*
X734417Y77150D01*
X734750Y77233D01*
X735083Y77150D01*
X735333Y76942D01*
X735458Y76567D01*
Y75567D01*
G01X736500Y79500D02*
X734000D01*
X734500Y79000D01*
G01X736500D02*
Y80000D01*
G01X736000Y81683D02*
X736292Y81933D01*
X736458Y82267D01*
X736500Y82642D01*
X736458Y82975D01*
X736250Y83308D01*
X736000Y83517D01*
X735750Y83558D01*
X735458Y83475D01*
X735250Y83183D01*
X735167Y82892D01*
Y82517D01*
G01Y82892D02*
X735042Y83142D01*
X734833Y83350D01*
X734583Y83433D01*
X734333Y83350D01*
X734125Y83142D01*
X734000Y82767D01*
X734042Y82392D01*
X734208Y82017D01*
G01X734000Y85700D02*
X734083Y85367D01*
X734292Y85117D01*
X734542Y84950D01*
X734875Y84825D01*
X735250Y84783D01*
X735625Y84825D01*
X735958Y84950D01*
X736208Y85117D01*
X736417Y85367D01*
X736500Y85700D01*
X736417Y86033D01*
X736208Y86283D01*
X735958Y86450D01*
X735625Y86575D01*
X735250Y86617D01*
X734875Y86575D01*
X734542Y86450D01*
X734292Y86283D01*
X734083Y86033D01*
X734000Y85700D01*
G01X738517Y72500D02*
Y75000D01*
X739558D01*
X739892Y74875D01*
X740100Y74708D01*
X740183Y74375D01*
X740100Y74042D01*
X739850Y73833D01*
X739558Y73708D01*
X738517D01*
G01X739558D02*
X740183Y72500D01*
G01X742950D02*
Y75000D01*
X741408Y73208D01*
X743492D01*
G01X744633Y72875D02*
X744883Y72667D01*
X745175Y72542D01*
X745550Y72500D01*
X745925Y72583D01*
X746217Y72750D01*
X746425Y73042D01*
X746467Y73375D01*
X746383Y73708D01*
X746175Y73917D01*
X745883Y74083D01*
X745592Y74125D01*
X745300Y74083D01*
X744925Y73917D01*
X745050Y75000D01*
X746175D01*
G01X747942Y72792D02*
X748233Y72583D01*
X748567Y72500D01*
X748900Y72583D01*
X749192Y72833D01*
X749400Y73208D01*
X749483Y73583D01*
Y74042D01*
X749400Y74417D01*
X749192Y74750D01*
X748942Y74917D01*
X748650Y75000D01*
X748317Y74917D01*
X748067Y74750D01*
X747900Y74500D01*
X747817Y74167D01*
X747900Y73875D01*
X748108Y73583D01*
X748358Y73417D01*
X748650Y73375D01*
X748983Y73458D01*
X749233Y73667D01*
X749483Y74042D01*
G01X731000Y85017D02*
X728500D01*
Y86058D01*
X728625Y86392D01*
X728792Y86600D01*
X729125Y86683D01*
X729458Y86600D01*
X729667Y86350D01*
X729792Y86058D01*
Y85017D01*
G01Y86058D02*
X731000Y86683D01*
G01Y89450D02*
X728500D01*
X730292Y87908D01*
Y89992D01*
G01X730625Y91133D02*
X730833Y91383D01*
X730958Y91675D01*
X731000Y92050D01*
X730917Y92425D01*
X730750Y92717D01*
X730458Y92925D01*
X730125Y92967D01*
X729792Y92883D01*
X729583Y92675D01*
X729417Y92383D01*
X729375Y92092D01*
X729417Y91800D01*
X729583Y91425D01*
X728500Y91550D01*
Y92675D01*
G01X730625Y94233D02*
X730833Y94483D01*
X730958Y94775D01*
X731000Y95150D01*
X730917Y95525D01*
X730750Y95817D01*
X730458Y96025D01*
X730125Y96067D01*
X729792Y95983D01*
X729583Y95775D01*
X729417Y95483D01*
X729375Y95192D01*
X729417Y94900D01*
X729583Y94525D01*
X728500Y94650D01*
Y95775D01*
G01X738500Y77300D02*
X742500D01*
Y84700D01*
G01X734516Y103484D02*
X739516D01*
Y108484D01*
G01X730572Y104384D02*
Y102384D01*
G01X738616Y116364D02*
X741616D01*
G01X738616Y126204D02*
X740616D01*
G01X724668Y138184D02*
Y140184D01*
G01X738748Y146800D02*
X742748D01*
Y154200D01*
G01X725216Y146584D02*
X729216D01*
Y153984D01*
G01X738248Y154200D02*
X734248D01*
Y146800D01*
G01X733716Y153984D02*
X729716D01*
Y146584D01*
G01X739748Y156017D02*
X737248D01*
Y157058D01*
X737373Y157392D01*
X737540Y157600D01*
X737873Y157683D01*
X738206Y157600D01*
X738415Y157350D01*
X738540Y157058D01*
Y156017D01*
G01Y157058D02*
X739748Y157683D01*
G01X739248Y159033D02*
X739540Y159283D01*
X739706Y159617D01*
X739748Y159992D01*
X739706Y160325D01*
X739498Y160658D01*
X739248Y160867D01*
X738998Y160908D01*
X738706Y160825D01*
X738498Y160533D01*
X738415Y160242D01*
Y159867D01*
G01Y160242D02*
X738290Y160492D01*
X738081Y160700D01*
X737831Y160783D01*
X737581Y160700D01*
X737373Y160492D01*
X737248Y160117D01*
X737290Y159742D01*
X737456Y159367D01*
G01X739748Y162967D02*
X739206Y163050D01*
X738748Y163175D01*
X738331Y163342D01*
X737873Y163550D01*
X737248Y163883D01*
Y162217D01*
G01X739456Y165442D02*
X739665Y165733D01*
X739748Y166067D01*
X739665Y166400D01*
X739415Y166692D01*
X739040Y166900D01*
X738665Y166983D01*
X738206D01*
X737831Y166900D01*
X737498Y166692D01*
X737331Y166442D01*
X737248Y166150D01*
X737331Y165817D01*
X737498Y165567D01*
X737748Y165400D01*
X738081Y165317D01*
X738373Y165400D01*
X738665Y165608D01*
X738831Y165858D01*
X738873Y166150D01*
X738790Y166483D01*
X738581Y166733D01*
X738206Y166983D01*
G01X726716Y155801D02*
X724216D01*
Y156842D01*
X724341Y157176D01*
X724508Y157384D01*
X724841Y157467D01*
X725174Y157384D01*
X725383Y157134D01*
X725508Y156842D01*
Y155801D01*
G01Y156842D02*
X726716Y157467D01*
G01X726216Y158817D02*
X726508Y159067D01*
X726674Y159401D01*
X726716Y159776D01*
X726674Y160109D01*
X726466Y160442D01*
X726216Y160651D01*
X725966Y160692D01*
X725674Y160609D01*
X725466Y160317D01*
X725383Y160026D01*
Y159651D01*
G01Y160026D02*
X725258Y160276D01*
X725049Y160484D01*
X724799Y160567D01*
X724549Y160484D01*
X724341Y160276D01*
X724216Y159901D01*
X724258Y159526D01*
X724424Y159151D01*
G01X726716Y162751D02*
X726174Y162834D01*
X725716Y162959D01*
X725299Y163126D01*
X724841Y163334D01*
X724216Y163667D01*
Y162001D01*
G01X726716Y166434D02*
X724216D01*
X726008Y164892D01*
Y166976D01*
G01X735248Y156017D02*
X732748D01*
Y157058D01*
X732873Y157392D01*
X733040Y157600D01*
X733373Y157683D01*
X733706Y157600D01*
X733915Y157350D01*
X734040Y157058D01*
Y156017D01*
G01Y157058D02*
X735248Y157683D01*
G01X734748Y159033D02*
X735040Y159283D01*
X735206Y159617D01*
X735248Y159992D01*
X735206Y160325D01*
X734998Y160658D01*
X734748Y160867D01*
X734498Y160908D01*
X734206Y160825D01*
X733998Y160533D01*
X733915Y160242D01*
Y159867D01*
G01Y160242D02*
X733790Y160492D01*
X733581Y160700D01*
X733331Y160783D01*
X733081Y160700D01*
X732873Y160492D01*
X732748Y160117D01*
X732790Y159742D01*
X732956Y159367D01*
G01X735248Y162967D02*
X734706Y163050D01*
X734248Y163175D01*
X733831Y163342D01*
X733373Y163550D01*
X732748Y163883D01*
Y162217D01*
G01X733165Y165358D02*
X732915Y165608D01*
X732790Y165900D01*
X732748Y166233D01*
X732831Y166650D01*
X733040Y166942D01*
X733290Y167025D01*
X733540Y166983D01*
X733748Y166817D01*
X734165Y165983D01*
X734456Y165608D01*
X734873Y165358D01*
X735248Y165275D01*
Y167025D01*
G01X731216Y155801D02*
X728716D01*
Y156842D01*
X728841Y157176D01*
X729008Y157384D01*
X729341Y157467D01*
X729674Y157384D01*
X729883Y157134D01*
X730008Y156842D01*
Y155801D01*
G01Y156842D02*
X731216Y157467D01*
G01X730716Y158817D02*
X731008Y159067D01*
X731174Y159401D01*
X731216Y159776D01*
X731174Y160109D01*
X730966Y160442D01*
X730716Y160651D01*
X730466Y160692D01*
X730174Y160609D01*
X729966Y160317D01*
X729883Y160026D01*
Y159651D01*
G01Y160026D02*
X729758Y160276D01*
X729549Y160484D01*
X729299Y160567D01*
X729049Y160484D01*
X728841Y160276D01*
X728716Y159901D01*
X728758Y159526D01*
X728924Y159151D01*
G01X731216Y162751D02*
X730674Y162834D01*
X730216Y162959D01*
X729799Y163126D01*
X729341Y163334D01*
X728716Y163667D01*
Y162001D01*
G01X731216Y165934D02*
X728716D01*
X729216Y165434D01*
G01X731216D02*
Y166434D01*
G01X736948Y187500D02*
Y191500D01*
X729548D01*
G01X727500Y199565D02*
X727760D01*
X729195Y201000D01*
X727760Y202435D01*
G01X727500Y199565D02*
Y202435D01*
X738500D01*
G01Y199565D02*
X727500D01*
G01X738500D02*
Y202435D01*
G01X734000Y208983D02*
X735792D01*
X736167Y209150D01*
X736417Y209483D01*
X736500Y209900D01*
X736417Y210317D01*
X736167Y210650D01*
X735792Y210817D01*
X734000D01*
G01X736500Y213500D02*
X734000D01*
X735792Y211958D01*
Y214042D01*
G01X736125Y215183D02*
X736333Y215433D01*
X736458Y215725D01*
X736500Y216100D01*
X736417Y216475D01*
X736250Y216767D01*
X735958Y216975D01*
X735625Y217017D01*
X735292Y216933D01*
X735083Y216725D01*
X734917Y216433D01*
X734875Y216142D01*
X734917Y215850D01*
X735083Y215475D01*
X734000Y215600D01*
Y216725D01*
G01X732500Y474522D02*
Y461122D01*
G01X739000Y476967D02*
X736500D01*
Y477967D01*
X736625Y478300D01*
X736917Y478550D01*
X737250Y478633D01*
X737583Y478550D01*
X737833Y478342D01*
X737958Y477967D01*
Y476967D01*
G01X739000Y480067D02*
X736500D01*
Y481108D01*
X736625Y481442D01*
X736792Y481650D01*
X737125Y481733D01*
X737458Y481650D01*
X737667Y481400D01*
X737792Y481108D01*
Y480067D01*
G01Y481108D02*
X739000Y481733D01*
G01Y484000D02*
X736500D01*
X737000Y483500D01*
G01X739000D02*
Y484500D01*
G01Y487017D02*
X738458Y487100D01*
X738000Y487225D01*
X737583Y487392D01*
X737125Y487600D01*
X736500Y487933D01*
Y486267D01*
G01Y490200D02*
X736583Y489867D01*
X736792Y489617D01*
X737042Y489450D01*
X737375Y489325D01*
X737750Y489283D01*
X738125Y489325D01*
X738458Y489450D01*
X738708Y489617D01*
X738917Y489867D01*
X739000Y490200D01*
X738917Y490533D01*
X738708Y490783D01*
X738458Y490950D01*
X738125Y491075D01*
X737750Y491117D01*
X737375Y491075D01*
X737042Y490950D01*
X736792Y490783D01*
X736583Y490533D01*
X736500Y490200D01*
G01X730500Y476800D02*
X734500D01*
Y484200D01*
G01X727208Y484767D02*
X727083Y484517D01*
X727000Y484225D01*
Y483892D01*
X727125Y483517D01*
X727333Y483225D01*
X727583Y483017D01*
X728000Y482850D01*
X728375Y482808D01*
X728750Y482892D01*
X729000Y483017D01*
X729250Y483267D01*
X729417Y483558D01*
X729500Y483850D01*
Y484142D01*
X729417Y484433D01*
X729292Y484683D01*
X729125Y484892D01*
G01X729000Y486033D02*
X729292Y486283D01*
X729458Y486617D01*
X729500Y486992D01*
X729458Y487325D01*
X729250Y487658D01*
X729000Y487867D01*
X728750Y487908D01*
X728458Y487825D01*
X728250Y487533D01*
X728167Y487242D01*
Y486867D01*
G01Y487242D02*
X728042Y487492D01*
X727833Y487700D01*
X727583Y487783D01*
X727333Y487700D01*
X727125Y487492D01*
X727000Y487117D01*
X727042Y486742D01*
X727208Y486367D01*
G01X727417Y489258D02*
X727167Y489508D01*
X727042Y489800D01*
X727000Y490133D01*
X727083Y490550D01*
X727292Y490842D01*
X727542Y490925D01*
X727792Y490883D01*
X728000Y490717D01*
X728417Y489883D01*
X728708Y489508D01*
X729125Y489258D01*
X729500Y489175D01*
Y490925D01*
G01X729208Y492442D02*
X729417Y492733D01*
X729500Y493067D01*
X729417Y493400D01*
X729167Y493692D01*
X728792Y493900D01*
X728417Y493983D01*
X727958D01*
X727583Y493900D01*
X727250Y493692D01*
X727083Y493442D01*
X727000Y493150D01*
X727083Y492817D01*
X727250Y492567D01*
X727500Y492400D01*
X727833Y492317D01*
X728125Y492400D01*
X728417Y492608D01*
X728583Y492858D01*
X728625Y493150D01*
X728542Y493483D01*
X728333Y493733D01*
X727958Y493983D01*
G01X734167Y533375D02*
X734375Y533708D01*
X734500Y534083D01*
Y534417D01*
X734375Y534750D01*
X734167Y535000D01*
X733875Y535125D01*
X733583Y535042D01*
X733333Y534833D01*
X733167Y534458D01*
X733083Y533958D01*
X732917Y533667D01*
X732625Y533542D01*
X732333Y533625D01*
X732125Y533833D01*
X732000Y534125D01*
Y534417D01*
X732083Y534708D01*
X732292Y534958D01*
G01X732208Y538267D02*
X732083Y538017D01*
X732000Y537725D01*
Y537392D01*
X732125Y537017D01*
X732333Y536725D01*
X732583Y536517D01*
X733000Y536350D01*
X733375Y536308D01*
X733750Y536392D01*
X734000Y536517D01*
X734250Y536767D01*
X734417Y537058D01*
X734500Y537350D01*
Y537642D01*
X734417Y537933D01*
X734292Y538183D01*
X734125Y538392D01*
G01X734500Y540450D02*
X732000D01*
X732500Y539950D01*
G01X734500D02*
Y540950D01*
G01Y543550D02*
X732000D01*
X732500Y543050D01*
G01X734500D02*
Y544050D01*
G01X732000Y546650D02*
X732083Y546317D01*
X732292Y546067D01*
X732542Y545900D01*
X732875Y545775D01*
X733250Y545733D01*
X733625Y545775D01*
X733958Y545900D01*
X734208Y546067D01*
X734417Y546317D01*
X734500Y546650D01*
X734417Y546983D01*
X734208Y547233D01*
X733958Y547400D01*
X733625Y547525D01*
X733250Y547567D01*
X732875Y547525D01*
X732542Y547400D01*
X732292Y547233D01*
X732083Y546983D01*
X732000Y546650D01*
G01X734208Y549042D02*
X734417Y549333D01*
X734500Y549667D01*
X734417Y550000D01*
X734167Y550292D01*
X733792Y550500D01*
X733417Y550583D01*
X732958D01*
X732583Y550500D01*
X732250Y550292D01*
X732083Y550042D01*
X732000Y549750D01*
X732083Y549417D01*
X732250Y549167D01*
X732500Y549000D01*
X732833Y548917D01*
X733125Y549000D01*
X733417Y549208D01*
X733583Y549458D01*
X733625Y549750D01*
X733542Y550083D01*
X733333Y550333D01*
X732958Y550583D01*
G01X729167Y533375D02*
X729375Y533708D01*
X729500Y534083D01*
Y534417D01*
X729375Y534750D01*
X729167Y535000D01*
X728875Y535125D01*
X728583Y535042D01*
X728333Y534833D01*
X728167Y534458D01*
X728083Y533958D01*
X727917Y533667D01*
X727625Y533542D01*
X727333Y533625D01*
X727125Y533833D01*
X727000Y534125D01*
Y534417D01*
X727083Y534708D01*
X727292Y534958D01*
G01X727208Y538267D02*
X727083Y538017D01*
X727000Y537725D01*
Y537392D01*
X727125Y537017D01*
X727333Y536725D01*
X727583Y536517D01*
X728000Y536350D01*
X728375Y536308D01*
X728750Y536392D01*
X729000Y536517D01*
X729250Y536767D01*
X729417Y537058D01*
X729500Y537350D01*
Y537642D01*
X729417Y537933D01*
X729292Y538183D01*
X729125Y538392D01*
G01X729500Y540450D02*
X727000D01*
X727500Y539950D01*
G01X729500D02*
Y540950D01*
G01Y543550D02*
X727000D01*
X727500Y543050D01*
G01X729500D02*
Y544050D01*
G01X727000Y546650D02*
X727083Y546317D01*
X727292Y546067D01*
X727542Y545900D01*
X727875Y545775D01*
X728250Y545733D01*
X728625Y545775D01*
X728958Y545900D01*
X729208Y546067D01*
X729417Y546317D01*
X729500Y546650D01*
X729417Y546983D01*
X729208Y547233D01*
X728958Y547400D01*
X728625Y547525D01*
X728250Y547567D01*
X727875Y547525D01*
X727542Y547400D01*
X727292Y547233D01*
X727083Y546983D01*
X727000Y546650D01*
G01X729500Y549750D02*
X729458Y550042D01*
X729333Y550375D01*
X729125Y550583D01*
X728833Y550667D01*
X728542Y550583D01*
X728292Y550333D01*
X728167Y549958D01*
Y549542D01*
X728083Y549292D01*
X727875Y549083D01*
X727583Y549000D01*
X727292Y549125D01*
X727083Y549417D01*
X727000Y549750D01*
X727083Y550083D01*
X727292Y550375D01*
X727583Y550500D01*
X727875Y550417D01*
X728083Y550208D01*
X728167Y549958D01*
Y549542D01*
X728292Y549167D01*
X728542Y548917D01*
X728833Y548833D01*
X729125Y548917D01*
X729333Y549125D01*
X729458Y549458D01*
X729500Y549750D01*
G01X741664Y556538D02*
Y560538D01*
X734264D01*
G01X741664Y561538D02*
Y565538D01*
X734264D01*
G01X743200Y551500D02*
Y555500D01*
X735800D01*
G01X732300Y581200D02*
Y571000D01*
G01X727700Y581200D02*
X732300D01*
G01X727700Y570300D02*
Y581200D01*
G01Y570300D02*
X739000D01*
G01X730000Y571500D02*
X728800Y570300D01*
G01X730000Y571500D02*
X731200Y570300D01*
G01X738667Y585375D02*
X738875Y585708D01*
X739000Y586083D01*
Y586417D01*
X738875Y586750D01*
X738667Y587000D01*
X738375Y587125D01*
X738083Y587042D01*
X737833Y586833D01*
X737667Y586458D01*
X737583Y585958D01*
X737417Y585667D01*
X737125Y585542D01*
X736833Y585625D01*
X736625Y585833D01*
X736500Y586125D01*
Y586417D01*
X736583Y586708D01*
X736792Y586958D01*
G01X736708Y590267D02*
X736583Y590017D01*
X736500Y589725D01*
Y589392D01*
X736625Y589017D01*
X736833Y588725D01*
X737083Y588517D01*
X737500Y588350D01*
X737875Y588308D01*
X738250Y588392D01*
X738500Y588517D01*
X738750Y588767D01*
X738917Y589058D01*
X739000Y589350D01*
Y589642D01*
X738917Y589933D01*
X738792Y590183D01*
X738625Y590392D01*
G01X739000Y592450D02*
X736500D01*
X737000Y591950D01*
G01X739000D02*
Y592950D01*
G01X736917Y594758D02*
X736667Y595008D01*
X736542Y595300D01*
X736500Y595633D01*
X736583Y596050D01*
X736792Y596342D01*
X737042Y596425D01*
X737292Y596383D01*
X737500Y596217D01*
X737917Y595383D01*
X738208Y595008D01*
X738625Y594758D01*
X739000Y594675D01*
Y596425D01*
G01X738708Y597942D02*
X738917Y598233D01*
X739000Y598567D01*
X738917Y598900D01*
X738667Y599192D01*
X738292Y599400D01*
X737917Y599483D01*
X737458D01*
X737083Y599400D01*
X736750Y599192D01*
X736583Y598942D01*
X736500Y598650D01*
X736583Y598317D01*
X736750Y598067D01*
X737000Y597900D01*
X737333Y597817D01*
X737625Y597900D01*
X737917Y598108D01*
X738083Y598358D01*
X738125Y598650D01*
X738042Y598983D01*
X737833Y599233D01*
X737458Y599483D01*
G01X739000Y602250D02*
X736500D01*
X738292Y600708D01*
Y602792D01*
G01X738168Y761984D02*
Y765984D01*
X730768D01*
G01X745668Y766784D02*
Y770784D01*
X738268D01*
G01X732517Y772000D02*
Y774500D01*
X733558D01*
X733892Y774375D01*
X734100Y774208D01*
X734183Y773875D01*
X734100Y773542D01*
X733850Y773333D01*
X733558Y773208D01*
X732517D01*
G01X733558D02*
X734183Y772000D01*
G01X736950D02*
Y774500D01*
X735408Y772708D01*
X737492D01*
G01X738633Y772500D02*
X738883Y772208D01*
X739217Y772042D01*
X739592Y772000D01*
X739925Y772042D01*
X740258Y772250D01*
X740467Y772500D01*
X740508Y772750D01*
X740425Y773042D01*
X740133Y773250D01*
X739842Y773333D01*
X739467D01*
G01X739842D02*
X740092Y773458D01*
X740300Y773667D01*
X740383Y773917D01*
X740300Y774167D01*
X740092Y774375D01*
X739717Y774500D01*
X739342Y774458D01*
X738967Y774292D01*
G01X741858Y774083D02*
X742108Y774333D01*
X742400Y774458D01*
X742733Y774500D01*
X743150Y774417D01*
X743442Y774208D01*
X743525Y773958D01*
X743483Y773708D01*
X743317Y773500D01*
X742483Y773083D01*
X742108Y772792D01*
X741858Y772375D01*
X741775Y772000D01*
X743525D01*
G01X738168Y766784D02*
Y770784D01*
X730768D01*
G01X740208Y780267D02*
X740083Y780017D01*
X740000Y779725D01*
Y779392D01*
X740125Y779017D01*
X740333Y778725D01*
X740583Y778517D01*
X741000Y778350D01*
X741375Y778308D01*
X741750Y778392D01*
X742000Y778517D01*
X742250Y778767D01*
X742417Y779058D01*
X742500Y779350D01*
Y779642D01*
X742417Y779933D01*
X742292Y780183D01*
X742125Y780392D01*
G01X740417Y781658D02*
X740167Y781908D01*
X740042Y782200D01*
X740000Y782533D01*
X740083Y782950D01*
X740292Y783242D01*
X740542Y783325D01*
X740792Y783283D01*
X741000Y783117D01*
X741417Y782283D01*
X741708Y781908D01*
X742125Y781658D01*
X742500Y781575D01*
Y783325D01*
G01Y786050D02*
X740000D01*
X741792Y784508D01*
Y786592D01*
G01X742500Y789150D02*
X740000D01*
X741792Y787608D01*
Y789692D01*
G01X735176Y780251D02*
X735051Y780001D01*
X734968Y779709D01*
Y779376D01*
X735093Y779001D01*
X735301Y778709D01*
X735551Y778501D01*
X735968Y778334D01*
X736343Y778292D01*
X736718Y778376D01*
X736968Y778501D01*
X737218Y778751D01*
X737385Y779042D01*
X737468Y779334D01*
Y779626D01*
X737385Y779917D01*
X737260Y780167D01*
X737093Y780376D01*
G01X735385Y781642D02*
X735135Y781892D01*
X735010Y782184D01*
X734968Y782517D01*
X735051Y782934D01*
X735260Y783226D01*
X735510Y783309D01*
X735760Y783267D01*
X735968Y783101D01*
X736385Y782267D01*
X736676Y781892D01*
X737093Y781642D01*
X737468Y781559D01*
Y783309D01*
G01Y786034D02*
X734968D01*
X736760Y784492D01*
Y786576D01*
G01X736968Y787717D02*
X737260Y787967D01*
X737426Y788301D01*
X737468Y788676D01*
X737426Y789009D01*
X737218Y789342D01*
X736968Y789551D01*
X736718Y789592D01*
X736426Y789509D01*
X736218Y789217D01*
X736135Y788926D01*
Y788551D01*
G01Y788926D02*
X736010Y789176D01*
X735801Y789384D01*
X735551Y789467D01*
X735301Y789384D01*
X735093Y789176D01*
X734968Y788801D01*
X735010Y788426D01*
X735176Y788051D01*
G01X732985Y795984D02*
Y798484D01*
X734026D01*
X734360Y798359D01*
X734568Y798192D01*
X734651Y797859D01*
X734568Y797526D01*
X734318Y797317D01*
X734026Y797192D01*
X732985D01*
G01X734026D02*
X734651Y795984D01*
G01X737418D02*
Y798484D01*
X735876Y796692D01*
X737960D01*
G01X739226Y798067D02*
X739476Y798317D01*
X739768Y798442D01*
X740101Y798484D01*
X740518Y798401D01*
X740810Y798192D01*
X740893Y797942D01*
X740851Y797692D01*
X740685Y797484D01*
X739851Y797067D01*
X739476Y796776D01*
X739226Y796359D01*
X739143Y795984D01*
X740893D01*
G01X742326Y797026D02*
X742618Y797317D01*
X742868Y797484D01*
X743201Y797567D01*
X743493Y797484D01*
X743701Y797317D01*
X743868Y797067D01*
X743910Y796776D01*
X743868Y796526D01*
X743701Y796276D01*
X743451Y796067D01*
X743160Y795984D01*
X742826Y796067D01*
X742535Y796317D01*
X742368Y796692D01*
X742326Y797109D01*
X742410Y797651D01*
X742535Y797942D01*
X742743Y798234D01*
X743035Y798442D01*
X743326Y798484D01*
X743618Y798401D01*
X743826Y798192D01*
G01X732985Y804784D02*
Y807284D01*
X734026D01*
X734360Y807159D01*
X734568Y806992D01*
X734651Y806659D01*
X734568Y806326D01*
X734318Y806117D01*
X734026Y805992D01*
X732985D01*
G01X734026D02*
X734651Y804784D01*
G01X736918D02*
Y807284D01*
X736418Y806784D01*
G01Y804784D02*
X737418D01*
G01X739101Y805159D02*
X739351Y804951D01*
X739643Y804826D01*
X740018Y804784D01*
X740393Y804867D01*
X740685Y805034D01*
X740893Y805326D01*
X740935Y805659D01*
X740851Y805992D01*
X740643Y806201D01*
X740351Y806367D01*
X740060Y806409D01*
X739768Y806367D01*
X739393Y806201D01*
X739518Y807284D01*
X740643D01*
G01X742326Y806867D02*
X742576Y807117D01*
X742868Y807242D01*
X743201Y807284D01*
X743618Y807201D01*
X743910Y806992D01*
X743993Y806742D01*
X743951Y806492D01*
X743785Y806284D01*
X742951Y805867D01*
X742576Y805576D01*
X742326Y805159D01*
X742243Y804784D01*
X743993D01*
G01X732985Y800484D02*
Y802984D01*
X734026D01*
X734360Y802859D01*
X734568Y802692D01*
X734651Y802359D01*
X734568Y802026D01*
X734318Y801817D01*
X734026Y801692D01*
X732985D01*
G01X734026D02*
X734651Y800484D01*
G01X737418D02*
Y802984D01*
X735876Y801192D01*
X737960D01*
G01X739226Y802567D02*
X739476Y802817D01*
X739768Y802942D01*
X740101Y802984D01*
X740518Y802901D01*
X740810Y802692D01*
X740893Y802442D01*
X740851Y802192D01*
X740685Y801984D01*
X739851Y801567D01*
X739476Y801276D01*
X739226Y800859D01*
X739143Y800484D01*
X740893D01*
G01X742201Y800859D02*
X742451Y800651D01*
X742743Y800526D01*
X743118Y800484D01*
X743493Y800567D01*
X743785Y800734D01*
X743993Y801026D01*
X744035Y801359D01*
X743951Y801692D01*
X743743Y801901D01*
X743451Y802067D01*
X743160Y802109D01*
X742868Y802067D01*
X742493Y801901D01*
X742618Y802984D01*
X743743D01*
G01X729708Y820267D02*
X729583Y820017D01*
X729500Y819725D01*
Y819392D01*
X729625Y819017D01*
X729833Y818725D01*
X730083Y818517D01*
X730500Y818350D01*
X730875Y818308D01*
X731250Y818392D01*
X731500Y818517D01*
X731750Y818767D01*
X731917Y819058D01*
X732000Y819350D01*
Y819642D01*
X731917Y819933D01*
X731792Y820183D01*
X731625Y820392D01*
G01X729917Y821658D02*
X729667Y821908D01*
X729542Y822200D01*
X729500Y822533D01*
X729583Y822950D01*
X729792Y823242D01*
X730042Y823325D01*
X730292Y823283D01*
X730500Y823117D01*
X730917Y822283D01*
X731208Y821908D01*
X731625Y821658D01*
X732000Y821575D01*
Y823325D01*
G01Y826050D02*
X729500D01*
X731292Y824508D01*
Y826592D01*
G01X729917Y827858D02*
X729667Y828108D01*
X729542Y828400D01*
X729500Y828733D01*
X729583Y829150D01*
X729792Y829442D01*
X730042Y829525D01*
X730292Y829483D01*
X730500Y829317D01*
X730917Y828483D01*
X731208Y828108D01*
X731625Y827858D01*
X732000Y827775D01*
Y829525D01*
G01X724676Y820251D02*
X724551Y820001D01*
X724468Y819709D01*
Y819376D01*
X724593Y819001D01*
X724801Y818709D01*
X725051Y818501D01*
X725468Y818334D01*
X725843Y818292D01*
X726218Y818376D01*
X726468Y818501D01*
X726718Y818751D01*
X726885Y819042D01*
X726968Y819334D01*
Y819626D01*
X726885Y819917D01*
X726760Y820167D01*
X726593Y820376D01*
G01X724885Y821642D02*
X724635Y821892D01*
X724510Y822184D01*
X724468Y822517D01*
X724551Y822934D01*
X724760Y823226D01*
X725010Y823309D01*
X725260Y823267D01*
X725468Y823101D01*
X725885Y822267D01*
X726176Y821892D01*
X726593Y821642D01*
X726968Y821559D01*
Y823309D01*
G01Y826034D02*
X724468D01*
X726260Y824492D01*
Y826576D01*
G01X726968Y828634D02*
X724468D01*
X724968Y828134D01*
G01X726968D02*
Y829134D01*
G01X734000Y865933D02*
X735792D01*
X736167Y866100D01*
X736417Y866433D01*
X736500Y866850D01*
X736417Y867267D01*
X736167Y867600D01*
X735792Y867767D01*
X734000D01*
G01X736500Y869950D02*
X734000D01*
X734500Y869450D01*
G01X736500D02*
Y870450D01*
G01Y872967D02*
X735958Y873050D01*
X735500Y873175D01*
X735083Y873342D01*
X734625Y873550D01*
X734000Y873883D01*
Y872217D01*
G01X736500Y876150D02*
X734000D01*
X734500Y875650D01*
G01X736500D02*
Y876650D01*
G01X731200Y878000D02*
Y868000D01*
G01X728000Y896700D02*
X724000D01*
Y889300D01*
G01X744700Y67400D02*
Y52600D01*
G01X764200Y49500D02*
Y53500D01*
X756800D01*
G01X742500Y66400D02*
X741500Y67400D01*
G01X743500D02*
X742500Y66400D01*
G01X764200Y57500D02*
Y61500D01*
X756800D01*
G01X764200Y53500D02*
Y57500D01*
X756800D01*
G01X764200Y61500D02*
Y65500D01*
X756800D01*
G01X743800Y84500D02*
Y80500D01*
X751200D01*
G01X743800Y90500D02*
Y86500D01*
X751200D01*
G01X759200Y80500D02*
Y84500D01*
X751800D01*
G01X743800Y96500D02*
Y92500D01*
X751200D01*
G01X743800Y101500D02*
Y97500D01*
X751200D01*
G01X759200Y86500D02*
Y90500D01*
X751800D01*
G01X759200Y92500D02*
Y96500D01*
X751800D01*
G01X759200Y97500D02*
Y101500D01*
X751800D01*
G01X751016Y118784D02*
Y114784D01*
X758416D01*
G01X751016Y114284D02*
Y110284D01*
X758416D01*
G01X744924Y132051D02*
X744799Y131801D01*
X744716Y131509D01*
Y131176D01*
X744841Y130801D01*
X745049Y130509D01*
X745299Y130301D01*
X745716Y130134D01*
X746091Y130092D01*
X746466Y130176D01*
X746716Y130301D01*
X746966Y130551D01*
X747133Y130842D01*
X747216Y131134D01*
Y131426D01*
X747133Y131717D01*
X747008Y131967D01*
X746841Y132176D01*
G01X745133Y133442D02*
X744883Y133692D01*
X744758Y133984D01*
X744716Y134317D01*
X744799Y134734D01*
X745008Y135026D01*
X745258Y135109D01*
X745508Y135067D01*
X745716Y134901D01*
X746133Y134067D01*
X746424Y133692D01*
X746841Y133442D01*
X747216Y133359D01*
Y135109D01*
G01X745133Y136542D02*
X744883Y136792D01*
X744758Y137084D01*
X744716Y137417D01*
X744799Y137834D01*
X745008Y138126D01*
X745258Y138209D01*
X745508Y138167D01*
X745716Y138001D01*
X746133Y137167D01*
X746424Y136792D01*
X746841Y136542D01*
X747216Y136459D01*
Y138209D01*
G01X746841Y139517D02*
X747049Y139767D01*
X747174Y140059D01*
X747216Y140434D01*
X747133Y140809D01*
X746966Y141101D01*
X746674Y141309D01*
X746341Y141351D01*
X746008Y141267D01*
X745799Y141059D01*
X745633Y140767D01*
X745591Y140476D01*
X745633Y140184D01*
X745799Y139809D01*
X744716Y139934D01*
Y141059D01*
G01X749456Y132267D02*
X749331Y132017D01*
X749248Y131725D01*
Y131392D01*
X749373Y131017D01*
X749581Y130725D01*
X749831Y130517D01*
X750248Y130350D01*
X750623Y130308D01*
X750998Y130392D01*
X751248Y130517D01*
X751498Y130767D01*
X751665Y131058D01*
X751748Y131350D01*
Y131642D01*
X751665Y131933D01*
X751540Y132183D01*
X751373Y132392D01*
G01X749665Y133658D02*
X749415Y133908D01*
X749290Y134200D01*
X749248Y134533D01*
X749331Y134950D01*
X749540Y135242D01*
X749790Y135325D01*
X750040Y135283D01*
X750248Y135117D01*
X750665Y134283D01*
X750956Y133908D01*
X751373Y133658D01*
X751748Y133575D01*
Y135325D01*
G01X749665Y136758D02*
X749415Y137008D01*
X749290Y137300D01*
X749248Y137633D01*
X749331Y138050D01*
X749540Y138342D01*
X749790Y138425D01*
X750040Y138383D01*
X750248Y138217D01*
X750665Y137383D01*
X750956Y137008D01*
X751373Y136758D01*
X751748Y136675D01*
Y138425D01*
G01Y141150D02*
X749248D01*
X751040Y139608D01*
Y141692D01*
G01X743500Y146800D02*
X747500D01*
Y154200D01*
G01X748248Y169950D02*
X748206Y169617D01*
X748040Y169325D01*
X747790Y169075D01*
X747498Y168908D01*
X747165Y168825D01*
X746831D01*
X746498Y168908D01*
X746206Y169075D01*
X745956Y169325D01*
X745790Y169617D01*
X745748Y169950D01*
X745790Y170283D01*
X745956Y170575D01*
X746206Y170825D01*
X746498Y170992D01*
X746831Y171075D01*
X747165D01*
X747498Y170992D01*
X747790Y170825D01*
X748040Y170575D01*
X748206Y170283D01*
X748248Y169950D01*
G01X747581Y170283D02*
X748248Y170783D01*
G01Y173050D02*
X748206Y173342D01*
X748081Y173675D01*
X747873Y173883D01*
X747581Y173967D01*
X747290Y173883D01*
X747040Y173633D01*
X746915Y173258D01*
Y172842D01*
X746831Y172592D01*
X746623Y172383D01*
X746331Y172300D01*
X746040Y172425D01*
X745831Y172717D01*
X745748Y173050D01*
X745831Y173383D01*
X746040Y173675D01*
X746331Y173800D01*
X746623Y173717D01*
X746831Y173508D01*
X746915Y173258D01*
Y172842D01*
X747040Y172467D01*
X747290Y172217D01*
X747581Y172133D01*
X747873Y172217D01*
X748081Y172425D01*
X748206Y172758D01*
X748248Y173050D01*
G01X750000Y156017D02*
X747500D01*
Y157058D01*
X747625Y157392D01*
X747792Y157600D01*
X748125Y157683D01*
X748458Y157600D01*
X748667Y157350D01*
X748792Y157058D01*
Y156017D01*
G01Y157058D02*
X750000Y157683D01*
G01Y160450D02*
X747500D01*
X749292Y158908D01*
Y160992D01*
G01X750000Y163550D02*
X747500D01*
X749292Y162008D01*
Y164092D01*
G01X749625Y165233D02*
X749833Y165483D01*
X749958Y165775D01*
X750000Y166150D01*
X749917Y166525D01*
X749750Y166817D01*
X749458Y167025D01*
X749125Y167067D01*
X748792Y166983D01*
X748583Y166775D01*
X748417Y166483D01*
X748375Y166192D01*
X748417Y165900D01*
X748583Y165525D01*
X747500Y165650D01*
Y166775D01*
G01X741248Y190500D02*
Y176500D01*
G01X754248D02*
Y190500D01*
G01X741248Y176500D02*
X754248D01*
G01Y190500D02*
X741248D01*
G01X741067Y193000D02*
Y195500D01*
X742108D01*
X742442Y195375D01*
X742650Y195208D01*
X742733Y194875D01*
X742650Y194542D01*
X742400Y194333D01*
X742108Y194208D01*
X741067D01*
G01X742108D02*
X742733Y193000D01*
G01X744208Y195083D02*
X744458Y195333D01*
X744750Y195458D01*
X745083Y195500D01*
X745500Y195417D01*
X745792Y195208D01*
X745875Y194958D01*
X745833Y194708D01*
X745667Y194500D01*
X744833Y194083D01*
X744458Y193792D01*
X744208Y193375D01*
X744125Y193000D01*
X745875D01*
G01X748100D02*
Y195500D01*
X747600Y195000D01*
G01Y193000D02*
X748600D01*
G01X748967Y426000D02*
Y428500D01*
X749967D01*
X750300Y428375D01*
X750550Y428083D01*
X750633Y427750D01*
X750550Y427417D01*
X750342Y427167D01*
X749967Y427042D01*
X748967D01*
G01X753817Y428292D02*
X753567Y428417D01*
X753275Y428500D01*
X752942D01*
X752567Y428375D01*
X752275Y428167D01*
X752067Y427917D01*
X751900Y427500D01*
X751858Y427125D01*
X751942Y426750D01*
X752067Y426500D01*
X752317Y426250D01*
X752608Y426083D01*
X752900Y426000D01*
X753192D01*
X753483Y426083D01*
X753733Y426208D01*
X753942Y426375D01*
G01X755208Y428083D02*
X755458Y428333D01*
X755750Y428458D01*
X756083Y428500D01*
X756500Y428417D01*
X756792Y428208D01*
X756875Y427958D01*
X756833Y427708D01*
X756667Y427500D01*
X755833Y427083D01*
X755458Y426792D01*
X755208Y426375D01*
X755125Y426000D01*
X756875D01*
G01X758183Y426500D02*
X758433Y426208D01*
X758767Y426042D01*
X759142Y426000D01*
X759475Y426042D01*
X759808Y426250D01*
X760017Y426500D01*
X760058Y426750D01*
X759975Y427042D01*
X759683Y427250D01*
X759392Y427333D01*
X759017D01*
G01X759392D02*
X759642Y427458D01*
X759850Y427667D01*
X759933Y427917D01*
X759850Y428167D01*
X759642Y428375D01*
X759267Y428500D01*
X758892Y428458D01*
X758517Y428292D01*
G01X762200Y426000D02*
Y428500D01*
X761700Y428000D01*
G01Y426000D02*
X762700D01*
G01X745917Y430500D02*
Y433000D01*
X746917D01*
X747250Y432875D01*
X747500Y432583D01*
X747583Y432250D01*
X747500Y431917D01*
X747292Y431667D01*
X746917Y431542D01*
X745917D01*
G01X749017Y430500D02*
Y433000D01*
X750058D01*
X750392Y432875D01*
X750600Y432708D01*
X750683Y432375D01*
X750600Y432042D01*
X750350Y431833D01*
X750058Y431708D01*
X749017D01*
G01X750058D02*
X750683Y430500D01*
G01X752242Y430792D02*
X752533Y430583D01*
X752867Y430500D01*
X753200Y430583D01*
X753492Y430833D01*
X753700Y431208D01*
X753783Y431583D01*
Y432042D01*
X753700Y432417D01*
X753492Y432750D01*
X753242Y432917D01*
X752950Y433000D01*
X752617Y432917D01*
X752367Y432750D01*
X752200Y432500D01*
X752117Y432167D01*
X752200Y431875D01*
X752408Y431583D01*
X752658Y431417D01*
X752950Y431375D01*
X753283Y431458D01*
X753533Y431667D01*
X753783Y432042D01*
G01X756050Y433000D02*
X755717Y432917D01*
X755467Y432708D01*
X755300Y432458D01*
X755175Y432125D01*
X755133Y431750D01*
X755175Y431375D01*
X755300Y431042D01*
X755467Y430792D01*
X755717Y430583D01*
X756050Y430500D01*
X756383Y430583D01*
X756633Y430792D01*
X756800Y431042D01*
X756925Y431375D01*
X756967Y431750D01*
X756925Y432125D01*
X756800Y432458D01*
X756633Y432708D01*
X756383Y432917D01*
X756050Y433000D01*
G01X759150Y430500D02*
Y433000D01*
X758650Y432500D01*
G01Y430500D02*
X759650D01*
G01X761542Y430792D02*
X761833Y430583D01*
X762167Y430500D01*
X762500Y430583D01*
X762792Y430833D01*
X763000Y431208D01*
X763083Y431583D01*
Y432042D01*
X763000Y432417D01*
X762792Y432750D01*
X762542Y432917D01*
X762250Y433000D01*
X761917Y432917D01*
X761667Y432750D01*
X761500Y432500D01*
X761417Y432167D01*
X761500Y431875D01*
X761708Y431583D01*
X761958Y431417D01*
X762250Y431375D01*
X762583Y431458D01*
X762833Y431667D01*
X763083Y432042D01*
G01X743000Y444067D02*
X740500D01*
Y445067D01*
X740625Y445400D01*
X740917Y445650D01*
X741250Y445733D01*
X741583Y445650D01*
X741833Y445442D01*
X741958Y445067D01*
Y444067D01*
G01X743000Y448000D02*
X742958Y447667D01*
X742792Y447375D01*
X742542Y447125D01*
X742250Y446958D01*
X741917Y446875D01*
X741583D01*
X741250Y446958D01*
X740958Y447125D01*
X740708Y447375D01*
X740542Y447667D01*
X740500Y448000D01*
X740542Y448333D01*
X740708Y448625D01*
X740958Y448875D01*
X741250Y449042D01*
X741583Y449125D01*
X741917D01*
X742250Y449042D01*
X742542Y448875D01*
X742792Y448625D01*
X742958Y448333D01*
X743000Y448000D01*
G01X742333Y448333D02*
X743000Y448833D01*
G01X741958Y450308D02*
X741667Y450600D01*
X741500Y450850D01*
X741417Y451183D01*
X741500Y451475D01*
X741667Y451683D01*
X741917Y451850D01*
X742208Y451892D01*
X742458Y451850D01*
X742708Y451683D01*
X742917Y451433D01*
X743000Y451142D01*
X742917Y450808D01*
X742667Y450517D01*
X742292Y450350D01*
X741875Y450308D01*
X741333Y450392D01*
X741042Y450517D01*
X740750Y450725D01*
X740542Y451017D01*
X740500Y451308D01*
X740583Y451600D01*
X740792Y451808D01*
G01X748000Y434917D02*
X745500D01*
Y435917D01*
X745625Y436250D01*
X745917Y436500D01*
X746250Y436583D01*
X746583Y436500D01*
X746833Y436292D01*
X746958Y435917D01*
Y434917D01*
G01X748000Y438017D02*
X745500D01*
Y439058D01*
X745625Y439392D01*
X745792Y439600D01*
X746125Y439683D01*
X746458Y439600D01*
X746667Y439350D01*
X746792Y439058D01*
Y438017D01*
G01Y439058D02*
X748000Y439683D01*
G01Y441867D02*
X747458Y441950D01*
X747000Y442075D01*
X746583Y442242D01*
X746125Y442450D01*
X745500Y442783D01*
Y441117D01*
G01X748000Y445050D02*
X747958Y445342D01*
X747833Y445675D01*
X747625Y445883D01*
X747333Y445967D01*
X747042Y445883D01*
X746792Y445633D01*
X746667Y445258D01*
Y444842D01*
X746583Y444592D01*
X746375Y444383D01*
X746083Y444300D01*
X745792Y444425D01*
X745583Y444717D01*
X745500Y445050D01*
X745583Y445383D01*
X745792Y445675D01*
X746083Y445800D01*
X746375Y445717D01*
X746583Y445508D01*
X746667Y445258D01*
Y444842D01*
X746792Y444467D01*
X747042Y444217D01*
X747333Y444133D01*
X747625Y444217D01*
X747833Y444425D01*
X747958Y444758D01*
X748000Y445050D01*
G01Y448150D02*
X747958Y448442D01*
X747833Y448775D01*
X747625Y448983D01*
X747333Y449067D01*
X747042Y448983D01*
X746792Y448733D01*
X746667Y448358D01*
Y447942D01*
X746583Y447692D01*
X746375Y447483D01*
X746083Y447400D01*
X745792Y447525D01*
X745583Y447817D01*
X745500Y448150D01*
X745583Y448483D01*
X745792Y448775D01*
X746083Y448900D01*
X746375Y448817D01*
X746583Y448608D01*
X746667Y448358D01*
Y447942D01*
X746792Y447567D01*
X747042Y447317D01*
X747333Y447233D01*
X747625Y447317D01*
X747833Y447525D01*
X747958Y447858D01*
X748000Y448150D01*
G01X747708Y450542D02*
X747917Y450833D01*
X748000Y451167D01*
X747917Y451500D01*
X747667Y451792D01*
X747292Y452000D01*
X746917Y452083D01*
X746458D01*
X746083Y452000D01*
X745750Y451792D01*
X745583Y451542D01*
X745500Y451250D01*
X745583Y450917D01*
X745750Y450667D01*
X746000Y450500D01*
X746333Y450417D01*
X746625Y450500D01*
X746917Y450708D01*
X747083Y450958D01*
X747125Y451250D01*
X747042Y451583D01*
X746833Y451833D01*
X746458Y452083D01*
G01X752000Y434917D02*
X749500D01*
Y435917D01*
X749625Y436250D01*
X749917Y436500D01*
X750250Y436583D01*
X750583Y436500D01*
X750833Y436292D01*
X750958Y435917D01*
Y434917D01*
G01X752000Y438017D02*
X749500D01*
Y439058D01*
X749625Y439392D01*
X749792Y439600D01*
X750125Y439683D01*
X750458Y439600D01*
X750667Y439350D01*
X750792Y439058D01*
Y438017D01*
G01Y439058D02*
X752000Y439683D01*
G01X751708Y441242D02*
X751917Y441533D01*
X752000Y441867D01*
X751917Y442200D01*
X751667Y442492D01*
X751292Y442700D01*
X750917Y442783D01*
X750458D01*
X750083Y442700D01*
X749750Y442492D01*
X749583Y442242D01*
X749500Y441950D01*
X749583Y441617D01*
X749750Y441367D01*
X750000Y441200D01*
X750333Y441117D01*
X750625Y441200D01*
X750917Y441408D01*
X751083Y441658D01*
X751125Y441950D01*
X751042Y442283D01*
X750833Y442533D01*
X750458Y442783D01*
G01X749500Y445050D02*
X749583Y444717D01*
X749792Y444467D01*
X750042Y444300D01*
X750375Y444175D01*
X750750Y444133D01*
X751125Y444175D01*
X751458Y444300D01*
X751708Y444467D01*
X751917Y444717D01*
X752000Y445050D01*
X751917Y445383D01*
X751708Y445633D01*
X751458Y445800D01*
X751125Y445925D01*
X750750Y445967D01*
X750375Y445925D01*
X750042Y445800D01*
X749792Y445633D01*
X749583Y445383D01*
X749500Y445050D01*
G01X749917Y447358D02*
X749667Y447608D01*
X749542Y447900D01*
X749500Y448233D01*
X749583Y448650D01*
X749792Y448942D01*
X750042Y449025D01*
X750292Y448983D01*
X750500Y448817D01*
X750917Y447983D01*
X751208Y447608D01*
X751625Y447358D01*
X752000Y447275D01*
Y449025D01*
G01X749500Y451250D02*
X749583Y450917D01*
X749792Y450667D01*
X750042Y450500D01*
X750375Y450375D01*
X750750Y450333D01*
X751125Y450375D01*
X751458Y450500D01*
X751708Y450667D01*
X751917Y450917D01*
X752000Y451250D01*
X751917Y451583D01*
X751708Y451833D01*
X751458Y452000D01*
X751125Y452125D01*
X750750Y452167D01*
X750375Y452125D01*
X750042Y452000D01*
X749792Y451833D01*
X749583Y451583D01*
X749500Y451250D01*
G01X756000Y436467D02*
X753500D01*
Y437467D01*
X753625Y437800D01*
X753917Y438050D01*
X754250Y438133D01*
X754583Y438050D01*
X754833Y437842D01*
X754958Y437467D01*
Y436467D01*
G01X753708Y441317D02*
X753583Y441067D01*
X753500Y440775D01*
Y440442D01*
X753625Y440067D01*
X753833Y439775D01*
X754083Y439567D01*
X754500Y439400D01*
X754875Y439358D01*
X755250Y439442D01*
X755500Y439567D01*
X755750Y439817D01*
X755917Y440108D01*
X756000Y440400D01*
Y440692D01*
X755917Y440983D01*
X755792Y441233D01*
X755625Y441442D01*
G01X753917Y442708D02*
X753667Y442958D01*
X753542Y443250D01*
X753500Y443583D01*
X753583Y444000D01*
X753792Y444292D01*
X754042Y444375D01*
X754292Y444333D01*
X754500Y444167D01*
X754917Y443333D01*
X755208Y442958D01*
X755625Y442708D01*
X756000Y442625D01*
Y444375D01*
G01Y447100D02*
X753500D01*
X755292Y445558D01*
Y447642D01*
G01X753500Y449700D02*
X753583Y449367D01*
X753792Y449117D01*
X754042Y448950D01*
X754375Y448825D01*
X754750Y448783D01*
X755125Y448825D01*
X755458Y448950D01*
X755708Y449117D01*
X755917Y449367D01*
X756000Y449700D01*
X755917Y450033D01*
X755708Y450283D01*
X755458Y450450D01*
X755125Y450575D01*
X754750Y450617D01*
X754375Y450575D01*
X754042Y450450D01*
X753792Y450283D01*
X753583Y450033D01*
X753500Y449700D01*
G01X746500Y455000D02*
X760500D01*
G01X746500Y468000D02*
Y455000D01*
G01X747100Y479200D02*
X757900D01*
G01X747100Y486800D02*
Y479200D01*
G01X760500Y468000D02*
X746500D01*
G01X755164Y469538D02*
Y473538D01*
X747764D01*
G01Y478038D02*
Y474038D01*
X755164D01*
G01X754000Y500900D02*
X753958Y500567D01*
X753792Y500275D01*
X753542Y500025D01*
X753250Y499858D01*
X752917Y499775D01*
X752583D01*
X752250Y499858D01*
X751958Y500025D01*
X751708Y500275D01*
X751542Y500567D01*
X751500Y500900D01*
X751542Y501233D01*
X751708Y501525D01*
X751958Y501775D01*
X752250Y501942D01*
X752583Y502025D01*
X752917D01*
X753250Y501942D01*
X753542Y501775D01*
X753792Y501525D01*
X753958Y501233D01*
X754000Y500900D01*
G01X753333Y501233D02*
X754000Y501733D01*
G01Y503917D02*
X753458Y504000D01*
X753000Y504125D01*
X752583Y504292D01*
X752125Y504500D01*
X751500Y504833D01*
Y503167D01*
G01X754000Y507017D02*
X753458Y507100D01*
X753000Y507225D01*
X752583Y507392D01*
X752125Y507600D01*
X751500Y507933D01*
Y506267D01*
G01X757900Y486800D02*
X747100D01*
G01X745967Y490000D02*
Y492500D01*
X746967D01*
X747300Y492375D01*
X747550Y492083D01*
X747633Y491750D01*
X747550Y491417D01*
X747342Y491167D01*
X746967Y491042D01*
X745967D01*
G01X749067Y490000D02*
Y492500D01*
X750108D01*
X750442Y492375D01*
X750650Y492208D01*
X750733Y491875D01*
X750650Y491542D01*
X750400Y491333D01*
X750108Y491208D01*
X749067D01*
G01X750108D02*
X750733Y490000D01*
G01X753000D02*
Y492500D01*
X752500Y492000D01*
G01Y490000D02*
X753500D01*
G01X756017D02*
X756100Y490542D01*
X756225Y491000D01*
X756392Y491417D01*
X756600Y491875D01*
X756933Y492500D01*
X755267D01*
G01X758408Y492083D02*
X758658Y492333D01*
X758950Y492458D01*
X759283Y492500D01*
X759700Y492417D01*
X759992Y492208D01*
X760075Y491958D01*
X760033Y491708D01*
X759867Y491500D01*
X759033Y491083D01*
X758658Y490792D01*
X758408Y490375D01*
X758325Y490000D01*
X760075D01*
G01X748517Y494500D02*
Y497000D01*
X749558D01*
X749892Y496875D01*
X750100Y496708D01*
X750183Y496375D01*
X750100Y496042D01*
X749850Y495833D01*
X749558Y495708D01*
X748517D01*
G01X749558D02*
X750183Y494500D01*
G01X751658Y495542D02*
X751950Y495833D01*
X752200Y496000D01*
X752533Y496083D01*
X752825Y496000D01*
X753033Y495833D01*
X753200Y495583D01*
X753242Y495292D01*
X753200Y495042D01*
X753033Y494792D01*
X752783Y494583D01*
X752492Y494500D01*
X752158Y494583D01*
X751867Y494833D01*
X751700Y495208D01*
X751658Y495625D01*
X751742Y496167D01*
X751867Y496458D01*
X752075Y496750D01*
X752367Y496958D01*
X752658Y497000D01*
X752950Y496917D01*
X753158Y496708D01*
G01X755550Y497000D02*
X755217Y496917D01*
X754967Y496708D01*
X754800Y496458D01*
X754675Y496125D01*
X754633Y495750D01*
X754675Y495375D01*
X754800Y495042D01*
X754967Y494792D01*
X755217Y494583D01*
X755550Y494500D01*
X755883Y494583D01*
X756133Y494792D01*
X756300Y495042D01*
X756425Y495375D01*
X756467Y495750D01*
X756425Y496125D01*
X756300Y496458D01*
X756133Y496708D01*
X755883Y496917D01*
X755550Y497000D01*
G01X758650D02*
X758317Y496917D01*
X758067Y496708D01*
X757900Y496458D01*
X757775Y496125D01*
X757733Y495750D01*
X757775Y495375D01*
X757900Y495042D01*
X758067Y494792D01*
X758317Y494583D01*
X758650Y494500D01*
X758983Y494583D01*
X759233Y494792D01*
X759400Y495042D01*
X759525Y495375D01*
X759567Y495750D01*
X759525Y496125D01*
X759400Y496458D01*
X759233Y496708D01*
X758983Y496917D01*
X758650Y497000D01*
G01X758000Y500017D02*
X755500D01*
Y501058D01*
X755625Y501392D01*
X755792Y501600D01*
X756125Y501683D01*
X756458Y501600D01*
X756667Y501350D01*
X756792Y501058D01*
Y500017D01*
G01Y501058D02*
X758000Y501683D01*
G01X756958Y503158D02*
X756667Y503450D01*
X756500Y503700D01*
X756417Y504033D01*
X756500Y504325D01*
X756667Y504533D01*
X756917Y504700D01*
X757208Y504742D01*
X757458Y504700D01*
X757708Y504533D01*
X757917Y504283D01*
X758000Y503992D01*
X757917Y503658D01*
X757667Y503367D01*
X757292Y503200D01*
X756875Y503158D01*
X756333Y503242D01*
X756042Y503367D01*
X755750Y503575D01*
X755542Y503867D01*
X755500Y504158D01*
X755583Y504450D01*
X755792Y504658D01*
G01X755500Y507050D02*
X755583Y506717D01*
X755792Y506467D01*
X756042Y506300D01*
X756375Y506175D01*
X756750Y506133D01*
X757125Y506175D01*
X757458Y506300D01*
X757708Y506467D01*
X757917Y506717D01*
X758000Y507050D01*
X757917Y507383D01*
X757708Y507633D01*
X757458Y507800D01*
X757125Y507925D01*
X756750Y507967D01*
X756375Y507925D01*
X756042Y507800D01*
X755792Y507633D01*
X755583Y507383D01*
X755500Y507050D01*
G01X755917Y509358D02*
X755667Y509608D01*
X755542Y509900D01*
X755500Y510233D01*
X755583Y510650D01*
X755792Y510942D01*
X756042Y511025D01*
X756292Y510983D01*
X756500Y510817D01*
X756917Y509983D01*
X757208Y509608D01*
X757625Y509358D01*
X758000Y509275D01*
Y511025D01*
G01X753975Y540333D02*
X754308Y540125D01*
X754683Y540000D01*
X755017D01*
X755350Y540125D01*
X755600Y540333D01*
X755725Y540625D01*
X755642Y540917D01*
X755433Y541167D01*
X755058Y541333D01*
X754558Y541417D01*
X754267Y541583D01*
X754142Y541875D01*
X754225Y542167D01*
X754433Y542375D01*
X754725Y542500D01*
X755017D01*
X755308Y542417D01*
X755558Y542208D01*
G01X757033Y542500D02*
Y540708D01*
X757200Y540333D01*
X757533Y540083D01*
X757950Y540000D01*
X758367Y540083D01*
X758700Y540333D01*
X758867Y540708D01*
Y542500D01*
G01X760258Y541042D02*
X760550Y541333D01*
X760800Y541500D01*
X761133Y541583D01*
X761425Y541500D01*
X761633Y541333D01*
X761800Y541083D01*
X761842Y540792D01*
X761800Y540542D01*
X761633Y540292D01*
X761383Y540083D01*
X761092Y540000D01*
X760758Y540083D01*
X760467Y540333D01*
X760300Y540708D01*
X760258Y541125D01*
X760342Y541667D01*
X760467Y541958D01*
X760675Y542250D01*
X760967Y542458D01*
X761258Y542500D01*
X761550Y542417D01*
X761758Y542208D01*
G01X764067Y540000D02*
X764150Y540542D01*
X764275Y541000D01*
X764442Y541417D01*
X764650Y541875D01*
X764983Y542500D01*
X763317D01*
G01X767084Y545191D02*
Y564391D01*
X755884D01*
Y545191D01*
X767084D01*
Y545591D01*
G01X757700Y569000D02*
Y573000D01*
X750300D01*
G01X757700Y573500D02*
Y577500D01*
X750300D01*
G01X747425Y594333D02*
X747758Y594125D01*
X748133Y594000D01*
X748467D01*
X748800Y594125D01*
X749050Y594333D01*
X749175Y594625D01*
X749092Y594917D01*
X748883Y595167D01*
X748508Y595333D01*
X748008Y595417D01*
X747717Y595583D01*
X747592Y595875D01*
X747675Y596167D01*
X747883Y596375D01*
X748175Y596500D01*
X748467D01*
X748758Y596417D01*
X749008Y596208D01*
G01X750567Y594000D02*
Y596500D01*
X751608D01*
X751942Y596375D01*
X752150Y596208D01*
X752233Y595875D01*
X752150Y595542D01*
X751900Y595333D01*
X751608Y595208D01*
X750567D01*
G01X751608D02*
X752233Y594000D01*
G01X754417D02*
X754500Y594542D01*
X754625Y595000D01*
X754792Y595417D01*
X755000Y595875D01*
X755333Y596500D01*
X753667D01*
G01X756683Y594500D02*
X756933Y594208D01*
X757267Y594042D01*
X757642Y594000D01*
X757975Y594042D01*
X758308Y594250D01*
X758517Y594500D01*
X758558Y594750D01*
X758475Y595042D01*
X758183Y595250D01*
X757892Y595333D01*
X757517D01*
G01X757892D02*
X758142Y595458D01*
X758350Y595667D01*
X758433Y595917D01*
X758350Y596167D01*
X758142Y596375D01*
X757767Y596500D01*
X757392Y596458D01*
X757017Y596292D01*
G01X760617Y594000D02*
X760700Y594542D01*
X760825Y595000D01*
X760992Y595417D01*
X761200Y595875D01*
X761533Y596500D01*
X759867D01*
G01X747425Y598833D02*
X747758Y598625D01*
X748133Y598500D01*
X748467D01*
X748800Y598625D01*
X749050Y598833D01*
X749175Y599125D01*
X749092Y599417D01*
X748883Y599667D01*
X748508Y599833D01*
X748008Y599917D01*
X747717Y600083D01*
X747592Y600375D01*
X747675Y600667D01*
X747883Y600875D01*
X748175Y601000D01*
X748467D01*
X748758Y600917D01*
X749008Y600708D01*
G01X750567Y598500D02*
Y601000D01*
X751608D01*
X751942Y600875D01*
X752150Y600708D01*
X752233Y600375D01*
X752150Y600042D01*
X751900Y599833D01*
X751608Y599708D01*
X750567D01*
G01X751608D02*
X752233Y598500D01*
G01X754417D02*
X754500Y599042D01*
X754625Y599500D01*
X754792Y599917D01*
X755000Y600375D01*
X755333Y601000D01*
X753667D01*
G01X756683Y599000D02*
X756933Y598708D01*
X757267Y598542D01*
X757642Y598500D01*
X757975Y598542D01*
X758308Y598750D01*
X758517Y599000D01*
X758558Y599250D01*
X758475Y599542D01*
X758183Y599750D01*
X757892Y599833D01*
X757517D01*
G01X757892D02*
X758142Y599958D01*
X758350Y600167D01*
X758433Y600417D01*
X758350Y600667D01*
X758142Y600875D01*
X757767Y601000D01*
X757392Y600958D01*
X757017Y600792D01*
G01X760700Y598500D02*
X760992Y598542D01*
X761325Y598667D01*
X761533Y598875D01*
X761617Y599167D01*
X761533Y599458D01*
X761283Y599708D01*
X760908Y599833D01*
X760492D01*
X760242Y599917D01*
X760033Y600125D01*
X759950Y600417D01*
X760075Y600708D01*
X760367Y600917D01*
X760700Y601000D01*
X761033Y600917D01*
X761325Y600708D01*
X761450Y600417D01*
X761367Y600125D01*
X761158Y599917D01*
X760908Y599833D01*
X760492D01*
X760117Y599708D01*
X759867Y599458D01*
X759783Y599167D01*
X759867Y598875D01*
X760075Y598667D01*
X760408Y598542D01*
X760700Y598500D01*
G01X747875Y603333D02*
X748208Y603125D01*
X748583Y603000D01*
X748917D01*
X749250Y603125D01*
X749500Y603333D01*
X749625Y603625D01*
X749542Y603917D01*
X749333Y604167D01*
X748958Y604333D01*
X748458Y604417D01*
X748167Y604583D01*
X748042Y604875D01*
X748125Y605167D01*
X748333Y605375D01*
X748625Y605500D01*
X748917D01*
X749208Y605417D01*
X749458Y605208D01*
G01X752767Y605292D02*
X752517Y605417D01*
X752225Y605500D01*
X751892D01*
X751517Y605375D01*
X751225Y605167D01*
X751017Y604917D01*
X750850Y604500D01*
X750808Y604125D01*
X750892Y603750D01*
X751017Y603500D01*
X751267Y603250D01*
X751558Y603083D01*
X751850Y603000D01*
X752142D01*
X752433Y603083D01*
X752683Y603208D01*
X752892Y603375D01*
G01X754950Y603000D02*
Y605500D01*
X754450Y605000D01*
G01Y603000D02*
X755450D01*
G01X758050D02*
Y605500D01*
X757550Y605000D01*
G01Y603000D02*
X758550D01*
G01X761150D02*
Y605500D01*
X760650Y605000D01*
G01Y603000D02*
X761650D01*
G01X764250Y605500D02*
X763917Y605417D01*
X763667Y605208D01*
X763500Y604958D01*
X763375Y604625D01*
X763333Y604250D01*
X763375Y603875D01*
X763500Y603542D01*
X763667Y603292D01*
X763917Y603083D01*
X764250Y603000D01*
X764583Y603083D01*
X764833Y603292D01*
X765000Y603542D01*
X765125Y603875D01*
X765167Y604250D01*
X765125Y604625D01*
X765000Y604958D01*
X764833Y605208D01*
X764583Y605417D01*
X764250Y605500D01*
G01X754500Y654900D02*
X754458Y654567D01*
X754292Y654275D01*
X754042Y654025D01*
X753750Y653858D01*
X753417Y653775D01*
X753083D01*
X752750Y653858D01*
X752458Y654025D01*
X752208Y654275D01*
X752042Y654567D01*
X752000Y654900D01*
X752042Y655233D01*
X752208Y655525D01*
X752458Y655775D01*
X752750Y655942D01*
X753083Y656025D01*
X753417D01*
X753750Y655942D01*
X754042Y655775D01*
X754292Y655525D01*
X754458Y655233D01*
X754500Y654900D01*
G01X753833Y655233D02*
X754500Y655733D01*
G01Y658000D02*
X752000D01*
X752500Y657500D01*
G01X754500D02*
Y658500D01*
G01Y661100D02*
X752000D01*
X752500Y660600D01*
G01X754500D02*
Y661600D01*
G01X757017Y674500D02*
Y677000D01*
X758017D01*
X758350Y676875D01*
X758600Y676583D01*
X758683Y676250D01*
X758600Y675917D01*
X758392Y675667D01*
X758017Y675542D01*
X757017D01*
G01X760117Y674500D02*
Y677000D01*
X761158D01*
X761492Y676875D01*
X761700Y676708D01*
X761783Y676375D01*
X761700Y676042D01*
X761450Y675833D01*
X761158Y675708D01*
X760117D01*
G01X761158D02*
X761783Y674500D01*
G01X763133Y674875D02*
X763383Y674667D01*
X763675Y674542D01*
X764050Y674500D01*
X764425Y674583D01*
X764717Y674750D01*
X764925Y675042D01*
X764967Y675375D01*
X764883Y675708D01*
X764675Y675917D01*
X764383Y676083D01*
X764092Y676125D01*
X763800Y676083D01*
X763425Y675917D01*
X763550Y677000D01*
X764675D01*
G01X767150Y674500D02*
X767442Y674542D01*
X767775Y674667D01*
X767983Y674875D01*
X768067Y675167D01*
X767983Y675458D01*
X767733Y675708D01*
X767358Y675833D01*
X766942D01*
X766692Y675917D01*
X766483Y676125D01*
X766400Y676417D01*
X766525Y676708D01*
X766817Y676917D01*
X767150Y677000D01*
X767483Y676917D01*
X767775Y676708D01*
X767900Y676417D01*
X767817Y676125D01*
X767608Y675917D01*
X767358Y675833D01*
X766942D01*
X766567Y675708D01*
X766317Y675458D01*
X766233Y675167D01*
X766317Y674875D01*
X766525Y674667D01*
X766858Y674542D01*
X767150Y674500D01*
G01X744000Y692000D02*
X770000D01*
G01X744000Y705000D02*
Y692000D01*
G01X746517Y706500D02*
Y709000D01*
X747558D01*
X747892Y708875D01*
X748100Y708708D01*
X748183Y708375D01*
X748100Y708042D01*
X747850Y707833D01*
X747558Y707708D01*
X746517D01*
G01X747558D02*
X748183Y706500D01*
G01X750950D02*
Y709000D01*
X749408Y707208D01*
X751492D01*
G01X753467Y706500D02*
X753550Y707042D01*
X753675Y707500D01*
X753842Y707917D01*
X754050Y708375D01*
X754383Y709000D01*
X752717D01*
G01X755942Y706792D02*
X756233Y706583D01*
X756567Y706500D01*
X756900Y706583D01*
X757192Y706833D01*
X757400Y707208D01*
X757483Y707583D01*
Y708042D01*
X757400Y708417D01*
X757192Y708750D01*
X756942Y708917D01*
X756650Y709000D01*
X756317Y708917D01*
X756067Y708750D01*
X755900Y708500D01*
X755817Y708167D01*
X755900Y707875D01*
X756108Y707583D01*
X756358Y707417D01*
X756650Y707375D01*
X756983Y707458D01*
X757233Y707667D01*
X757483Y708042D01*
G01X770000Y705000D02*
X744000D01*
G01X741517Y762000D02*
Y764500D01*
X742558D01*
X742892Y764375D01*
X743100Y764208D01*
X743183Y763875D01*
X743100Y763542D01*
X742850Y763333D01*
X742558Y763208D01*
X741517D01*
G01X742558D02*
X743183Y762000D01*
G01X745950D02*
Y764500D01*
X744408Y762708D01*
X746492D01*
G01X747758Y764083D02*
X748008Y764333D01*
X748300Y764458D01*
X748633Y764500D01*
X749050Y764417D01*
X749342Y764208D01*
X749425Y763958D01*
X749383Y763708D01*
X749217Y763500D01*
X748383Y763083D01*
X748008Y762792D01*
X747758Y762375D01*
X747675Y762000D01*
X749425D01*
G01X750942Y762292D02*
X751233Y762083D01*
X751567Y762000D01*
X751900Y762083D01*
X752192Y762333D01*
X752400Y762708D01*
X752483Y763083D01*
Y763542D01*
X752400Y763917D01*
X752192Y764250D01*
X751942Y764417D01*
X751650Y764500D01*
X751317Y764417D01*
X751067Y764250D01*
X750900Y764000D01*
X750817Y763667D01*
X750900Y763375D01*
X751108Y763083D01*
X751358Y762917D01*
X751650Y762875D01*
X751983Y762958D01*
X752233Y763167D01*
X752483Y763542D01*
G01X748517Y768000D02*
Y770500D01*
X749558D01*
X749892Y770375D01*
X750100Y770208D01*
X750183Y769875D01*
X750100Y769542D01*
X749850Y769333D01*
X749558Y769208D01*
X748517D01*
G01X749558D02*
X750183Y768000D01*
G01X752450D02*
Y770500D01*
X751950Y770000D01*
G01Y768000D02*
X752950D01*
G01X754633Y768375D02*
X754883Y768167D01*
X755175Y768042D01*
X755550Y768000D01*
X755925Y768083D01*
X756217Y768250D01*
X756425Y768542D01*
X756467Y768875D01*
X756383Y769208D01*
X756175Y769417D01*
X755883Y769583D01*
X755592Y769625D01*
X755300Y769583D01*
X754925Y769417D01*
X755050Y770500D01*
X756175D01*
G01X759150Y768000D02*
Y770500D01*
X757608Y768708D01*
X759692D01*
G01X752017Y856500D02*
Y859000D01*
X753058D01*
X753392Y858875D01*
X753600Y858708D01*
X753683Y858375D01*
X753600Y858042D01*
X753350Y857833D01*
X753058Y857708D01*
X752017D01*
G01X753058D02*
X753683Y856500D01*
G01X755158Y858583D02*
X755408Y858833D01*
X755700Y858958D01*
X756033Y859000D01*
X756450Y858917D01*
X756742Y858708D01*
X756825Y858458D01*
X756783Y858208D01*
X756617Y858000D01*
X755783Y857583D01*
X755408Y857292D01*
X755158Y856875D01*
X755075Y856500D01*
X756825D01*
G01X758258Y858583D02*
X758508Y858833D01*
X758800Y858958D01*
X759133Y859000D01*
X759550Y858917D01*
X759842Y858708D01*
X759925Y858458D01*
X759883Y858208D01*
X759717Y858000D01*
X758883Y857583D01*
X758508Y857292D01*
X758258Y856875D01*
X758175Y856500D01*
X759925D01*
G01X762150D02*
Y859000D01*
X761650Y858500D01*
G01Y856500D02*
X762650D01*
G01X752017Y852000D02*
Y854500D01*
X753058D01*
X753392Y854375D01*
X753600Y854208D01*
X753683Y853875D01*
X753600Y853542D01*
X753350Y853333D01*
X753058Y853208D01*
X752017D01*
G01X753058D02*
X753683Y852000D01*
G01X755033Y852500D02*
X755283Y852208D01*
X755617Y852042D01*
X755992Y852000D01*
X756325Y852042D01*
X756658Y852250D01*
X756867Y852500D01*
X756908Y852750D01*
X756825Y853042D01*
X756533Y853250D01*
X756242Y853333D01*
X755867D01*
G01X756242D02*
X756492Y853458D01*
X756700Y853667D01*
X756783Y853917D01*
X756700Y854167D01*
X756492Y854375D01*
X756117Y854500D01*
X755742Y854458D01*
X755367Y854292D01*
G01X758258Y854083D02*
X758508Y854333D01*
X758800Y854458D01*
X759133Y854500D01*
X759550Y854417D01*
X759842Y854208D01*
X759925Y853958D01*
X759883Y853708D01*
X759717Y853500D01*
X758883Y853083D01*
X758508Y852792D01*
X758258Y852375D01*
X758175Y852000D01*
X759925D01*
G01X761358Y853042D02*
X761650Y853333D01*
X761900Y853500D01*
X762233Y853583D01*
X762525Y853500D01*
X762733Y853333D01*
X762900Y853083D01*
X762942Y852792D01*
X762900Y852542D01*
X762733Y852292D01*
X762483Y852083D01*
X762192Y852000D01*
X761858Y852083D01*
X761567Y852333D01*
X761400Y852708D01*
X761358Y853125D01*
X761442Y853667D01*
X761567Y853958D01*
X761775Y854250D01*
X762067Y854458D01*
X762358Y854500D01*
X762650Y854417D01*
X762858Y854208D01*
G01X749467Y867500D02*
Y870000D01*
X750508D01*
X750842Y869875D01*
X751050Y869708D01*
X751133Y869375D01*
X751050Y869042D01*
X750800Y868833D01*
X750508Y868708D01*
X749467D01*
G01X750508D02*
X751133Y867500D01*
G01X753400D02*
Y870000D01*
X752900Y869500D01*
G01Y867500D02*
X753900D01*
G01X755583Y867875D02*
X755833Y867667D01*
X756125Y867542D01*
X756500Y867500D01*
X756875Y867583D01*
X757167Y867750D01*
X757375Y868042D01*
X757417Y868375D01*
X757333Y868708D01*
X757125Y868917D01*
X756833Y869083D01*
X756542Y869125D01*
X756250Y869083D01*
X755875Y868917D01*
X756000Y870000D01*
X757125D01*
G01X759600Y867500D02*
X759892Y867542D01*
X760225Y867667D01*
X760433Y867875D01*
X760517Y868167D01*
X760433Y868458D01*
X760183Y868708D01*
X759808Y868833D01*
X759392D01*
X759142Y868917D01*
X758933Y869125D01*
X758850Y869417D01*
X758975Y869708D01*
X759267Y869917D01*
X759600Y870000D01*
X759933Y869917D01*
X760225Y869708D01*
X760350Y869417D01*
X760267Y869125D01*
X760058Y868917D01*
X759808Y868833D01*
X759392D01*
X759017Y868708D01*
X758767Y868458D01*
X758683Y868167D01*
X758767Y867875D01*
X758975Y867667D01*
X759308Y867542D01*
X759600Y867500D01*
G01X761908Y868542D02*
X762200Y868833D01*
X762450Y869000D01*
X762783Y869083D01*
X763075Y869000D01*
X763283Y868833D01*
X763450Y868583D01*
X763492Y868292D01*
X763450Y868042D01*
X763283Y867792D01*
X763033Y867583D01*
X762742Y867500D01*
X762408Y867583D01*
X762117Y867833D01*
X761950Y868208D01*
X761908Y868625D01*
X761992Y869167D01*
X762117Y869458D01*
X762325Y869750D01*
X762617Y869958D01*
X762908Y870000D01*
X763200Y869917D01*
X763408Y869708D01*
G01X752800Y876500D02*
Y872500D01*
X760200D01*
G01X750433Y906500D02*
Y904708D01*
X750600Y904333D01*
X750933Y904083D01*
X751350Y904000D01*
X751767Y904083D01*
X752100Y904333D01*
X752267Y904708D01*
Y906500D01*
G01X754450Y904000D02*
Y906500D01*
X753950Y906000D01*
G01Y904000D02*
X754950D01*
G01X757467D02*
X757550Y904542D01*
X757675Y905000D01*
X757842Y905417D01*
X758050Y905875D01*
X758383Y906500D01*
X756717D01*
G01X759733Y904375D02*
X759983Y904167D01*
X760275Y904042D01*
X760650Y904000D01*
X761025Y904083D01*
X761317Y904250D01*
X761525Y904542D01*
X761567Y904875D01*
X761483Y905208D01*
X761275Y905417D01*
X760983Y905583D01*
X760692Y905625D01*
X760400Y905583D01*
X760025Y905417D01*
X760150Y906500D01*
X761275D01*
G01X755650Y982750D02*
X756483D01*
Y982000D01*
X756233Y981750D01*
X755942Y981583D01*
X755525Y981500D01*
X755108Y981583D01*
X754817Y981750D01*
X754567Y982000D01*
X754400Y982292D01*
X754317Y982625D01*
Y982917D01*
X754400Y983167D01*
X754567Y983458D01*
X754817Y983708D01*
X755067Y983875D01*
X755400Y984000D01*
X755692D01*
X756025Y983917D01*
X756275Y983750D01*
G01X757708Y981500D02*
Y984000D01*
X759292D01*
G01X758708Y982792D02*
X757708D01*
G01X761517Y981500D02*
X761600Y982042D01*
X761725Y982500D01*
X761892Y982917D01*
X762100Y983375D01*
X762433Y984000D01*
X760767D01*
G01X770017Y49500D02*
Y52000D01*
X771058D01*
X771392Y51875D01*
X771600Y51708D01*
X771683Y51375D01*
X771600Y51042D01*
X771350Y50833D01*
X771058Y50708D01*
X770017D01*
G01X771058D02*
X771683Y49500D01*
G01X773950D02*
Y52000D01*
X773450Y51500D01*
G01Y49500D02*
X774450D01*
G01X776342Y49792D02*
X776633Y49583D01*
X776967Y49500D01*
X777300Y49583D01*
X777592Y49833D01*
X777800Y50208D01*
X777883Y50583D01*
Y51042D01*
X777800Y51417D01*
X777592Y51750D01*
X777342Y51917D01*
X777050Y52000D01*
X776717Y51917D01*
X776467Y51750D01*
X776300Y51500D01*
X776217Y51167D01*
X776300Y50875D01*
X776508Y50583D01*
X776758Y50417D01*
X777050Y50375D01*
X777383Y50458D01*
X777633Y50667D01*
X777883Y51042D01*
G01X780150Y49500D02*
Y52000D01*
X779650Y51500D01*
G01Y49500D02*
X780650D01*
G01X766967Y54000D02*
Y56500D01*
X768008D01*
X768342Y56375D01*
X768550Y56208D01*
X768633Y55875D01*
X768550Y55542D01*
X768300Y55333D01*
X768008Y55208D01*
X766967D01*
G01X768008D02*
X768633Y54000D01*
G01X769983Y54375D02*
X770233Y54167D01*
X770525Y54042D01*
X770900Y54000D01*
X771275Y54083D01*
X771567Y54250D01*
X771775Y54542D01*
X771817Y54875D01*
X771733Y55208D01*
X771525Y55417D01*
X771233Y55583D01*
X770942Y55625D01*
X770650Y55583D01*
X770275Y55417D01*
X770400Y56500D01*
X771525D01*
G01X773083Y54500D02*
X773333Y54208D01*
X773667Y54042D01*
X774042Y54000D01*
X774375Y54042D01*
X774708Y54250D01*
X774917Y54500D01*
X774958Y54750D01*
X774875Y55042D01*
X774583Y55250D01*
X774292Y55333D01*
X773917D01*
G01X774292D02*
X774542Y55458D01*
X774750Y55667D01*
X774833Y55917D01*
X774750Y56167D01*
X774542Y56375D01*
X774167Y56500D01*
X773792Y56458D01*
X773417Y56292D01*
G01X777100Y56500D02*
X776767Y56417D01*
X776517Y56208D01*
X776350Y55958D01*
X776225Y55625D01*
X776183Y55250D01*
X776225Y54875D01*
X776350Y54542D01*
X776517Y54292D01*
X776767Y54083D01*
X777100Y54000D01*
X777433Y54083D01*
X777683Y54292D01*
X777850Y54542D01*
X777975Y54875D01*
X778017Y55250D01*
X777975Y55625D01*
X777850Y55958D01*
X777683Y56208D01*
X777433Y56417D01*
X777100Y56500D01*
G01X779408Y55042D02*
X779700Y55333D01*
X779950Y55500D01*
X780283Y55583D01*
X780575Y55500D01*
X780783Y55333D01*
X780950Y55083D01*
X780992Y54792D01*
X780950Y54542D01*
X780783Y54292D01*
X780533Y54083D01*
X780242Y54000D01*
X779908Y54083D01*
X779617Y54333D01*
X779450Y54708D01*
X779408Y55125D01*
X779492Y55667D01*
X779617Y55958D01*
X779825Y56250D01*
X780117Y56458D01*
X780408Y56500D01*
X780700Y56417D01*
X780908Y56208D01*
G01X770017Y58000D02*
Y60500D01*
X771058D01*
X771392Y60375D01*
X771600Y60208D01*
X771683Y59875D01*
X771600Y59542D01*
X771350Y59333D01*
X771058Y59208D01*
X770017D01*
G01X771058D02*
X771683Y58000D01*
G01X773950D02*
Y60500D01*
X773450Y60000D01*
G01Y58000D02*
X774450D01*
G01X776342Y58292D02*
X776633Y58083D01*
X776967Y58000D01*
X777300Y58083D01*
X777592Y58333D01*
X777800Y58708D01*
X777883Y59083D01*
Y59542D01*
X777800Y59917D01*
X777592Y60250D01*
X777342Y60417D01*
X777050Y60500D01*
X776717Y60417D01*
X776467Y60250D01*
X776300Y60000D01*
X776217Y59667D01*
X776300Y59375D01*
X776508Y59083D01*
X776758Y58917D01*
X777050Y58875D01*
X777383Y58958D01*
X777633Y59167D01*
X777883Y59542D01*
G01X780150Y60500D02*
X779817Y60417D01*
X779567Y60208D01*
X779400Y59958D01*
X779275Y59625D01*
X779233Y59250D01*
X779275Y58875D01*
X779400Y58542D01*
X779567Y58292D01*
X779817Y58083D01*
X780150Y58000D01*
X780483Y58083D01*
X780733Y58292D01*
X780900Y58542D01*
X781025Y58875D01*
X781067Y59250D01*
X781025Y59625D01*
X780900Y59958D01*
X780733Y60208D01*
X780483Y60417D01*
X780150Y60500D01*
G01X766967Y62000D02*
Y64500D01*
X768008D01*
X768342Y64375D01*
X768550Y64208D01*
X768633Y63875D01*
X768550Y63542D01*
X768300Y63333D01*
X768008Y63208D01*
X766967D01*
G01X768008D02*
X768633Y62000D01*
G01X769983Y62375D02*
X770233Y62167D01*
X770525Y62042D01*
X770900Y62000D01*
X771275Y62083D01*
X771567Y62250D01*
X771775Y62542D01*
X771817Y62875D01*
X771733Y63208D01*
X771525Y63417D01*
X771233Y63583D01*
X770942Y63625D01*
X770650Y63583D01*
X770275Y63417D01*
X770400Y64500D01*
X771525D01*
G01X773083Y62500D02*
X773333Y62208D01*
X773667Y62042D01*
X774042Y62000D01*
X774375Y62042D01*
X774708Y62250D01*
X774917Y62500D01*
X774958Y62750D01*
X774875Y63042D01*
X774583Y63250D01*
X774292Y63333D01*
X773917D01*
G01X774292D02*
X774542Y63458D01*
X774750Y63667D01*
X774833Y63917D01*
X774750Y64167D01*
X774542Y64375D01*
X774167Y64500D01*
X773792Y64458D01*
X773417Y64292D01*
G01X777100Y64500D02*
X776767Y64417D01*
X776517Y64208D01*
X776350Y63958D01*
X776225Y63625D01*
X776183Y63250D01*
X776225Y62875D01*
X776350Y62542D01*
X776517Y62292D01*
X776767Y62083D01*
X777100Y62000D01*
X777433Y62083D01*
X777683Y62292D01*
X777850Y62542D01*
X777975Y62875D01*
X778017Y63250D01*
X777975Y63625D01*
X777850Y63958D01*
X777683Y64208D01*
X777433Y64417D01*
X777100Y64500D01*
G01X780117Y62000D02*
X780200Y62542D01*
X780325Y63000D01*
X780492Y63417D01*
X780700Y63875D01*
X781033Y64500D01*
X779367D01*
G01X771767Y68292D02*
X771517Y68417D01*
X771225Y68500D01*
X770892D01*
X770517Y68375D01*
X770225Y68167D01*
X770017Y67917D01*
X769850Y67500D01*
X769808Y67125D01*
X769892Y66750D01*
X770017Y66500D01*
X770267Y66250D01*
X770558Y66083D01*
X770850Y66000D01*
X771142D01*
X771433Y66083D01*
X771683Y66208D01*
X771892Y66375D01*
G01X773950Y66000D02*
Y68500D01*
X773450Y68000D01*
G01Y66000D02*
X774450D01*
G01X776133Y66375D02*
X776383Y66167D01*
X776675Y66042D01*
X777050Y66000D01*
X777425Y66083D01*
X777717Y66250D01*
X777925Y66542D01*
X777967Y66875D01*
X777883Y67208D01*
X777675Y67417D01*
X777383Y67583D01*
X777092Y67625D01*
X776800Y67583D01*
X776425Y67417D01*
X776550Y68500D01*
X777675D01*
G01X780150Y66000D02*
Y68500D01*
X779650Y68000D01*
G01Y66000D02*
X780650D01*
G01X763000Y90300D02*
X765500D01*
G01X763000Y89342D02*
Y91258D01*
G01X765500Y92567D02*
X763000D01*
Y93567D01*
X763125Y93900D01*
X763417Y94150D01*
X763750Y94233D01*
X764083Y94150D01*
X764333Y93942D01*
X764458Y93567D01*
Y92567D01*
G01X765500Y96500D02*
X763000D01*
X763500Y96000D01*
G01X765500D02*
Y97000D01*
G01X763417Y98808D02*
X763167Y99058D01*
X763042Y99350D01*
X763000Y99683D01*
X763083Y100100D01*
X763292Y100392D01*
X763542Y100475D01*
X763792Y100433D01*
X764000Y100267D01*
X764417Y99433D01*
X764708Y99058D01*
X765125Y98808D01*
X765500Y98725D01*
Y100475D01*
G01Y102617D02*
X764958Y102700D01*
X764500Y102825D01*
X764083Y102992D01*
X763625Y103200D01*
X763000Y103533D01*
Y101867D01*
G01X773017Y82500D02*
Y85000D01*
X774058D01*
X774392Y84875D01*
X774600Y84708D01*
X774683Y84375D01*
X774600Y84042D01*
X774350Y83833D01*
X774058Y83708D01*
X773017D01*
G01X774058D02*
X774683Y82500D01*
G01X776033Y83000D02*
X776283Y82708D01*
X776617Y82542D01*
X776992Y82500D01*
X777325Y82542D01*
X777658Y82750D01*
X777867Y83000D01*
X777908Y83250D01*
X777825Y83542D01*
X777533Y83750D01*
X777242Y83833D01*
X776867D01*
G01X777242D02*
X777492Y83958D01*
X777700Y84167D01*
X777783Y84417D01*
X777700Y84667D01*
X777492Y84875D01*
X777117Y85000D01*
X776742Y84958D01*
X776367Y84792D01*
G01X780050Y82500D02*
X780342Y82542D01*
X780675Y82667D01*
X780883Y82875D01*
X780967Y83167D01*
X780883Y83458D01*
X780633Y83708D01*
X780258Y83833D01*
X779842D01*
X779592Y83917D01*
X779383Y84125D01*
X779300Y84417D01*
X779425Y84708D01*
X779717Y84917D01*
X780050Y85000D01*
X780383Y84917D01*
X780675Y84708D01*
X780800Y84417D01*
X780717Y84125D01*
X780508Y83917D01*
X780258Y83833D01*
X779842D01*
X779467Y83708D01*
X779217Y83458D01*
X779133Y83167D01*
X779217Y82875D01*
X779425Y82667D01*
X779758Y82542D01*
X780050Y82500D01*
G01X783150Y85000D02*
X782817Y84917D01*
X782567Y84708D01*
X782400Y84458D01*
X782275Y84125D01*
X782233Y83750D01*
X782275Y83375D01*
X782400Y83042D01*
X782567Y82792D01*
X782817Y82583D01*
X783150Y82500D01*
X783483Y82583D01*
X783733Y82792D01*
X783900Y83042D01*
X784025Y83375D01*
X784067Y83750D01*
X784025Y84125D01*
X783900Y84458D01*
X783733Y84708D01*
X783483Y84917D01*
X783150Y85000D01*
G01X773017Y88500D02*
Y91000D01*
X774058D01*
X774392Y90875D01*
X774600Y90708D01*
X774683Y90375D01*
X774600Y90042D01*
X774350Y89833D01*
X774058Y89708D01*
X773017D01*
G01X774058D02*
X774683Y88500D01*
G01X776033Y89000D02*
X776283Y88708D01*
X776617Y88542D01*
X776992Y88500D01*
X777325Y88542D01*
X777658Y88750D01*
X777867Y89000D01*
X777908Y89250D01*
X777825Y89542D01*
X777533Y89750D01*
X777242Y89833D01*
X776867D01*
G01X777242D02*
X777492Y89958D01*
X777700Y90167D01*
X777783Y90417D01*
X777700Y90667D01*
X777492Y90875D01*
X777117Y91000D01*
X776742Y90958D01*
X776367Y90792D01*
G01X780050Y88500D02*
X780342Y88542D01*
X780675Y88667D01*
X780883Y88875D01*
X780967Y89167D01*
X780883Y89458D01*
X780633Y89708D01*
X780258Y89833D01*
X779842D01*
X779592Y89917D01*
X779383Y90125D01*
X779300Y90417D01*
X779425Y90708D01*
X779717Y90917D01*
X780050Y91000D01*
X780383Y90917D01*
X780675Y90708D01*
X780800Y90417D01*
X780717Y90125D01*
X780508Y89917D01*
X780258Y89833D01*
X779842D01*
X779467Y89708D01*
X779217Y89458D01*
X779133Y89167D01*
X779217Y88875D01*
X779425Y88667D01*
X779758Y88542D01*
X780050Y88500D01*
G01X783150D02*
Y91000D01*
X782650Y90500D01*
G01Y88500D02*
X783650D01*
G01X764000Y106300D02*
X766500D01*
G01X764000Y105342D02*
Y107258D01*
G01X766500Y108567D02*
X764000D01*
Y109567D01*
X764125Y109900D01*
X764417Y110150D01*
X764750Y110233D01*
X765083Y110150D01*
X765333Y109942D01*
X765458Y109567D01*
Y108567D01*
G01X766500Y112500D02*
X764000D01*
X764500Y112000D01*
G01X766500D02*
Y113000D01*
G01X764417Y114808D02*
X764167Y115058D01*
X764042Y115350D01*
X764000Y115683D01*
X764083Y116100D01*
X764292Y116392D01*
X764542Y116475D01*
X764792Y116433D01*
X765000Y116267D01*
X765417Y115433D01*
X765708Y115058D01*
X766125Y114808D01*
X766500Y114725D01*
Y116475D01*
G01X765458Y117908D02*
X765167Y118200D01*
X765000Y118450D01*
X764917Y118783D01*
X765000Y119075D01*
X765167Y119283D01*
X765417Y119450D01*
X765708Y119492D01*
X765958Y119450D01*
X766208Y119283D01*
X766417Y119033D01*
X766500Y118742D01*
X766417Y118408D01*
X766167Y118117D01*
X765792Y117950D01*
X765375Y117908D01*
X764833Y117992D01*
X764542Y118117D01*
X764250Y118325D01*
X764042Y118617D01*
X764000Y118908D01*
X764083Y119200D01*
X764292Y119408D01*
G01X773017Y94500D02*
Y97000D01*
X774058D01*
X774392Y96875D01*
X774600Y96708D01*
X774683Y96375D01*
X774600Y96042D01*
X774350Y95833D01*
X774058Y95708D01*
X773017D01*
G01X774058D02*
X774683Y94500D01*
G01X776033Y95000D02*
X776283Y94708D01*
X776617Y94542D01*
X776992Y94500D01*
X777325Y94542D01*
X777658Y94750D01*
X777867Y95000D01*
X777908Y95250D01*
X777825Y95542D01*
X777533Y95750D01*
X777242Y95833D01*
X776867D01*
G01X777242D02*
X777492Y95958D01*
X777700Y96167D01*
X777783Y96417D01*
X777700Y96667D01*
X777492Y96875D01*
X777117Y97000D01*
X776742Y96958D01*
X776367Y96792D01*
G01X779967Y94500D02*
X780050Y95042D01*
X780175Y95500D01*
X780342Y95917D01*
X780550Y96375D01*
X780883Y97000D01*
X779217D01*
G01X782233Y94875D02*
X782483Y94667D01*
X782775Y94542D01*
X783150Y94500D01*
X783525Y94583D01*
X783817Y94750D01*
X784025Y95042D01*
X784067Y95375D01*
X783983Y95708D01*
X783775Y95917D01*
X783483Y96083D01*
X783192Y96125D01*
X782900Y96083D01*
X782525Y95917D01*
X782650Y97000D01*
X783775D01*
G01X773017Y99500D02*
Y102000D01*
X774058D01*
X774392Y101875D01*
X774600Y101708D01*
X774683Y101375D01*
X774600Y101042D01*
X774350Y100833D01*
X774058Y100708D01*
X773017D01*
G01X774058D02*
X774683Y99500D01*
G01X776033Y100000D02*
X776283Y99708D01*
X776617Y99542D01*
X776992Y99500D01*
X777325Y99542D01*
X777658Y99750D01*
X777867Y100000D01*
X777908Y100250D01*
X777825Y100542D01*
X777533Y100750D01*
X777242Y100833D01*
X776867D01*
G01X777242D02*
X777492Y100958D01*
X777700Y101167D01*
X777783Y101417D01*
X777700Y101667D01*
X777492Y101875D01*
X777117Y102000D01*
X776742Y101958D01*
X776367Y101792D01*
G01X779967Y99500D02*
X780050Y100042D01*
X780175Y100500D01*
X780342Y100917D01*
X780550Y101375D01*
X780883Y102000D01*
X779217D01*
G01X782358Y100542D02*
X782650Y100833D01*
X782900Y101000D01*
X783233Y101083D01*
X783525Y101000D01*
X783733Y100833D01*
X783900Y100583D01*
X783942Y100292D01*
X783900Y100042D01*
X783733Y99792D01*
X783483Y99583D01*
X783192Y99500D01*
X782858Y99583D01*
X782567Y99833D01*
X782400Y100208D01*
X782358Y100625D01*
X782442Y101167D01*
X782567Y101458D01*
X782775Y101750D01*
X783067Y101958D01*
X783358Y102000D01*
X783650Y101917D01*
X783858Y101708D01*
G01X770233Y114284D02*
Y116784D01*
X771274D01*
X771608Y116659D01*
X771816Y116492D01*
X771899Y116159D01*
X771816Y115826D01*
X771566Y115617D01*
X771274Y115492D01*
X770233D01*
G01X771274D02*
X771899Y114284D01*
G01X773249Y114784D02*
X773499Y114492D01*
X773833Y114326D01*
X774208Y114284D01*
X774541Y114326D01*
X774874Y114534D01*
X775083Y114784D01*
X775124Y115034D01*
X775041Y115326D01*
X774749Y115534D01*
X774458Y115617D01*
X774083D01*
G01X774458D02*
X774708Y115742D01*
X774916Y115951D01*
X774999Y116201D01*
X774916Y116451D01*
X774708Y116659D01*
X774333Y116784D01*
X773958Y116742D01*
X773583Y116576D01*
G01X776558Y114576D02*
X776849Y114367D01*
X777183Y114284D01*
X777516Y114367D01*
X777808Y114617D01*
X778016Y114992D01*
X778099Y115367D01*
Y115826D01*
X778016Y116201D01*
X777808Y116534D01*
X777558Y116701D01*
X777266Y116784D01*
X776933Y116701D01*
X776683Y116534D01*
X776516Y116284D01*
X776433Y115951D01*
X776516Y115659D01*
X776724Y115367D01*
X776974Y115201D01*
X777266Y115159D01*
X777599Y115242D01*
X777849Y115451D01*
X778099Y115826D01*
G01X780866Y114284D02*
Y116784D01*
X779324Y114992D01*
X781408D01*
G01X770233Y109784D02*
Y112284D01*
X771274D01*
X771608Y112159D01*
X771816Y111992D01*
X771899Y111659D01*
X771816Y111326D01*
X771566Y111117D01*
X771274Y110992D01*
X770233D01*
G01X771274D02*
X771899Y109784D01*
G01X773249Y110284D02*
X773499Y109992D01*
X773833Y109826D01*
X774208Y109784D01*
X774541Y109826D01*
X774874Y110034D01*
X775083Y110284D01*
X775124Y110534D01*
X775041Y110826D01*
X774749Y111034D01*
X774458Y111117D01*
X774083D01*
G01X774458D02*
X774708Y111242D01*
X774916Y111451D01*
X774999Y111701D01*
X774916Y111951D01*
X774708Y112159D01*
X774333Y112284D01*
X773958Y112242D01*
X773583Y112076D01*
G01X777183Y109784D02*
X777266Y110326D01*
X777391Y110784D01*
X777558Y111201D01*
X777766Y111659D01*
X778099Y112284D01*
X776433D01*
G01X780283Y109784D02*
X780366Y110326D01*
X780491Y110784D01*
X780658Y111201D01*
X780866Y111659D01*
X781199Y112284D01*
X779533D01*
G01X772233Y123833D02*
X772400Y123958D01*
X772525Y124167D01*
X772608Y124458D01*
X772525Y124708D01*
X772358Y124875D01*
X772067Y125000D01*
X770942D01*
Y122500D01*
X772317D01*
X772608Y122667D01*
X772775Y122917D01*
X772858Y123208D01*
X772775Y123500D01*
X772525Y123750D01*
X772233Y123833D01*
X770942D01*
G01X775917Y124792D02*
X775667Y124917D01*
X775375Y125000D01*
X775042D01*
X774667Y124875D01*
X774375Y124667D01*
X774167Y124417D01*
X774000Y124000D01*
X773958Y123625D01*
X774042Y123250D01*
X774167Y123000D01*
X774417Y122750D01*
X774708Y122583D01*
X775000Y122500D01*
X775292D01*
X775583Y122583D01*
X775833Y122708D01*
X776042Y122875D01*
G01X777308Y124583D02*
X777558Y124833D01*
X777850Y124958D01*
X778183Y125000D01*
X778600Y124917D01*
X778892Y124708D01*
X778975Y124458D01*
X778933Y124208D01*
X778767Y124000D01*
X777933Y123583D01*
X777558Y123292D01*
X777308Y122875D01*
X777225Y122500D01*
X778975D01*
G01X769441Y137248D02*
Y139748D01*
X770482D01*
X770816Y139623D01*
X771024Y139456D01*
X771107Y139123D01*
X771024Y138790D01*
X770774Y138581D01*
X770482Y138456D01*
X769441D01*
G01X770482D02*
X771107Y137248D01*
G01X773874D02*
Y139748D01*
X772332Y137956D01*
X774416D01*
G01X775682Y138290D02*
X775974Y138581D01*
X776224Y138748D01*
X776557Y138831D01*
X776849Y138748D01*
X777057Y138581D01*
X777224Y138331D01*
X777266Y138040D01*
X777224Y137790D01*
X777057Y137540D01*
X776807Y137331D01*
X776516Y137248D01*
X776182Y137331D01*
X775891Y137581D01*
X775724Y137956D01*
X775682Y138373D01*
X775766Y138915D01*
X775891Y139206D01*
X776099Y139498D01*
X776391Y139706D01*
X776682Y139748D01*
X776974Y139665D01*
X777182Y139456D01*
G01X780074Y137248D02*
Y139748D01*
X778532Y137956D01*
X780616D01*
G01X768200Y136500D02*
Y140500D01*
X760800D01*
G01X769441Y132748D02*
Y135248D01*
X770482D01*
X770816Y135123D01*
X771024Y134956D01*
X771107Y134623D01*
X771024Y134290D01*
X770774Y134081D01*
X770482Y133956D01*
X769441D01*
G01X770482D02*
X771107Y132748D01*
G01X773874D02*
Y135248D01*
X772332Y133456D01*
X774416D01*
G01X775682Y133790D02*
X775974Y134081D01*
X776224Y134248D01*
X776557Y134331D01*
X776849Y134248D01*
X777057Y134081D01*
X777224Y133831D01*
X777266Y133540D01*
X777224Y133290D01*
X777057Y133040D01*
X776807Y132831D01*
X776516Y132748D01*
X776182Y132831D01*
X775891Y133081D01*
X775724Y133456D01*
X775682Y133873D01*
X775766Y134415D01*
X775891Y134706D01*
X776099Y134998D01*
X776391Y135206D01*
X776682Y135248D01*
X776974Y135165D01*
X777182Y134956D01*
G01X778657Y133248D02*
X778907Y132956D01*
X779241Y132790D01*
X779616Y132748D01*
X779949Y132790D01*
X780282Y132998D01*
X780491Y133248D01*
X780532Y133498D01*
X780449Y133790D01*
X780157Y133998D01*
X779866Y134081D01*
X779491D01*
G01X779866D02*
X780116Y134206D01*
X780324Y134415D01*
X780407Y134665D01*
X780324Y134915D01*
X780116Y135123D01*
X779741Y135248D01*
X779366Y135206D01*
X778991Y135040D01*
G01X768200Y132000D02*
Y136000D01*
X760800D01*
G01X769341Y143048D02*
Y145548D01*
X770382D01*
X770716Y145423D01*
X770924Y145256D01*
X771007Y144923D01*
X770924Y144590D01*
X770674Y144381D01*
X770382Y144256D01*
X769341D01*
G01X770382D02*
X771007Y143048D01*
G01X772482Y144090D02*
X772774Y144381D01*
X773024Y144548D01*
X773357Y144631D01*
X773649Y144548D01*
X773857Y144381D01*
X774024Y144131D01*
X774066Y143840D01*
X774024Y143590D01*
X773857Y143340D01*
X773607Y143131D01*
X773316Y143048D01*
X772982Y143131D01*
X772691Y143381D01*
X772524Y143756D01*
X772482Y144173D01*
X772566Y144715D01*
X772691Y145006D01*
X772899Y145298D01*
X773191Y145506D01*
X773482Y145548D01*
X773774Y145465D01*
X773982Y145256D01*
G01X775582Y145131D02*
X775832Y145381D01*
X776124Y145506D01*
X776457Y145548D01*
X776874Y145465D01*
X777166Y145256D01*
X777249Y145006D01*
X777207Y144756D01*
X777041Y144548D01*
X776207Y144131D01*
X775832Y143840D01*
X775582Y143423D01*
X775499Y143048D01*
X777249D01*
G01X779474Y145548D02*
X779141Y145465D01*
X778891Y145256D01*
X778724Y145006D01*
X778599Y144673D01*
X778557Y144298D01*
X778599Y143923D01*
X778724Y143590D01*
X778891Y143340D01*
X779141Y143131D01*
X779474Y143048D01*
X779807Y143131D01*
X780057Y143340D01*
X780224Y143590D01*
X780349Y143923D01*
X780391Y144298D01*
X780349Y144673D01*
X780224Y145006D01*
X780057Y145256D01*
X779807Y145465D01*
X779474Y145548D01*
G01X768100Y142300D02*
Y146300D01*
X760700D01*
G01X766216Y170234D02*
X766174Y169901D01*
X766008Y169609D01*
X765758Y169359D01*
X765466Y169192D01*
X765133Y169109D01*
X764799D01*
X764466Y169192D01*
X764174Y169359D01*
X763924Y169609D01*
X763758Y169901D01*
X763716Y170234D01*
X763758Y170567D01*
X763924Y170859D01*
X764174Y171109D01*
X764466Y171276D01*
X764799Y171359D01*
X765133D01*
X765466Y171276D01*
X765758Y171109D01*
X766008Y170859D01*
X766174Y170567D01*
X766216Y170234D01*
G01X765549Y170567D02*
X766216Y171067D01*
G01Y173251D02*
X765674Y173334D01*
X765216Y173459D01*
X764799Y173626D01*
X764341Y173834D01*
X763716Y174167D01*
Y172501D01*
G01X758716Y177284D02*
X772716D01*
G01X758716Y190284D02*
Y177284D01*
G01X772716D02*
Y190284D01*
G01D02*
X758716D01*
G01X765167Y331375D02*
X765375Y331708D01*
X765500Y332083D01*
Y332417D01*
X765375Y332750D01*
X765167Y333000D01*
X764875Y333125D01*
X764583Y333042D01*
X764333Y332833D01*
X764167Y332458D01*
X764083Y331958D01*
X763917Y331667D01*
X763625Y331542D01*
X763333Y331625D01*
X763125Y331833D01*
X763000Y332125D01*
Y332417D01*
X763083Y332708D01*
X763292Y332958D01*
G01X763208Y336267D02*
X763083Y336017D01*
X763000Y335725D01*
Y335392D01*
X763125Y335017D01*
X763333Y334725D01*
X763583Y334517D01*
X764000Y334350D01*
X764375Y334308D01*
X764750Y334392D01*
X765000Y334517D01*
X765250Y334767D01*
X765417Y335058D01*
X765500Y335350D01*
Y335642D01*
X765417Y335933D01*
X765292Y336183D01*
X765125Y336392D01*
G01X765500Y338450D02*
X763000D01*
X763500Y337950D01*
G01X765500D02*
Y338950D01*
G01Y341550D02*
X763000D01*
X763500Y341050D01*
G01X765500D02*
Y342050D01*
G01X765000Y343733D02*
X765292Y343983D01*
X765458Y344317D01*
X765500Y344692D01*
X765458Y345025D01*
X765250Y345358D01*
X765000Y345567D01*
X764750Y345608D01*
X764458Y345525D01*
X764250Y345233D01*
X764167Y344942D01*
Y344567D01*
G01Y344942D02*
X764042Y345192D01*
X763833Y345400D01*
X763583Y345483D01*
X763333Y345400D01*
X763125Y345192D01*
X763000Y344817D01*
X763042Y344442D01*
X763208Y344067D01*
G01X765500Y347750D02*
X763000D01*
X763500Y347250D01*
G01X765500D02*
Y348250D01*
G01X772624Y337048D02*
Y330848D01*
X785024D01*
Y337048D01*
G01X769991Y331423D02*
X770199Y331756D01*
X770324Y332131D01*
Y332465D01*
X770199Y332798D01*
X769991Y333048D01*
X769699Y333173D01*
X769407Y333090D01*
X769157Y332881D01*
X768991Y332506D01*
X768907Y332006D01*
X768741Y331715D01*
X768449Y331590D01*
X768157Y331673D01*
X767949Y331881D01*
X767824Y332173D01*
Y332465D01*
X767907Y332756D01*
X768116Y333006D01*
G01X768032Y336315D02*
X767907Y336065D01*
X767824Y335773D01*
Y335440D01*
X767949Y335065D01*
X768157Y334773D01*
X768407Y334565D01*
X768824Y334398D01*
X769199Y334356D01*
X769574Y334440D01*
X769824Y334565D01*
X770074Y334815D01*
X770241Y335106D01*
X770324Y335398D01*
Y335690D01*
X770241Y335981D01*
X770116Y336231D01*
X769949Y336440D01*
G01X770324Y338498D02*
X767824D01*
X768324Y337998D01*
G01X770324D02*
Y338998D01*
G01Y341598D02*
X767824D01*
X768324Y341098D01*
G01X770324D02*
Y342098D01*
G01X769824Y343781D02*
X770116Y344031D01*
X770282Y344365D01*
X770324Y344740D01*
X770282Y345073D01*
X770074Y345406D01*
X769824Y345615D01*
X769574Y345656D01*
X769282Y345573D01*
X769074Y345281D01*
X768991Y344990D01*
Y344615D01*
G01Y344990D02*
X768866Y345240D01*
X768657Y345448D01*
X768407Y345531D01*
X768157Y345448D01*
X767949Y345240D01*
X767824Y344865D01*
X767866Y344490D01*
X768032Y344115D01*
G01X768241Y347006D02*
X767991Y347256D01*
X767866Y347548D01*
X767824Y347881D01*
X767907Y348298D01*
X768116Y348590D01*
X768366Y348673D01*
X768616Y348631D01*
X768824Y348465D01*
X769241Y347631D01*
X769532Y347256D01*
X769949Y347006D01*
X770324Y346923D01*
Y348673D01*
G01X785024Y343048D02*
Y349248D01*
X772624D01*
Y343048D01*
G01X759467Y360500D02*
Y363000D01*
X760467D01*
X760800Y362875D01*
X761050Y362583D01*
X761133Y362250D01*
X761050Y361917D01*
X760842Y361667D01*
X760467Y361542D01*
X759467D01*
G01X764317Y362792D02*
X764067Y362917D01*
X763775Y363000D01*
X763442D01*
X763067Y362875D01*
X762775Y362667D01*
X762567Y362417D01*
X762400Y362000D01*
X762358Y361625D01*
X762442Y361250D01*
X762567Y361000D01*
X762817Y360750D01*
X763108Y360583D01*
X763400Y360500D01*
X763692D01*
X763983Y360583D01*
X764233Y360708D01*
X764442Y360875D01*
G01X765708Y362583D02*
X765958Y362833D01*
X766250Y362958D01*
X766583Y363000D01*
X767000Y362917D01*
X767292Y362708D01*
X767375Y362458D01*
X767333Y362208D01*
X767167Y362000D01*
X766333Y361583D01*
X765958Y361292D01*
X765708Y360875D01*
X765625Y360500D01*
X767375D01*
G01X768683Y361000D02*
X768933Y360708D01*
X769267Y360542D01*
X769642Y360500D01*
X769975Y360542D01*
X770308Y360750D01*
X770517Y361000D01*
X770558Y361250D01*
X770475Y361542D01*
X770183Y361750D01*
X769892Y361833D01*
X769517D01*
G01X769892D02*
X770142Y361958D01*
X770350Y362167D01*
X770433Y362417D01*
X770350Y362667D01*
X770142Y362875D01*
X769767Y363000D01*
X769392Y362958D01*
X769017Y362792D01*
G01X771783Y360875D02*
X772033Y360667D01*
X772325Y360542D01*
X772700Y360500D01*
X773075Y360583D01*
X773367Y360750D01*
X773575Y361042D01*
X773617Y361375D01*
X773533Y361708D01*
X773325Y361917D01*
X773033Y362083D01*
X772742Y362125D01*
X772450Y362083D01*
X772075Y361917D01*
X772200Y363000D01*
X773325D01*
G01X759467Y368500D02*
Y371000D01*
X760467D01*
X760800Y370875D01*
X761050Y370583D01*
X761133Y370250D01*
X761050Y369917D01*
X760842Y369667D01*
X760467Y369542D01*
X759467D01*
G01X764317Y370792D02*
X764067Y370917D01*
X763775Y371000D01*
X763442D01*
X763067Y370875D01*
X762775Y370667D01*
X762567Y370417D01*
X762400Y370000D01*
X762358Y369625D01*
X762442Y369250D01*
X762567Y369000D01*
X762817Y368750D01*
X763108Y368583D01*
X763400Y368500D01*
X763692D01*
X763983Y368583D01*
X764233Y368708D01*
X764442Y368875D01*
G01X765708Y370583D02*
X765958Y370833D01*
X766250Y370958D01*
X766583Y371000D01*
X767000Y370917D01*
X767292Y370708D01*
X767375Y370458D01*
X767333Y370208D01*
X767167Y370000D01*
X766333Y369583D01*
X765958Y369292D01*
X765708Y368875D01*
X765625Y368500D01*
X767375D01*
G01X768683Y369000D02*
X768933Y368708D01*
X769267Y368542D01*
X769642Y368500D01*
X769975Y368542D01*
X770308Y368750D01*
X770517Y369000D01*
X770558Y369250D01*
X770475Y369542D01*
X770183Y369750D01*
X769892Y369833D01*
X769517D01*
G01X769892D02*
X770142Y369958D01*
X770350Y370167D01*
X770433Y370417D01*
X770350Y370667D01*
X770142Y370875D01*
X769767Y371000D01*
X769392Y370958D01*
X769017Y370792D01*
G01X771908Y369542D02*
X772200Y369833D01*
X772450Y370000D01*
X772783Y370083D01*
X773075Y370000D01*
X773283Y369833D01*
X773450Y369583D01*
X773492Y369292D01*
X773450Y369042D01*
X773283Y368792D01*
X773033Y368583D01*
X772742Y368500D01*
X772408Y368583D01*
X772117Y368833D01*
X771950Y369208D01*
X771908Y369625D01*
X771992Y370167D01*
X772117Y370458D01*
X772325Y370750D01*
X772617Y370958D01*
X772908Y371000D01*
X773200Y370917D01*
X773408Y370708D01*
G01X761967Y354000D02*
Y356500D01*
X762967D01*
X763300Y356375D01*
X763550Y356083D01*
X763633Y355750D01*
X763550Y355417D01*
X763342Y355167D01*
X762967Y355042D01*
X761967D01*
G01X766817Y356292D02*
X766567Y356417D01*
X766275Y356500D01*
X765942D01*
X765567Y356375D01*
X765275Y356167D01*
X765067Y355917D01*
X764900Y355500D01*
X764858Y355125D01*
X764942Y354750D01*
X765067Y354500D01*
X765317Y354250D01*
X765608Y354083D01*
X765900Y354000D01*
X766192D01*
X766483Y354083D01*
X766733Y354208D01*
X766942Y354375D01*
G01X768208Y356083D02*
X768458Y356333D01*
X768750Y356458D01*
X769083Y356500D01*
X769500Y356417D01*
X769792Y356208D01*
X769875Y355958D01*
X769833Y355708D01*
X769667Y355500D01*
X768833Y355083D01*
X768458Y354792D01*
X768208Y354375D01*
X768125Y354000D01*
X769875D01*
G01X771183Y354500D02*
X771433Y354208D01*
X771767Y354042D01*
X772142Y354000D01*
X772475Y354042D01*
X772808Y354250D01*
X773017Y354500D01*
X773058Y354750D01*
X772975Y355042D01*
X772683Y355250D01*
X772392Y355333D01*
X772017D01*
G01X772392D02*
X772642Y355458D01*
X772850Y355667D01*
X772933Y355917D01*
X772850Y356167D01*
X772642Y356375D01*
X772267Y356500D01*
X771892Y356458D01*
X771517Y356292D01*
G01X775700Y354000D02*
Y356500D01*
X774158Y354708D01*
X776242D01*
G01X759467Y376500D02*
Y379000D01*
X760467D01*
X760800Y378875D01*
X761050Y378583D01*
X761133Y378250D01*
X761050Y377917D01*
X760842Y377667D01*
X760467Y377542D01*
X759467D01*
G01X764317Y378792D02*
X764067Y378917D01*
X763775Y379000D01*
X763442D01*
X763067Y378875D01*
X762775Y378667D01*
X762567Y378417D01*
X762400Y378000D01*
X762358Y377625D01*
X762442Y377250D01*
X762567Y377000D01*
X762817Y376750D01*
X763108Y376583D01*
X763400Y376500D01*
X763692D01*
X763983Y376583D01*
X764233Y376708D01*
X764442Y376875D01*
G01X765708Y378583D02*
X765958Y378833D01*
X766250Y378958D01*
X766583Y379000D01*
X767000Y378917D01*
X767292Y378708D01*
X767375Y378458D01*
X767333Y378208D01*
X767167Y378000D01*
X766333Y377583D01*
X765958Y377292D01*
X765708Y376875D01*
X765625Y376500D01*
X767375D01*
G01X768683Y377000D02*
X768933Y376708D01*
X769267Y376542D01*
X769642Y376500D01*
X769975Y376542D01*
X770308Y376750D01*
X770517Y377000D01*
X770558Y377250D01*
X770475Y377542D01*
X770183Y377750D01*
X769892Y377833D01*
X769517D01*
G01X769892D02*
X770142Y377958D01*
X770350Y378167D01*
X770433Y378417D01*
X770350Y378667D01*
X770142Y378875D01*
X769767Y379000D01*
X769392Y378958D01*
X769017Y378792D01*
G01X772617Y376500D02*
X772700Y377042D01*
X772825Y377500D01*
X772992Y377917D01*
X773200Y378375D01*
X773533Y379000D01*
X771867D01*
G01X759467Y384500D02*
Y387000D01*
X760467D01*
X760800Y386875D01*
X761050Y386583D01*
X761133Y386250D01*
X761050Y385917D01*
X760842Y385667D01*
X760467Y385542D01*
X759467D01*
G01X764317Y386792D02*
X764067Y386917D01*
X763775Y387000D01*
X763442D01*
X763067Y386875D01*
X762775Y386667D01*
X762567Y386417D01*
X762400Y386000D01*
X762358Y385625D01*
X762442Y385250D01*
X762567Y385000D01*
X762817Y384750D01*
X763108Y384583D01*
X763400Y384500D01*
X763692D01*
X763983Y384583D01*
X764233Y384708D01*
X764442Y384875D01*
G01X765708Y386583D02*
X765958Y386833D01*
X766250Y386958D01*
X766583Y387000D01*
X767000Y386917D01*
X767292Y386708D01*
X767375Y386458D01*
X767333Y386208D01*
X767167Y386000D01*
X766333Y385583D01*
X765958Y385292D01*
X765708Y384875D01*
X765625Y384500D01*
X767375D01*
G01X768683Y385000D02*
X768933Y384708D01*
X769267Y384542D01*
X769642Y384500D01*
X769975Y384542D01*
X770308Y384750D01*
X770517Y385000D01*
X770558Y385250D01*
X770475Y385542D01*
X770183Y385750D01*
X769892Y385833D01*
X769517D01*
G01X769892D02*
X770142Y385958D01*
X770350Y386167D01*
X770433Y386417D01*
X770350Y386667D01*
X770142Y386875D01*
X769767Y387000D01*
X769392Y386958D01*
X769017Y386792D01*
G01X772700Y384500D02*
X772992Y384542D01*
X773325Y384667D01*
X773533Y384875D01*
X773617Y385167D01*
X773533Y385458D01*
X773283Y385708D01*
X772908Y385833D01*
X772492D01*
X772242Y385917D01*
X772033Y386125D01*
X771950Y386417D01*
X772075Y386708D01*
X772367Y386917D01*
X772700Y387000D01*
X773033Y386917D01*
X773325Y386708D01*
X773450Y386417D01*
X773367Y386125D01*
X773158Y385917D01*
X772908Y385833D01*
X772492D01*
X772117Y385708D01*
X771867Y385458D01*
X771783Y385167D01*
X771867Y384875D01*
X772075Y384667D01*
X772408Y384542D01*
X772700Y384500D01*
G01X768000Y401017D02*
X765500D01*
Y402017D01*
X765625Y402350D01*
X765917Y402600D01*
X766250Y402683D01*
X766583Y402600D01*
X766833Y402392D01*
X766958Y402017D01*
Y401017D01*
G01X765500Y404117D02*
X768000D01*
Y405783D01*
G01Y408050D02*
X765500D01*
X766000Y407550D01*
G01X768000D02*
Y408550D01*
G01X765917Y410358D02*
X765667Y410608D01*
X765542Y410900D01*
X765500Y411233D01*
X765583Y411650D01*
X765792Y411942D01*
X766042Y412025D01*
X766292Y411983D01*
X766500Y411817D01*
X766917Y410983D01*
X767208Y410608D01*
X767625Y410358D01*
X768000Y410275D01*
Y412025D01*
G01X772500Y390800D02*
Y426200D01*
X800500D01*
Y390800D01*
X772500D01*
G01X769467Y432500D02*
Y435000D01*
X770467D01*
X770800Y434875D01*
X771050Y434583D01*
X771133Y434250D01*
X771050Y433917D01*
X770842Y433667D01*
X770467Y433542D01*
X769467D01*
G01X774317Y434792D02*
X774067Y434917D01*
X773775Y435000D01*
X773442D01*
X773067Y434875D01*
X772775Y434667D01*
X772567Y434417D01*
X772400Y434000D01*
X772358Y433625D01*
X772442Y433250D01*
X772567Y433000D01*
X772817Y432750D01*
X773108Y432583D01*
X773400Y432500D01*
X773692D01*
X773983Y432583D01*
X774233Y432708D01*
X774442Y432875D01*
G01X775708Y434583D02*
X775958Y434833D01*
X776250Y434958D01*
X776583Y435000D01*
X777000Y434917D01*
X777292Y434708D01*
X777375Y434458D01*
X777333Y434208D01*
X777167Y434000D01*
X776333Y433583D01*
X775958Y433292D01*
X775708Y432875D01*
X775625Y432500D01*
X777375D01*
G01X778808Y434583D02*
X779058Y434833D01*
X779350Y434958D01*
X779683Y435000D01*
X780100Y434917D01*
X780392Y434708D01*
X780475Y434458D01*
X780433Y434208D01*
X780267Y434000D01*
X779433Y433583D01*
X779058Y433292D01*
X778808Y432875D01*
X778725Y432500D01*
X780475D01*
G01X781992Y432792D02*
X782283Y432583D01*
X782617Y432500D01*
X782950Y432583D01*
X783242Y432833D01*
X783450Y433208D01*
X783533Y433583D01*
Y434042D01*
X783450Y434417D01*
X783242Y434750D01*
X782992Y434917D01*
X782700Y435000D01*
X782367Y434917D01*
X782117Y434750D01*
X781950Y434500D01*
X781867Y434167D01*
X781950Y433875D01*
X782158Y433583D01*
X782408Y433417D01*
X782700Y433375D01*
X783033Y433458D01*
X783283Y433667D01*
X783533Y434042D01*
G01X761074Y444578D02*
X768874D01*
G01X761074Y451578D02*
Y444578D01*
G01X768074D02*
X774474D01*
G01X761074Y451578D02*
X766274D01*
G01X774474D02*
X765774D01*
G01X760500Y455000D02*
Y468000D01*
G01X765000Y461200D02*
X761000D01*
Y453800D01*
G01X765000Y461800D02*
X769000D01*
Y469200D01*
G01Y461200D02*
X765000D01*
Y453800D01*
G01X757900Y479200D02*
Y486800D01*
G01X767517Y484000D02*
Y486500D01*
X768558D01*
X768892Y486375D01*
X769100Y486208D01*
X769183Y485875D01*
X769100Y485542D01*
X768850Y485333D01*
X768558Y485208D01*
X767517D01*
G01X768558D02*
X769183Y484000D01*
G01X770658Y485042D02*
X770950Y485333D01*
X771200Y485500D01*
X771533Y485583D01*
X771825Y485500D01*
X772033Y485333D01*
X772200Y485083D01*
X772242Y484792D01*
X772200Y484542D01*
X772033Y484292D01*
X771783Y484083D01*
X771492Y484000D01*
X771158Y484083D01*
X770867Y484333D01*
X770700Y484708D01*
X770658Y485125D01*
X770742Y485667D01*
X770867Y485958D01*
X771075Y486250D01*
X771367Y486458D01*
X771658Y486500D01*
X771950Y486417D01*
X772158Y486208D01*
G01X774550Y486500D02*
X774217Y486417D01*
X773967Y486208D01*
X773800Y485958D01*
X773675Y485625D01*
X773633Y485250D01*
X773675Y484875D01*
X773800Y484542D01*
X773967Y484292D01*
X774217Y484083D01*
X774550Y484000D01*
X774883Y484083D01*
X775133Y484292D01*
X775300Y484542D01*
X775425Y484875D01*
X775467Y485250D01*
X775425Y485625D01*
X775300Y485958D01*
X775133Y486208D01*
X774883Y486417D01*
X774550Y486500D01*
G01X777650Y484000D02*
Y486500D01*
X777150Y486000D01*
G01Y484000D02*
X778150D01*
G01X769000Y477200D02*
X765000D01*
Y469800D01*
G01X758500Y479300D02*
X762500D01*
Y486700D01*
G01X767517Y488500D02*
Y491000D01*
X768558D01*
X768892Y490875D01*
X769100Y490708D01*
X769183Y490375D01*
X769100Y490042D01*
X768850Y489833D01*
X768558Y489708D01*
X767517D01*
G01X768558D02*
X769183Y488500D01*
G01X770533Y488875D02*
X770783Y488667D01*
X771075Y488542D01*
X771450Y488500D01*
X771825Y488583D01*
X772117Y488750D01*
X772325Y489042D01*
X772367Y489375D01*
X772283Y489708D01*
X772075Y489917D01*
X771783Y490083D01*
X771492Y490125D01*
X771200Y490083D01*
X770825Y489917D01*
X770950Y491000D01*
X772075D01*
G01X773842Y488792D02*
X774133Y488583D01*
X774467Y488500D01*
X774800Y488583D01*
X775092Y488833D01*
X775300Y489208D01*
X775383Y489583D01*
Y490042D01*
X775300Y490417D01*
X775092Y490750D01*
X774842Y490917D01*
X774550Y491000D01*
X774217Y490917D01*
X773967Y490750D01*
X773800Y490500D01*
X773717Y490167D01*
X773800Y489875D01*
X774008Y489583D01*
X774258Y489417D01*
X774550Y489375D01*
X774883Y489458D01*
X775133Y489667D01*
X775383Y490042D01*
G01X776942Y488792D02*
X777233Y488583D01*
X777567Y488500D01*
X777900Y488583D01*
X778192Y488833D01*
X778400Y489208D01*
X778483Y489583D01*
Y490042D01*
X778400Y490417D01*
X778192Y490750D01*
X777942Y490917D01*
X777650Y491000D01*
X777317Y490917D01*
X777067Y490750D01*
X776900Y490500D01*
X776817Y490167D01*
X776900Y489875D01*
X777108Y489583D01*
X777358Y489417D01*
X777650Y489375D01*
X777983Y489458D01*
X778233Y489667D01*
X778483Y490042D01*
G01X759484Y545291D02*
X761284Y547391D01*
X763484Y545291D01*
G01X769794Y572768D02*
Y582968D01*
G01X774394Y572768D02*
X769794D01*
G01X764475Y586833D02*
X764808Y586625D01*
X765183Y586500D01*
X765517D01*
X765850Y586625D01*
X766100Y586833D01*
X766225Y587125D01*
X766142Y587417D01*
X765933Y587667D01*
X765558Y587833D01*
X765058Y587917D01*
X764767Y588083D01*
X764642Y588375D01*
X764725Y588667D01*
X764933Y588875D01*
X765225Y589000D01*
X765517D01*
X765808Y588917D01*
X766058Y588708D01*
G01X767533Y589000D02*
Y587208D01*
X767700Y586833D01*
X768033Y586583D01*
X768450Y586500D01*
X768867Y586583D01*
X769200Y586833D01*
X769367Y587208D01*
Y589000D01*
G01X770758Y587542D02*
X771050Y587833D01*
X771300Y588000D01*
X771633Y588083D01*
X771925Y588000D01*
X772133Y587833D01*
X772300Y587583D01*
X772342Y587292D01*
X772300Y587042D01*
X772133Y586792D01*
X771883Y586583D01*
X771592Y586500D01*
X771258Y586583D01*
X770967Y586833D01*
X770800Y587208D01*
X770758Y587625D01*
X770842Y588167D01*
X770967Y588458D01*
X771175Y588750D01*
X771467Y588958D01*
X771758Y589000D01*
X772050Y588917D01*
X772258Y588708D01*
G01X774650Y586500D02*
X774942Y586542D01*
X775275Y586667D01*
X775483Y586875D01*
X775567Y587167D01*
X775483Y587458D01*
X775233Y587708D01*
X774858Y587833D01*
X774442D01*
X774192Y587917D01*
X773983Y588125D01*
X773900Y588417D01*
X774025Y588708D01*
X774317Y588917D01*
X774650Y589000D01*
X774983Y588917D01*
X775275Y588708D01*
X775400Y588417D01*
X775317Y588125D01*
X775108Y587917D01*
X774858Y587833D01*
X774442D01*
X774067Y587708D01*
X773817Y587458D01*
X773733Y587167D01*
X773817Y586875D01*
X774025Y586667D01*
X774358Y586542D01*
X774650Y586500D01*
G01X774394Y583668D02*
X763094D01*
G01X772094Y582468D02*
X773294Y583668D01*
G01X772094Y582468D02*
X770894Y583668D01*
G01X771517Y638000D02*
Y640500D01*
X772558D01*
X772892Y640375D01*
X773100Y640208D01*
X773183Y639875D01*
X773100Y639542D01*
X772850Y639333D01*
X772558Y639208D01*
X771517D01*
G01X772558D02*
X773183Y638000D01*
G01X774533Y638375D02*
X774783Y638167D01*
X775075Y638042D01*
X775450Y638000D01*
X775825Y638083D01*
X776117Y638250D01*
X776325Y638542D01*
X776367Y638875D01*
X776283Y639208D01*
X776075Y639417D01*
X775783Y639583D01*
X775492Y639625D01*
X775200Y639583D01*
X774825Y639417D01*
X774950Y640500D01*
X776075D01*
G01X778467Y638000D02*
X778550Y638542D01*
X778675Y639000D01*
X778842Y639417D01*
X779050Y639875D01*
X779383Y640500D01*
X777717D01*
G01X780942Y638292D02*
X781233Y638083D01*
X781567Y638000D01*
X781900Y638083D01*
X782192Y638333D01*
X782400Y638708D01*
X782483Y639083D01*
Y639542D01*
X782400Y639917D01*
X782192Y640250D01*
X781942Y640417D01*
X781650Y640500D01*
X781317Y640417D01*
X781067Y640250D01*
X780900Y640000D01*
X780817Y639667D01*
X780900Y639375D01*
X781108Y639083D01*
X781358Y638917D01*
X781650Y638875D01*
X781983Y638958D01*
X782233Y639167D01*
X782483Y639542D01*
G01X771517Y633500D02*
Y636000D01*
X772558D01*
X772892Y635875D01*
X773100Y635708D01*
X773183Y635375D01*
X773100Y635042D01*
X772850Y634833D01*
X772558Y634708D01*
X771517D01*
G01X772558D02*
X773183Y633500D01*
G01X774533Y633875D02*
X774783Y633667D01*
X775075Y633542D01*
X775450Y633500D01*
X775825Y633583D01*
X776117Y633750D01*
X776325Y634042D01*
X776367Y634375D01*
X776283Y634708D01*
X776075Y634917D01*
X775783Y635083D01*
X775492Y635125D01*
X775200Y635083D01*
X774825Y634917D01*
X774950Y636000D01*
X776075D01*
G01X778467Y633500D02*
X778550Y634042D01*
X778675Y634500D01*
X778842Y634917D01*
X779050Y635375D01*
X779383Y636000D01*
X777717D01*
G01X780858Y634542D02*
X781150Y634833D01*
X781400Y635000D01*
X781733Y635083D01*
X782025Y635000D01*
X782233Y634833D01*
X782400Y634583D01*
X782442Y634292D01*
X782400Y634042D01*
X782233Y633792D01*
X781983Y633583D01*
X781692Y633500D01*
X781358Y633583D01*
X781067Y633833D01*
X780900Y634208D01*
X780858Y634625D01*
X780942Y635167D01*
X781067Y635458D01*
X781275Y635750D01*
X781567Y635958D01*
X781858Y636000D01*
X782150Y635917D01*
X782358Y635708D01*
G01X772284Y652032D02*
X786284D01*
G01X772284Y665032D02*
Y652032D01*
G01X770500Y650000D02*
Y664000D01*
G01X757500Y650000D02*
X770500D01*
G01X757500Y664000D02*
Y650000D01*
G01X770500Y664000D02*
X757500D01*
G01X786284Y665032D02*
X772284D01*
G01X766800Y670000D02*
Y666000D01*
X774200D01*
G01X770000Y692000D02*
Y705000D01*
G01X767500Y681900D02*
X767458Y681567D01*
X767292Y681275D01*
X767042Y681025D01*
X766750Y680858D01*
X766417Y680775D01*
X766083D01*
X765750Y680858D01*
X765458Y681025D01*
X765208Y681275D01*
X765042Y681567D01*
X765000Y681900D01*
X765042Y682233D01*
X765208Y682525D01*
X765458Y682775D01*
X765750Y682942D01*
X766083Y683025D01*
X766417D01*
X766750Y682942D01*
X767042Y682775D01*
X767292Y682525D01*
X767458Y682233D01*
X767500Y681900D01*
G01X766833Y682233D02*
X767500Y682733D01*
G01Y685000D02*
X765000D01*
X765500Y684500D01*
G01X767500D02*
Y685500D01*
G01X765000Y688100D02*
X765083Y687767D01*
X765292Y687517D01*
X765542Y687350D01*
X765875Y687225D01*
X766250Y687183D01*
X766625Y687225D01*
X766958Y687350D01*
X767208Y687517D01*
X767417Y687767D01*
X767500Y688100D01*
X767417Y688433D01*
X767208Y688683D01*
X766958Y688850D01*
X766625Y688975D01*
X766250Y689017D01*
X765875Y688975D01*
X765542Y688850D01*
X765292Y688683D01*
X765083Y688433D01*
X765000Y688100D01*
G01X771798Y682354D02*
X783198D01*
G01X771798Y695754D02*
Y682354D01*
G01X783198Y695754D02*
X771798D01*
G01X767998Y713254D02*
X763998D01*
Y705854D01*
G01X772498Y713254D02*
X768498D01*
Y705854D01*
G01X766998Y716571D02*
X764498D01*
Y717612D01*
X764623Y717946D01*
X764790Y718154D01*
X765123Y718237D01*
X765456Y718154D01*
X765665Y717904D01*
X765790Y717612D01*
Y716571D01*
G01Y717612D02*
X766998Y718237D01*
G01Y721004D02*
X764498D01*
X766290Y719462D01*
Y721546D01*
G01X766998Y723604D02*
X766956Y723896D01*
X766831Y724229D01*
X766623Y724437D01*
X766331Y724521D01*
X766040Y724437D01*
X765790Y724187D01*
X765665Y723812D01*
Y723396D01*
X765581Y723146D01*
X765373Y722937D01*
X765081Y722854D01*
X764790Y722979D01*
X764581Y723271D01*
X764498Y723604D01*
X764581Y723937D01*
X764790Y724229D01*
X765081Y724354D01*
X765373Y724271D01*
X765581Y724062D01*
X765665Y723812D01*
Y723396D01*
X765790Y723021D01*
X766040Y722771D01*
X766331Y722687D01*
X766623Y722771D01*
X766831Y722979D01*
X766956Y723312D01*
X766998Y723604D01*
G01X766498Y725787D02*
X766790Y726037D01*
X766956Y726371D01*
X766998Y726746D01*
X766956Y727079D01*
X766748Y727412D01*
X766498Y727621D01*
X766248Y727662D01*
X765956Y727579D01*
X765748Y727287D01*
X765665Y726996D01*
Y726621D01*
G01Y726996D02*
X765540Y727246D01*
X765331Y727454D01*
X765081Y727537D01*
X764831Y727454D01*
X764623Y727246D01*
X764498Y726871D01*
X764540Y726496D01*
X764706Y726121D01*
G01X771498Y716571D02*
X768998D01*
Y717612D01*
X769123Y717946D01*
X769290Y718154D01*
X769623Y718237D01*
X769956Y718154D01*
X770165Y717904D01*
X770290Y717612D01*
Y716571D01*
G01Y717612D02*
X771498Y718237D01*
G01Y721004D02*
X768998D01*
X770790Y719462D01*
Y721546D01*
G01X771498Y723604D02*
X771456Y723896D01*
X771331Y724229D01*
X771123Y724437D01*
X770831Y724521D01*
X770540Y724437D01*
X770290Y724187D01*
X770165Y723812D01*
Y723396D01*
X770081Y723146D01*
X769873Y722937D01*
X769581Y722854D01*
X769290Y722979D01*
X769081Y723271D01*
X768998Y723604D01*
X769081Y723937D01*
X769290Y724229D01*
X769581Y724354D01*
X769873Y724271D01*
X770081Y724062D01*
X770165Y723812D01*
Y723396D01*
X770290Y723021D01*
X770540Y722771D01*
X770831Y722687D01*
X771123Y722771D01*
X771331Y722979D01*
X771456Y723312D01*
X771498Y723604D01*
G01X769415Y725912D02*
X769165Y726162D01*
X769040Y726454D01*
X768998Y726787D01*
X769081Y727204D01*
X769290Y727496D01*
X769540Y727579D01*
X769790Y727537D01*
X769998Y727371D01*
X770415Y726537D01*
X770706Y726162D01*
X771123Y725912D01*
X771498Y725829D01*
Y727579D01*
G01X764800Y860000D02*
Y856000D01*
X772200D01*
G01X764800Y855500D02*
Y851500D01*
X772200D01*
G01X787517Y82500D02*
Y85000D01*
X788558D01*
X788892Y84875D01*
X789100Y84708D01*
X789183Y84375D01*
X789100Y84042D01*
X788850Y83833D01*
X788558Y83708D01*
X787517D01*
G01X788558D02*
X789183Y82500D01*
G01X790658Y83542D02*
X790950Y83833D01*
X791200Y84000D01*
X791533Y84083D01*
X791825Y84000D01*
X792033Y83833D01*
X792200Y83583D01*
X792242Y83292D01*
X792200Y83042D01*
X792033Y82792D01*
X791783Y82583D01*
X791492Y82500D01*
X791158Y82583D01*
X790867Y82833D01*
X790700Y83208D01*
X790658Y83625D01*
X790742Y84167D01*
X790867Y84458D01*
X791075Y84750D01*
X791367Y84958D01*
X791658Y85000D01*
X791950Y84917D01*
X792158Y84708D01*
G01X794550Y82500D02*
X794842Y82542D01*
X795175Y82667D01*
X795383Y82875D01*
X795467Y83167D01*
X795383Y83458D01*
X795133Y83708D01*
X794758Y83833D01*
X794342D01*
X794092Y83917D01*
X793883Y84125D01*
X793800Y84417D01*
X793925Y84708D01*
X794217Y84917D01*
X794550Y85000D01*
X794883Y84917D01*
X795175Y84708D01*
X795300Y84417D01*
X795217Y84125D01*
X795008Y83917D01*
X794758Y83833D01*
X794342D01*
X793967Y83708D01*
X793717Y83458D01*
X793633Y83167D01*
X793717Y82875D01*
X793925Y82667D01*
X794258Y82542D01*
X794550Y82500D01*
G01X797567D02*
X797650Y83042D01*
X797775Y83500D01*
X797942Y83917D01*
X798150Y84375D01*
X798483Y85000D01*
X796817D01*
G01X787517Y88500D02*
Y91000D01*
X788558D01*
X788892Y90875D01*
X789100Y90708D01*
X789183Y90375D01*
X789100Y90042D01*
X788850Y89833D01*
X788558Y89708D01*
X787517D01*
G01X788558D02*
X789183Y88500D01*
G01X790658Y89542D02*
X790950Y89833D01*
X791200Y90000D01*
X791533Y90083D01*
X791825Y90000D01*
X792033Y89833D01*
X792200Y89583D01*
X792242Y89292D01*
X792200Y89042D01*
X792033Y88792D01*
X791783Y88583D01*
X791492Y88500D01*
X791158Y88583D01*
X790867Y88833D01*
X790700Y89208D01*
X790658Y89625D01*
X790742Y90167D01*
X790867Y90458D01*
X791075Y90750D01*
X791367Y90958D01*
X791658Y91000D01*
X791950Y90917D01*
X792158Y90708D01*
G01X795050Y88500D02*
Y91000D01*
X793508Y89208D01*
X795592D01*
G01X796858Y89542D02*
X797150Y89833D01*
X797400Y90000D01*
X797733Y90083D01*
X798025Y90000D01*
X798233Y89833D01*
X798400Y89583D01*
X798442Y89292D01*
X798400Y89042D01*
X798233Y88792D01*
X797983Y88583D01*
X797692Y88500D01*
X797358Y88583D01*
X797067Y88833D01*
X796900Y89208D01*
X796858Y89625D01*
X796942Y90167D01*
X797067Y90458D01*
X797275Y90750D01*
X797567Y90958D01*
X797858Y91000D01*
X798150Y90917D01*
X798358Y90708D01*
G01X787517Y94500D02*
Y97000D01*
X788558D01*
X788892Y96875D01*
X789100Y96708D01*
X789183Y96375D01*
X789100Y96042D01*
X788850Y95833D01*
X788558Y95708D01*
X787517D01*
G01X788558D02*
X789183Y94500D01*
G01X791950D02*
Y97000D01*
X790408Y95208D01*
X792492D01*
G01X795050Y94500D02*
Y97000D01*
X793508Y95208D01*
X795592D01*
G01X798150Y94500D02*
Y97000D01*
X796608Y95208D01*
X798692D01*
G01X787517Y99500D02*
Y102000D01*
X788558D01*
X788892Y101875D01*
X789100Y101708D01*
X789183Y101375D01*
X789100Y101042D01*
X788850Y100833D01*
X788558Y100708D01*
X787517D01*
G01X788558D02*
X789183Y99500D01*
G01X791950D02*
Y102000D01*
X790408Y100208D01*
X792492D01*
G01X795050Y99500D02*
Y102000D01*
X793508Y100208D01*
X795592D01*
G01X796858Y101583D02*
X797108Y101833D01*
X797400Y101958D01*
X797733Y102000D01*
X798150Y101917D01*
X798442Y101708D01*
X798525Y101458D01*
X798483Y101208D01*
X798317Y101000D01*
X797483Y100583D01*
X797108Y100292D01*
X796858Y99875D01*
X796775Y99500D01*
X798525D01*
G01X776248Y165017D02*
X773748D01*
Y166058D01*
X773873Y166392D01*
X774040Y166600D01*
X774373Y166683D01*
X774706Y166600D01*
X774915Y166350D01*
X775040Y166058D01*
Y165017D01*
G01Y166058D02*
X776248Y166683D01*
G01X775873Y168033D02*
X776081Y168283D01*
X776206Y168575D01*
X776248Y168950D01*
X776165Y169325D01*
X775998Y169617D01*
X775706Y169825D01*
X775373Y169867D01*
X775040Y169783D01*
X774831Y169575D01*
X774665Y169283D01*
X774623Y168992D01*
X774665Y168700D01*
X774831Y168325D01*
X773748Y168450D01*
Y169575D01*
G01X774165Y171258D02*
X773915Y171508D01*
X773790Y171800D01*
X773748Y172133D01*
X773831Y172550D01*
X774040Y172842D01*
X774290Y172925D01*
X774540Y172883D01*
X774748Y172717D01*
X775165Y171883D01*
X775456Y171508D01*
X775873Y171258D01*
X776248Y171175D01*
Y172925D01*
G01Y175150D02*
X773748D01*
X774248Y174650D01*
G01X776248D02*
Y175650D01*
G01X773748Y178800D02*
X777748D01*
Y186200D01*
G01X780372Y283792D02*
X780122Y283917D01*
X779830Y284000D01*
X779497D01*
X779122Y283875D01*
X778830Y283667D01*
X778622Y283417D01*
X778455Y283000D01*
X778413Y282625D01*
X778497Y282250D01*
X778622Y282000D01*
X778872Y281750D01*
X779163Y281583D01*
X779455Y281500D01*
X779747D01*
X780038Y281583D01*
X780288Y281708D01*
X780497Y281875D01*
G01X781597Y281500D02*
Y284000D01*
X783513Y281500D01*
Y284000D01*
G01X785655Y281500D02*
X785947Y281542D01*
X786280Y281667D01*
X786488Y281875D01*
X786572Y282167D01*
X786488Y282458D01*
X786238Y282708D01*
X785863Y282833D01*
X785447D01*
X785197Y282917D01*
X784988Y283125D01*
X784905Y283417D01*
X785030Y283708D01*
X785322Y283917D01*
X785655Y284000D01*
X785988Y283917D01*
X786280Y283708D01*
X786405Y283417D01*
X786322Y283125D01*
X786113Y282917D01*
X785863Y282833D01*
X785447D01*
X785072Y282708D01*
X784822Y282458D01*
X784738Y282167D01*
X784822Y281875D01*
X785030Y281667D01*
X785363Y281542D01*
X785655Y281500D01*
G01X786124Y337048D02*
Y330848D01*
X798524D01*
Y337048D01*
G01Y343048D02*
Y349248D01*
X786124D01*
Y343048D01*
G01X776874Y446178D02*
Y441178D01*
X781874D01*
G01X785790Y442172D02*
Y439172D01*
G01X774474Y444578D02*
Y451578D01*
G01X778967Y463500D02*
Y466000D01*
X779967D01*
X780300Y465875D01*
X780550Y465583D01*
X780633Y465250D01*
X780550Y464917D01*
X780342Y464667D01*
X779967Y464542D01*
X778967D01*
G01X781983Y466000D02*
Y464208D01*
X782150Y463833D01*
X782483Y463583D01*
X782900Y463500D01*
X783317Y463583D01*
X783650Y463833D01*
X783817Y464208D01*
Y466000D01*
G01X786000Y463500D02*
Y466000D01*
X785500Y465500D01*
G01Y463500D02*
X786500D01*
G01X789100Y466000D02*
X788767Y465917D01*
X788517Y465708D01*
X788350Y465458D01*
X788225Y465125D01*
X788183Y464750D01*
X788225Y464375D01*
X788350Y464042D01*
X788517Y463792D01*
X788767Y463583D01*
X789100Y463500D01*
X789433Y463583D01*
X789683Y463792D01*
X789850Y464042D01*
X789975Y464375D01*
X790017Y464750D01*
X789975Y465125D01*
X789850Y465458D01*
X789683Y465708D01*
X789433Y465917D01*
X789100Y466000D01*
G01X792200D02*
X791867Y465917D01*
X791617Y465708D01*
X791450Y465458D01*
X791325Y465125D01*
X791283Y464750D01*
X791325Y464375D01*
X791450Y464042D01*
X791617Y463792D01*
X791867Y463583D01*
X792200Y463500D01*
X792533Y463583D01*
X792783Y463792D01*
X792950Y464042D01*
X793075Y464375D01*
X793117Y464750D01*
X793075Y465125D01*
X792950Y465458D01*
X792783Y465708D01*
X792533Y465917D01*
X792200Y466000D01*
G01X781874Y460978D02*
X776874D01*
Y455978D01*
G01X777868Y454031D02*
X775868D01*
G01X790774Y480778D02*
X786774D01*
Y473378D01*
G01X781774Y480778D02*
X777774D01*
Y473378D01*
G01X787500Y487917D02*
X785000D01*
Y488917D01*
X785125Y489250D01*
X785417Y489500D01*
X785750Y489583D01*
X786083Y489500D01*
X786333Y489292D01*
X786458Y488917D01*
Y487917D01*
G01X787500Y491017D02*
X785000D01*
Y492058D01*
X785125Y492392D01*
X785292Y492600D01*
X785625Y492683D01*
X785958Y492600D01*
X786167Y492350D01*
X786292Y492058D01*
Y491017D01*
G01Y492058D02*
X787500Y492683D01*
G01X787208Y494242D02*
X787417Y494533D01*
X787500Y494867D01*
X787417Y495200D01*
X787167Y495492D01*
X786792Y495700D01*
X786417Y495783D01*
X785958D01*
X785583Y495700D01*
X785250Y495492D01*
X785083Y495242D01*
X785000Y494950D01*
X785083Y494617D01*
X785250Y494367D01*
X785500Y494200D01*
X785833Y494117D01*
X786125Y494200D01*
X786417Y494408D01*
X786583Y494658D01*
X786625Y494950D01*
X786542Y495283D01*
X786333Y495533D01*
X785958Y495783D01*
G01X785000Y498050D02*
X785083Y497717D01*
X785292Y497467D01*
X785542Y497300D01*
X785875Y497175D01*
X786250Y497133D01*
X786625Y497175D01*
X786958Y497300D01*
X787208Y497467D01*
X787417Y497717D01*
X787500Y498050D01*
X787417Y498383D01*
X787208Y498633D01*
X786958Y498800D01*
X786625Y498925D01*
X786250Y498967D01*
X785875Y498925D01*
X785542Y498800D01*
X785292Y498633D01*
X785083Y498383D01*
X785000Y498050D01*
G01X787500Y501150D02*
X785000D01*
X785500Y500650D01*
G01X787500D02*
Y501650D01*
G01Y504167D02*
X786958Y504250D01*
X786500Y504375D01*
X786083Y504542D01*
X785625Y504750D01*
X785000Y505083D01*
Y503417D01*
G01X792000Y487967D02*
X789500D01*
Y488967D01*
X789625Y489300D01*
X789917Y489550D01*
X790250Y489633D01*
X790583Y489550D01*
X790833Y489342D01*
X790958Y488967D01*
Y487967D01*
G01X789708Y492817D02*
X789583Y492567D01*
X789500Y492275D01*
Y491942D01*
X789625Y491567D01*
X789833Y491275D01*
X790083Y491067D01*
X790500Y490900D01*
X790875Y490858D01*
X791250Y490942D01*
X791500Y491067D01*
X791750Y491317D01*
X791917Y491608D01*
X792000Y491900D01*
Y492192D01*
X791917Y492483D01*
X791792Y492733D01*
X791625Y492942D01*
G01X789917Y494208D02*
X789667Y494458D01*
X789542Y494750D01*
X789500Y495083D01*
X789583Y495500D01*
X789792Y495792D01*
X790042Y495875D01*
X790292Y495833D01*
X790500Y495667D01*
X790917Y494833D01*
X791208Y494458D01*
X791625Y494208D01*
X792000Y494125D01*
Y495875D01*
G01X791500Y497183D02*
X791792Y497433D01*
X791958Y497767D01*
X792000Y498142D01*
X791958Y498475D01*
X791750Y498808D01*
X791500Y499017D01*
X791250Y499058D01*
X790958Y498975D01*
X790750Y498683D01*
X790667Y498392D01*
Y498017D01*
G01Y498392D02*
X790542Y498642D01*
X790333Y498850D01*
X790083Y498933D01*
X789833Y498850D01*
X789625Y498642D01*
X789500Y498267D01*
X789542Y497892D01*
X789708Y497517D01*
G01X789917Y500408D02*
X789667Y500658D01*
X789542Y500950D01*
X789500Y501283D01*
X789583Y501700D01*
X789792Y501992D01*
X790042Y502075D01*
X790292Y502033D01*
X790500Y501867D01*
X790917Y501033D01*
X791208Y500658D01*
X791625Y500408D01*
X792000Y500325D01*
Y502075D01*
G01X783500Y487967D02*
X781000D01*
Y488967D01*
X781125Y489300D01*
X781417Y489550D01*
X781750Y489633D01*
X782083Y489550D01*
X782333Y489342D01*
X782458Y488967D01*
Y487967D01*
G01X781208Y492817D02*
X781083Y492567D01*
X781000Y492275D01*
Y491942D01*
X781125Y491567D01*
X781333Y491275D01*
X781583Y491067D01*
X782000Y490900D01*
X782375Y490858D01*
X782750Y490942D01*
X783000Y491067D01*
X783250Y491317D01*
X783417Y491608D01*
X783500Y491900D01*
Y492192D01*
X783417Y492483D01*
X783292Y492733D01*
X783125Y492942D01*
G01X781417Y494208D02*
X781167Y494458D01*
X781042Y494750D01*
X781000Y495083D01*
X781083Y495500D01*
X781292Y495792D01*
X781542Y495875D01*
X781792Y495833D01*
X782000Y495667D01*
X782417Y494833D01*
X782708Y494458D01*
X783125Y494208D01*
X783500Y494125D01*
Y495875D01*
G01X783000Y497183D02*
X783292Y497433D01*
X783458Y497767D01*
X783500Y498142D01*
X783458Y498475D01*
X783250Y498808D01*
X783000Y499017D01*
X782750Y499058D01*
X782458Y498975D01*
X782250Y498683D01*
X782167Y498392D01*
Y498017D01*
G01Y498392D02*
X782042Y498642D01*
X781833Y498850D01*
X781583Y498933D01*
X781333Y498850D01*
X781125Y498642D01*
X781000Y498267D01*
X781042Y497892D01*
X781208Y497517D01*
G01X781000Y501200D02*
X781083Y500867D01*
X781292Y500617D01*
X781542Y500450D01*
X781875Y500325D01*
X782250Y500283D01*
X782625Y500325D01*
X782958Y500450D01*
X783208Y500617D01*
X783417Y500867D01*
X783500Y501200D01*
X783417Y501533D01*
X783208Y501783D01*
X782958Y501950D01*
X782625Y502075D01*
X782250Y502117D01*
X781875Y502075D01*
X781542Y501950D01*
X781292Y501783D01*
X781083Y501533D01*
X781000Y501200D01*
G01X775925Y531833D02*
X776258Y531625D01*
X776633Y531500D01*
X776967D01*
X777300Y531625D01*
X777550Y531833D01*
X777675Y532125D01*
X777592Y532417D01*
X777383Y532667D01*
X777008Y532833D01*
X776508Y532917D01*
X776217Y533083D01*
X776092Y533375D01*
X776175Y533667D01*
X776383Y533875D01*
X776675Y534000D01*
X776967D01*
X777258Y533917D01*
X777508Y533708D01*
G01X779067Y531500D02*
Y534000D01*
X780108D01*
X780442Y533875D01*
X780650Y533708D01*
X780733Y533375D01*
X780650Y533042D01*
X780400Y532833D01*
X780108Y532708D01*
X779067D01*
G01X780108D02*
X780733Y531500D01*
G01X782917D02*
X783000Y532042D01*
X783125Y532500D01*
X783292Y532917D01*
X783500Y533375D01*
X783833Y534000D01*
X782167D01*
G01X785308Y532542D02*
X785600Y532833D01*
X785850Y533000D01*
X786183Y533083D01*
X786475Y533000D01*
X786683Y532833D01*
X786850Y532583D01*
X786892Y532292D01*
X786850Y532042D01*
X786683Y531792D01*
X786433Y531583D01*
X786142Y531500D01*
X785808Y531583D01*
X785517Y531833D01*
X785350Y532208D01*
X785308Y532625D01*
X785392Y533167D01*
X785517Y533458D01*
X785725Y533750D01*
X786017Y533958D01*
X786308Y534000D01*
X786600Y533917D01*
X786808Y533708D01*
G01X788283Y531875D02*
X788533Y531667D01*
X788825Y531542D01*
X789200Y531500D01*
X789575Y531583D01*
X789867Y531750D01*
X790075Y532042D01*
X790117Y532375D01*
X790033Y532708D01*
X789825Y532917D01*
X789533Y533083D01*
X789242Y533125D01*
X788950Y533083D01*
X788575Y532917D01*
X788700Y534000D01*
X789825D01*
G01X780800Y548500D02*
Y544500D01*
X788200D01*
G01X775925Y535833D02*
X776258Y535625D01*
X776633Y535500D01*
X776967D01*
X777300Y535625D01*
X777550Y535833D01*
X777675Y536125D01*
X777592Y536417D01*
X777383Y536667D01*
X777008Y536833D01*
X776508Y536917D01*
X776217Y537083D01*
X776092Y537375D01*
X776175Y537667D01*
X776383Y537875D01*
X776675Y538000D01*
X776967D01*
X777258Y537917D01*
X777508Y537708D01*
G01X779067Y535500D02*
Y538000D01*
X780108D01*
X780442Y537875D01*
X780650Y537708D01*
X780733Y537375D01*
X780650Y537042D01*
X780400Y536833D01*
X780108Y536708D01*
X779067D01*
G01X780108D02*
X780733Y535500D01*
G01X782917D02*
X783000Y536042D01*
X783125Y536500D01*
X783292Y536917D01*
X783500Y537375D01*
X783833Y538000D01*
X782167D01*
G01X785308Y536542D02*
X785600Y536833D01*
X785850Y537000D01*
X786183Y537083D01*
X786475Y537000D01*
X786683Y536833D01*
X786850Y536583D01*
X786892Y536292D01*
X786850Y536042D01*
X786683Y535792D01*
X786433Y535583D01*
X786142Y535500D01*
X785808Y535583D01*
X785517Y535833D01*
X785350Y536208D01*
X785308Y536625D01*
X785392Y537167D01*
X785517Y537458D01*
X785725Y537750D01*
X786017Y537958D01*
X786308Y538000D01*
X786600Y537917D01*
X786808Y537708D01*
G01X788408Y536542D02*
X788700Y536833D01*
X788950Y537000D01*
X789283Y537083D01*
X789575Y537000D01*
X789783Y536833D01*
X789950Y536583D01*
X789992Y536292D01*
X789950Y536042D01*
X789783Y535792D01*
X789533Y535583D01*
X789242Y535500D01*
X788908Y535583D01*
X788617Y535833D01*
X788450Y536208D01*
X788408Y536625D01*
X788492Y537167D01*
X788617Y537458D01*
X788825Y537750D01*
X789117Y537958D01*
X789408Y538000D01*
X789700Y537917D01*
X789908Y537708D01*
G01X775925Y539833D02*
X776258Y539625D01*
X776633Y539500D01*
X776967D01*
X777300Y539625D01*
X777550Y539833D01*
X777675Y540125D01*
X777592Y540417D01*
X777383Y540667D01*
X777008Y540833D01*
X776508Y540917D01*
X776217Y541083D01*
X776092Y541375D01*
X776175Y541667D01*
X776383Y541875D01*
X776675Y542000D01*
X776967D01*
X777258Y541917D01*
X777508Y541708D01*
G01X779067Y539500D02*
Y542000D01*
X780108D01*
X780442Y541875D01*
X780650Y541708D01*
X780733Y541375D01*
X780650Y541042D01*
X780400Y540833D01*
X780108Y540708D01*
X779067D01*
G01X780108D02*
X780733Y539500D01*
G01X782917D02*
X783000Y540042D01*
X783125Y540500D01*
X783292Y540917D01*
X783500Y541375D01*
X783833Y542000D01*
X782167D01*
G01X785308Y540542D02*
X785600Y540833D01*
X785850Y541000D01*
X786183Y541083D01*
X786475Y541000D01*
X786683Y540833D01*
X786850Y540583D01*
X786892Y540292D01*
X786850Y540042D01*
X786683Y539792D01*
X786433Y539583D01*
X786142Y539500D01*
X785808Y539583D01*
X785517Y539833D01*
X785350Y540208D01*
X785308Y540625D01*
X785392Y541167D01*
X785517Y541458D01*
X785725Y541750D01*
X786017Y541958D01*
X786308Y542000D01*
X786600Y541917D01*
X786808Y541708D01*
G01X789117Y539500D02*
X789200Y540042D01*
X789325Y540500D01*
X789492Y540917D01*
X789700Y541375D01*
X790033Y542000D01*
X788367D01*
G01X781300Y555500D02*
Y551500D01*
X788700D01*
G01X781300Y563000D02*
Y559000D01*
X788700D01*
G01X774394Y583668D02*
Y572768D01*
G01X781200Y647000D02*
Y651000D01*
X773800D01*
G01Y646500D02*
Y642500D01*
X781200D01*
G01X786284Y652032D02*
Y665032D01*
G01X784017Y667000D02*
Y669500D01*
X785058D01*
X785392Y669375D01*
X785600Y669208D01*
X785683Y668875D01*
X785600Y668542D01*
X785350Y668333D01*
X785058Y668208D01*
X784017D01*
G01X785058D02*
X785683Y667000D01*
G01X787033Y667375D02*
X787283Y667167D01*
X787575Y667042D01*
X787950Y667000D01*
X788325Y667083D01*
X788617Y667250D01*
X788825Y667542D01*
X788867Y667875D01*
X788783Y668208D01*
X788575Y668417D01*
X788283Y668583D01*
X787992Y668625D01*
X787700Y668583D01*
X787325Y668417D01*
X787450Y669500D01*
X788575D01*
G01X790967Y667000D02*
X791050Y667542D01*
X791175Y668000D01*
X791342Y668417D01*
X791550Y668875D01*
X791883Y669500D01*
X790217D01*
G01X794150Y667000D02*
X794442Y667042D01*
X794775Y667167D01*
X794983Y667375D01*
X795067Y667667D01*
X794983Y667958D01*
X794733Y668208D01*
X794358Y668333D01*
X793942D01*
X793692Y668417D01*
X793483Y668625D01*
X793400Y668917D01*
X793525Y669208D01*
X793817Y669417D01*
X794150Y669500D01*
X794483Y669417D01*
X794775Y669208D01*
X794900Y668917D01*
X794817Y668625D01*
X794608Y668417D01*
X794358Y668333D01*
X793942D01*
X793567Y668208D01*
X793317Y667958D01*
X793233Y667667D01*
X793317Y667375D01*
X793525Y667167D01*
X793858Y667042D01*
X794150Y667000D01*
G01X781700Y666000D02*
Y670000D01*
X774300D01*
G01X783517Y674500D02*
Y677000D01*
X784558D01*
X784892Y676875D01*
X785100Y676708D01*
X785183Y676375D01*
X785100Y676042D01*
X784850Y675833D01*
X784558Y675708D01*
X783517D01*
G01X784558D02*
X785183Y674500D01*
G01X787950D02*
Y677000D01*
X786408Y675208D01*
X788492D01*
G01X790550Y674500D02*
X790842Y674542D01*
X791175Y674667D01*
X791383Y674875D01*
X791467Y675167D01*
X791383Y675458D01*
X791133Y675708D01*
X790758Y675833D01*
X790342D01*
X790092Y675917D01*
X789883Y676125D01*
X789800Y676417D01*
X789925Y676708D01*
X790217Y676917D01*
X790550Y677000D01*
X790883Y676917D01*
X791175Y676708D01*
X791300Y676417D01*
X791217Y676125D01*
X791008Y675917D01*
X790758Y675833D01*
X790342D01*
X789967Y675708D01*
X789717Y675458D01*
X789633Y675167D01*
X789717Y674875D01*
X789925Y674667D01*
X790258Y674542D01*
X790550Y674500D01*
G01X793650Y677000D02*
X793317Y676917D01*
X793067Y676708D01*
X792900Y676458D01*
X792775Y676125D01*
X792733Y675750D01*
X792775Y675375D01*
X792900Y675042D01*
X793067Y674792D01*
X793317Y674583D01*
X793650Y674500D01*
X793983Y674583D01*
X794233Y674792D01*
X794400Y675042D01*
X794525Y675375D01*
X794567Y675750D01*
X794525Y676125D01*
X794400Y676458D01*
X794233Y676708D01*
X793983Y676917D01*
X793650Y677000D01*
G01X777998Y671354D02*
X781998D01*
Y678754D01*
G01X783198Y682354D02*
Y695754D01*
G01X783000Y704517D02*
X780500D01*
Y705558D01*
X780625Y705892D01*
X780792Y706100D01*
X781125Y706183D01*
X781458Y706100D01*
X781667Y705850D01*
X781792Y705558D01*
Y704517D01*
G01Y705558D02*
X783000Y706183D01*
G01Y708950D02*
X780500D01*
X782292Y707408D01*
Y709492D01*
G01X783000Y711550D02*
X782958Y711842D01*
X782833Y712175D01*
X782625Y712383D01*
X782333Y712467D01*
X782042Y712383D01*
X781792Y712133D01*
X781667Y711758D01*
Y711342D01*
X781583Y711092D01*
X781375Y710883D01*
X781083Y710800D01*
X780792Y710925D01*
X780583Y711217D01*
X780500Y711550D01*
X780583Y711883D01*
X780792Y712175D01*
X781083Y712300D01*
X781375Y712217D01*
X781583Y712008D01*
X781667Y711758D01*
Y711342D01*
X781792Y710967D01*
X782042Y710717D01*
X782333Y710633D01*
X782625Y710717D01*
X782833Y710925D01*
X782958Y711258D01*
X783000Y711550D01*
G01Y714650D02*
X780500D01*
X781000Y714150D01*
G01X783000D02*
Y715150D01*
G01X780667Y720875D02*
X780875Y721208D01*
X781000Y721583D01*
Y721917D01*
X780875Y722250D01*
X780667Y722500D01*
X780375Y722625D01*
X780083Y722542D01*
X779833Y722333D01*
X779667Y721958D01*
X779583Y721458D01*
X779417Y721167D01*
X779125Y721042D01*
X778833Y721125D01*
X778625Y721333D01*
X778500Y721625D01*
Y721917D01*
X778583Y722208D01*
X778792Y722458D01*
G01X778708Y725767D02*
X778583Y725517D01*
X778500Y725225D01*
Y724892D01*
X778625Y724517D01*
X778833Y724225D01*
X779083Y724017D01*
X779500Y723850D01*
X779875Y723808D01*
X780250Y723892D01*
X780500Y724017D01*
X780750Y724267D01*
X780917Y724558D01*
X781000Y724850D01*
Y725142D01*
X780917Y725433D01*
X780792Y725683D01*
X780625Y725892D01*
G01X781000Y727950D02*
X778500D01*
X779000Y727450D01*
G01X781000D02*
Y728450D01*
G01X780500Y730133D02*
X780792Y730383D01*
X780958Y730717D01*
X781000Y731092D01*
X780958Y731425D01*
X780750Y731758D01*
X780500Y731967D01*
X780250Y732008D01*
X779958Y731925D01*
X779750Y731633D01*
X779667Y731342D01*
Y730967D01*
G01Y731342D02*
X779542Y731592D01*
X779333Y731800D01*
X779083Y731883D01*
X778833Y731800D01*
X778625Y731592D01*
X778500Y731217D01*
X778542Y730842D01*
X778708Y730467D01*
G01X781000Y734150D02*
X778500D01*
X779000Y733650D01*
G01X781000D02*
Y734650D01*
G01X778500Y737250D02*
X778583Y736917D01*
X778792Y736667D01*
X779042Y736500D01*
X779375Y736375D01*
X779750Y736333D01*
X780125Y736375D01*
X780458Y736500D01*
X780708Y736667D01*
X780917Y736917D01*
X781000Y737250D01*
X780917Y737583D01*
X780708Y737833D01*
X780458Y738000D01*
X780125Y738125D01*
X779750Y738167D01*
X779375Y738125D01*
X779042Y738000D01*
X778792Y737833D01*
X778583Y737583D01*
X778500Y737250D01*
G01X781500Y749483D02*
X783292D01*
X783667Y749650D01*
X783917Y749983D01*
X784000Y750400D01*
X783917Y750817D01*
X783667Y751150D01*
X783292Y751317D01*
X781500D01*
G01X784000Y754000D02*
X781500D01*
X783292Y752458D01*
Y754542D01*
G01X784000Y756600D02*
X781500D01*
X782000Y756100D01*
G01X784000D02*
Y757100D01*
G01X786768Y755784D02*
X788868Y753984D01*
X786768Y751784D01*
G01X786668Y748184D02*
X805868D01*
Y759384D01*
X786668D01*
Y748184D01*
X787068D01*
G01X786208Y784267D02*
X786083Y784017D01*
X786000Y783725D01*
Y783392D01*
X786125Y783017D01*
X786333Y782725D01*
X786583Y782517D01*
X787000Y782350D01*
X787375Y782308D01*
X787750Y782392D01*
X788000Y782517D01*
X788250Y782767D01*
X788417Y783058D01*
X788500Y783350D01*
Y783642D01*
X788417Y783933D01*
X788292Y784183D01*
X788125Y784392D01*
G01X786417Y785658D02*
X786167Y785908D01*
X786042Y786200D01*
X786000Y786533D01*
X786083Y786950D01*
X786292Y787242D01*
X786542Y787325D01*
X786792Y787283D01*
X787000Y787117D01*
X787417Y786283D01*
X787708Y785908D01*
X788125Y785658D01*
X788500Y785575D01*
Y787325D01*
G01X787458Y788758D02*
X787167Y789050D01*
X787000Y789300D01*
X786917Y789633D01*
X787000Y789925D01*
X787167Y790133D01*
X787417Y790300D01*
X787708Y790342D01*
X787958Y790300D01*
X788208Y790133D01*
X788417Y789883D01*
X788500Y789592D01*
X788417Y789258D01*
X788167Y788967D01*
X787792Y788800D01*
X787375Y788758D01*
X786833Y788842D01*
X786542Y788967D01*
X786250Y789175D01*
X786042Y789467D01*
X786000Y789758D01*
X786083Y790050D01*
X786292Y790258D01*
G01X788500Y793150D02*
X786000D01*
X787792Y791608D01*
Y793692D01*
G01X779933Y845000D02*
Y843208D01*
X780100Y842833D01*
X780433Y842583D01*
X780850Y842500D01*
X781267Y842583D01*
X781600Y842833D01*
X781767Y843208D01*
Y845000D01*
G01X783950Y842500D02*
Y845000D01*
X783450Y844500D01*
G01Y842500D02*
X784450D01*
G01X786967D02*
X787050Y843042D01*
X787175Y843500D01*
X787342Y843917D01*
X787550Y844375D01*
X787883Y845000D01*
X786217D01*
G01X789233Y843000D02*
X789483Y842708D01*
X789817Y842542D01*
X790192Y842500D01*
X790525Y842542D01*
X790858Y842750D01*
X791067Y843000D01*
X791108Y843250D01*
X791025Y843542D01*
X790733Y843750D01*
X790442Y843833D01*
X790067D01*
G01X790442D02*
X790692Y843958D01*
X790900Y844167D01*
X790983Y844417D01*
X790900Y844667D01*
X790692Y844875D01*
X790317Y845000D01*
X789942Y844958D01*
X789567Y844792D01*
G01X792700Y848500D02*
X779300D01*
G01Y858500D02*
X792700D01*
G01X779300Y848500D02*
Y858500D01*
G01X775000Y862933D02*
X776792D01*
X777167Y863100D01*
X777417Y863433D01*
X777500Y863850D01*
X777417Y864267D01*
X777167Y864600D01*
X776792Y864767D01*
X775000D01*
G01X777500Y866950D02*
X775000D01*
X775500Y866450D01*
G01X777500D02*
Y867450D01*
G01Y869967D02*
X776958Y870050D01*
X776500Y870175D01*
X776083Y870342D01*
X775625Y870550D01*
X775000Y870883D01*
Y869217D01*
G01X777500Y873650D02*
X775000D01*
X776792Y872108D01*
Y874192D01*
G01X780500Y861300D02*
Y874700D01*
G01X790500Y861300D02*
X780500D01*
G01Y874700D02*
X790500D01*
G01X782500Y886700D02*
X778500D01*
Y879300D01*
G01X787000Y886700D02*
X783000D01*
Y879300D01*
G01X787500D02*
X791500D01*
Y886700D01*
G01X783267Y903292D02*
X783017Y903417D01*
X782725Y903500D01*
X782392D01*
X782017Y903375D01*
X781725Y903167D01*
X781517Y902917D01*
X781350Y902500D01*
X781308Y902125D01*
X781392Y901750D01*
X781517Y901500D01*
X781767Y901250D01*
X782058Y901083D01*
X782350Y901000D01*
X782642D01*
X782933Y901083D01*
X783183Y901208D01*
X783392Y901375D01*
G01X784533Y901500D02*
X784783Y901208D01*
X785117Y901042D01*
X785492Y901000D01*
X785825Y901042D01*
X786158Y901250D01*
X786367Y901500D01*
X786408Y901750D01*
X786325Y902042D01*
X786033Y902250D01*
X785742Y902333D01*
X785367D01*
G01X785742D02*
X785992Y902458D01*
X786200Y902667D01*
X786283Y902917D01*
X786200Y903167D01*
X785992Y903375D01*
X785617Y903500D01*
X785242Y903458D01*
X784867Y903292D01*
G01X788467Y901000D02*
X788550Y901542D01*
X788675Y902000D01*
X788842Y902417D01*
X789050Y902875D01*
X789383Y903500D01*
X787717D01*
G01X791650D02*
X791317Y903417D01*
X791067Y903208D01*
X790900Y902958D01*
X790775Y902625D01*
X790733Y902250D01*
X790775Y901875D01*
X790900Y901542D01*
X791067Y901292D01*
X791317Y901083D01*
X791650Y901000D01*
X791983Y901083D01*
X792233Y901292D01*
X792400Y901542D01*
X792525Y901875D01*
X792567Y902250D01*
X792525Y902625D01*
X792400Y902958D01*
X792233Y903208D01*
X791983Y903417D01*
X791650Y903500D01*
G01X799324Y346748D02*
X806324D01*
Y333348D01*
X799324D01*
Y346748D01*
G01X804491Y349523D02*
X804699Y349856D01*
X804824Y350231D01*
Y350565D01*
X804699Y350898D01*
X804491Y351148D01*
X804199Y351273D01*
X803907Y351190D01*
X803657Y350981D01*
X803491Y350606D01*
X803407Y350106D01*
X803241Y349815D01*
X802949Y349690D01*
X802657Y349773D01*
X802449Y349981D01*
X802324Y350273D01*
Y350565D01*
X802407Y350856D01*
X802616Y351106D01*
G01X802324Y352665D02*
X804824D01*
Y354331D01*
G01Y356598D02*
X802324D01*
X802824Y356098D01*
G01X804824D02*
Y357098D01*
G01Y359698D02*
X802324D01*
X802824Y359198D01*
G01X804824D02*
Y360198D01*
G01X797967Y368000D02*
Y370500D01*
X798967D01*
X799300Y370375D01*
X799550Y370083D01*
X799633Y369750D01*
X799550Y369417D01*
X799342Y369167D01*
X798967Y369042D01*
X797967D01*
G01X802817Y370292D02*
X802567Y370417D01*
X802275Y370500D01*
X801942D01*
X801567Y370375D01*
X801275Y370167D01*
X801067Y369917D01*
X800900Y369500D01*
X800858Y369125D01*
X800942Y368750D01*
X801067Y368500D01*
X801317Y368250D01*
X801608Y368083D01*
X801900Y368000D01*
X802192D01*
X802483Y368083D01*
X802733Y368208D01*
X802942Y368375D01*
G01X805000Y368000D02*
Y370500D01*
X804500Y370000D01*
G01Y368000D02*
X805500D01*
G01X808600D02*
Y370500D01*
X807058Y368708D01*
X809142D01*
G01X810408Y369042D02*
X810700Y369333D01*
X810950Y369500D01*
X811283Y369583D01*
X811575Y369500D01*
X811783Y369333D01*
X811950Y369083D01*
X811992Y368792D01*
X811950Y368542D01*
X811783Y368292D01*
X811533Y368083D01*
X811242Y368000D01*
X810908Y368083D01*
X810617Y368333D01*
X810450Y368708D01*
X810408Y369125D01*
X810492Y369667D01*
X810617Y369958D01*
X810825Y370250D01*
X811117Y370458D01*
X811408Y370500D01*
X811700Y370417D01*
X811908Y370208D01*
G01X797467Y381500D02*
Y384000D01*
X798467D01*
X798800Y383875D01*
X799050Y383583D01*
X799133Y383250D01*
X799050Y382917D01*
X798842Y382667D01*
X798467Y382542D01*
X797467D01*
G01X802317Y383792D02*
X802067Y383917D01*
X801775Y384000D01*
X801442D01*
X801067Y383875D01*
X800775Y383667D01*
X800567Y383417D01*
X800400Y383000D01*
X800358Y382625D01*
X800442Y382250D01*
X800567Y382000D01*
X800817Y381750D01*
X801108Y381583D01*
X801400Y381500D01*
X801692D01*
X801983Y381583D01*
X802233Y381708D01*
X802442Y381875D01*
G01X804500Y381500D02*
Y384000D01*
X804000Y383500D01*
G01Y381500D02*
X805000D01*
G01X808100D02*
Y384000D01*
X806558Y382208D01*
X808642D01*
G01X811200Y381500D02*
Y384000D01*
X809658Y382208D01*
X811742D01*
G01X797467Y373500D02*
Y376000D01*
X798467D01*
X798800Y375875D01*
X799050Y375583D01*
X799133Y375250D01*
X799050Y374917D01*
X798842Y374667D01*
X798467Y374542D01*
X797467D01*
G01X802317Y375792D02*
X802067Y375917D01*
X801775Y376000D01*
X801442D01*
X801067Y375875D01*
X800775Y375667D01*
X800567Y375417D01*
X800400Y375000D01*
X800358Y374625D01*
X800442Y374250D01*
X800567Y374000D01*
X800817Y373750D01*
X801108Y373583D01*
X801400Y373500D01*
X801692D01*
X801983Y373583D01*
X802233Y373708D01*
X802442Y373875D01*
G01X804500Y373500D02*
Y376000D01*
X804000Y375500D01*
G01Y373500D02*
X805000D01*
G01X808100D02*
Y376000D01*
X806558Y374208D01*
X808642D01*
G01X809783Y373875D02*
X810033Y373667D01*
X810325Y373542D01*
X810700Y373500D01*
X811075Y373583D01*
X811367Y373750D01*
X811575Y374042D01*
X811617Y374375D01*
X811533Y374708D01*
X811325Y374917D01*
X811033Y375083D01*
X810742Y375125D01*
X810450Y375083D01*
X810075Y374917D01*
X810200Y376000D01*
X811325D01*
G01X797467Y386000D02*
Y388500D01*
X798467D01*
X798800Y388375D01*
X799050Y388083D01*
X799133Y387750D01*
X799050Y387417D01*
X798842Y387167D01*
X798467Y387042D01*
X797467D01*
G01X802317Y388292D02*
X802067Y388417D01*
X801775Y388500D01*
X801442D01*
X801067Y388375D01*
X800775Y388167D01*
X800567Y387917D01*
X800400Y387500D01*
X800358Y387125D01*
X800442Y386750D01*
X800567Y386500D01*
X800817Y386250D01*
X801108Y386083D01*
X801400Y386000D01*
X801692D01*
X801983Y386083D01*
X802233Y386208D01*
X802442Y386375D01*
G01X804500Y386000D02*
Y388500D01*
X804000Y388000D01*
G01Y386000D02*
X805000D01*
G01X808100D02*
Y388500D01*
X806558Y386708D01*
X808642D01*
G01X809783Y386500D02*
X810033Y386208D01*
X810367Y386042D01*
X810742Y386000D01*
X811075Y386042D01*
X811408Y386250D01*
X811617Y386500D01*
X811658Y386750D01*
X811575Y387042D01*
X811283Y387250D01*
X810992Y387333D01*
X810617D01*
G01X810992D02*
X811242Y387458D01*
X811450Y387667D01*
X811533Y387917D01*
X811450Y388167D01*
X811242Y388375D01*
X810867Y388500D01*
X810492Y388458D01*
X810117Y388292D01*
G01X803467Y402500D02*
Y405000D01*
X804467D01*
X804800Y404875D01*
X805050Y404583D01*
X805133Y404250D01*
X805050Y403917D01*
X804842Y403667D01*
X804467Y403542D01*
X803467D01*
G01X808317Y404792D02*
X808067Y404917D01*
X807775Y405000D01*
X807442D01*
X807067Y404875D01*
X806775Y404667D01*
X806567Y404417D01*
X806400Y404000D01*
X806358Y403625D01*
X806442Y403250D01*
X806567Y403000D01*
X806817Y402750D01*
X807108Y402583D01*
X807400Y402500D01*
X807692D01*
X807983Y402583D01*
X808233Y402708D01*
X808442Y402875D01*
G01X810500Y402500D02*
Y405000D01*
X810000Y404500D01*
G01Y402500D02*
X811000D01*
G01X814100D02*
Y405000D01*
X812558Y403208D01*
X814642D01*
G01X815908Y404583D02*
X816158Y404833D01*
X816450Y404958D01*
X816783Y405000D01*
X817200Y404917D01*
X817492Y404708D01*
X817575Y404458D01*
X817533Y404208D01*
X817367Y404000D01*
X816533Y403583D01*
X816158Y403292D01*
X815908Y402875D01*
X815825Y402500D01*
X817575D01*
G01X805000Y416917D02*
X802500D01*
Y417917D01*
X802625Y418250D01*
X802917Y418500D01*
X803250Y418583D01*
X803583Y418500D01*
X803833Y418292D01*
X803958Y417917D01*
Y416917D01*
G01X805000Y420017D02*
X802500D01*
Y421058D01*
X802625Y421392D01*
X802792Y421600D01*
X803125Y421683D01*
X803458Y421600D01*
X803667Y421350D01*
X803792Y421058D01*
Y420017D01*
G01Y421058D02*
X805000Y421683D01*
G01X804708Y423242D02*
X804917Y423533D01*
X805000Y423867D01*
X804917Y424200D01*
X804667Y424492D01*
X804292Y424700D01*
X803917Y424783D01*
X803458D01*
X803083Y424700D01*
X802750Y424492D01*
X802583Y424242D01*
X802500Y423950D01*
X802583Y423617D01*
X802750Y423367D01*
X803000Y423200D01*
X803333Y423117D01*
X803625Y423200D01*
X803917Y423408D01*
X804083Y423658D01*
X804125Y423950D01*
X804042Y424283D01*
X803833Y424533D01*
X803458Y424783D01*
G01X802500Y427050D02*
X802583Y426717D01*
X802792Y426467D01*
X803042Y426300D01*
X803375Y426175D01*
X803750Y426133D01*
X804125Y426175D01*
X804458Y426300D01*
X804708Y426467D01*
X804917Y426717D01*
X805000Y427050D01*
X804917Y427383D01*
X804708Y427633D01*
X804458Y427800D01*
X804125Y427925D01*
X803750Y427967D01*
X803375Y427925D01*
X803042Y427800D01*
X802792Y427633D01*
X802583Y427383D01*
X802500Y427050D01*
G01X805000Y430150D02*
X802500D01*
X803000Y429650D01*
G01X805000D02*
Y430650D01*
G01X803958Y432458D02*
X803667Y432750D01*
X803500Y433000D01*
X803417Y433333D01*
X803500Y433625D01*
X803667Y433833D01*
X803917Y434000D01*
X804208Y434042D01*
X804458Y434000D01*
X804708Y433833D01*
X804917Y433583D01*
X805000Y433292D01*
X804917Y432958D01*
X804667Y432667D01*
X804292Y432500D01*
X803875Y432458D01*
X803333Y432542D01*
X803042Y432667D01*
X802750Y432875D01*
X802542Y433167D01*
X802500Y433458D01*
X802583Y433750D01*
X802792Y433958D01*
G01X796774Y431878D02*
X800774D01*
Y439278D01*
G01X791674Y441178D02*
X796674D01*
Y446178D01*
G01X798417Y448000D02*
Y450500D01*
X799417D01*
X799750Y450375D01*
X800000Y450083D01*
X800083Y449750D01*
X800000Y449417D01*
X799792Y449167D01*
X799417Y449042D01*
X798417D01*
G01X801517Y448000D02*
Y450500D01*
X802558D01*
X802892Y450375D01*
X803100Y450208D01*
X803183Y449875D01*
X803100Y449542D01*
X802850Y449333D01*
X802558Y449208D01*
X801517D01*
G01X802558D02*
X803183Y448000D01*
G01X804742Y448292D02*
X805033Y448083D01*
X805367Y448000D01*
X805700Y448083D01*
X805992Y448333D01*
X806200Y448708D01*
X806283Y449083D01*
Y449542D01*
X806200Y449917D01*
X805992Y450250D01*
X805742Y450417D01*
X805450Y450500D01*
X805117Y450417D01*
X804867Y450250D01*
X804700Y450000D01*
X804617Y449667D01*
X804700Y449375D01*
X804908Y449083D01*
X805158Y448917D01*
X805450Y448875D01*
X805783Y448958D01*
X806033Y449167D01*
X806283Y449542D01*
G01X808550Y450500D02*
X808217Y450417D01*
X807967Y450208D01*
X807800Y449958D01*
X807675Y449625D01*
X807633Y449250D01*
X807675Y448875D01*
X807800Y448542D01*
X807967Y448292D01*
X808217Y448083D01*
X808550Y448000D01*
X808883Y448083D01*
X809133Y448292D01*
X809300Y448542D01*
X809425Y448875D01*
X809467Y449250D01*
X809425Y449625D01*
X809300Y449958D01*
X809133Y450208D01*
X808883Y450417D01*
X808550Y450500D01*
G01X811650D02*
X811317Y450417D01*
X811067Y450208D01*
X810900Y449958D01*
X810775Y449625D01*
X810733Y449250D01*
X810775Y448875D01*
X810900Y448542D01*
X811067Y448292D01*
X811317Y448083D01*
X811650Y448000D01*
X811983Y448083D01*
X812233Y448292D01*
X812400Y448542D01*
X812525Y448875D01*
X812567Y449250D01*
X812525Y449625D01*
X812400Y449958D01*
X812233Y450208D01*
X811983Y450417D01*
X811650Y450500D01*
G01X814750Y448000D02*
X815042Y448042D01*
X815375Y448167D01*
X815583Y448375D01*
X815667Y448667D01*
X815583Y448958D01*
X815333Y449208D01*
X814958Y449333D01*
X814542D01*
X814292Y449417D01*
X814083Y449625D01*
X814000Y449917D01*
X814125Y450208D01*
X814417Y450417D01*
X814750Y450500D01*
X815083Y450417D01*
X815375Y450208D01*
X815500Y449917D01*
X815417Y449625D01*
X815208Y449417D01*
X814958Y449333D01*
X814542D01*
X814167Y449208D01*
X813917Y448958D01*
X813833Y448667D01*
X813917Y448375D01*
X814125Y448167D01*
X814458Y448042D01*
X814750Y448000D01*
G01X795680Y452062D02*
X797680D01*
G01X802200Y469000D02*
Y473000D01*
X794800D01*
G01X804574Y471578D02*
Y467578D01*
X811974D01*
G01X802967Y498000D02*
Y500500D01*
X804008D01*
X804342Y500375D01*
X804550Y500208D01*
X804633Y499875D01*
X804550Y499542D01*
X804300Y499333D01*
X804008Y499208D01*
X802967D01*
G01X804008D02*
X804633Y498000D01*
G01X806192Y498292D02*
X806483Y498083D01*
X806817Y498000D01*
X807150Y498083D01*
X807442Y498333D01*
X807650Y498708D01*
X807733Y499083D01*
Y499542D01*
X807650Y499917D01*
X807442Y500250D01*
X807192Y500417D01*
X806900Y500500D01*
X806567Y500417D01*
X806317Y500250D01*
X806150Y500000D01*
X806067Y499667D01*
X806150Y499375D01*
X806358Y499083D01*
X806608Y498917D01*
X806900Y498875D01*
X807233Y498958D01*
X807483Y499167D01*
X807733Y499542D01*
G01X810000Y500500D02*
X809667Y500417D01*
X809417Y500208D01*
X809250Y499958D01*
X809125Y499625D01*
X809083Y499250D01*
X809125Y498875D01*
X809250Y498542D01*
X809417Y498292D01*
X809667Y498083D01*
X810000Y498000D01*
X810333Y498083D01*
X810583Y498292D01*
X810750Y498542D01*
X810875Y498875D01*
X810917Y499250D01*
X810875Y499625D01*
X810750Y499958D01*
X810583Y500208D01*
X810333Y500417D01*
X810000Y500500D01*
G01X813100Y498000D02*
Y500500D01*
X812600Y500000D01*
G01Y498000D02*
X813600D01*
G01X816700D02*
Y500500D01*
X815158Y498708D01*
X817242D01*
G01X804417Y491500D02*
Y494000D01*
X805417D01*
X805750Y493875D01*
X806000Y493583D01*
X806083Y493250D01*
X806000Y492917D01*
X805792Y492667D01*
X805417Y492542D01*
X804417D01*
G01X807517Y491500D02*
Y494000D01*
X808558D01*
X808892Y493875D01*
X809100Y493708D01*
X809183Y493375D01*
X809100Y493042D01*
X808850Y492833D01*
X808558Y492708D01*
X807517D01*
G01X808558D02*
X809183Y491500D01*
G01X810742Y491792D02*
X811033Y491583D01*
X811367Y491500D01*
X811700Y491583D01*
X811992Y491833D01*
X812200Y492208D01*
X812283Y492583D01*
Y493042D01*
X812200Y493417D01*
X811992Y493750D01*
X811742Y493917D01*
X811450Y494000D01*
X811117Y493917D01*
X810867Y493750D01*
X810700Y493500D01*
X810617Y493167D01*
X810700Y492875D01*
X810908Y492583D01*
X811158Y492417D01*
X811450Y492375D01*
X811783Y492458D01*
X812033Y492667D01*
X812283Y493042D01*
G01X814550Y494000D02*
X814217Y493917D01*
X813967Y493708D01*
X813800Y493458D01*
X813675Y493125D01*
X813633Y492750D01*
X813675Y492375D01*
X813800Y492042D01*
X813967Y491792D01*
X814217Y491583D01*
X814550Y491500D01*
X814883Y491583D01*
X815133Y491792D01*
X815300Y492042D01*
X815425Y492375D01*
X815467Y492750D01*
X815425Y493125D01*
X815300Y493458D01*
X815133Y493708D01*
X814883Y493917D01*
X814550Y494000D01*
G01X817650Y491500D02*
Y494000D01*
X817150Y493500D01*
G01Y491500D02*
X818150D01*
G01X819833Y491875D02*
X820083Y491667D01*
X820375Y491542D01*
X820750Y491500D01*
X821125Y491583D01*
X821417Y491750D01*
X821625Y492042D01*
X821667Y492375D01*
X821583Y492708D01*
X821375Y492917D01*
X821083Y493083D01*
X820792Y493125D01*
X820500Y493083D01*
X820125Y492917D01*
X820250Y494000D01*
X821375D01*
G01X796274Y487995D02*
X793774D01*
Y488995D01*
X793899Y489328D01*
X794191Y489578D01*
X794524Y489661D01*
X794857Y489578D01*
X795107Y489370D01*
X795232Y488995D01*
Y487995D01*
G01X796274Y491095D02*
X793774D01*
Y492136D01*
X793899Y492470D01*
X794066Y492678D01*
X794399Y492761D01*
X794732Y492678D01*
X794941Y492428D01*
X795066Y492136D01*
Y491095D01*
G01Y492136D02*
X796274Y492761D01*
G01X795982Y494320D02*
X796191Y494611D01*
X796274Y494945D01*
X796191Y495278D01*
X795941Y495570D01*
X795566Y495778D01*
X795191Y495861D01*
X794732D01*
X794357Y495778D01*
X794024Y495570D01*
X793857Y495320D01*
X793774Y495028D01*
X793857Y494695D01*
X794024Y494445D01*
X794274Y494278D01*
X794607Y494195D01*
X794899Y494278D01*
X795191Y494486D01*
X795357Y494736D01*
X795399Y495028D01*
X795316Y495361D01*
X795107Y495611D01*
X794732Y495861D01*
G01X793774Y498128D02*
X793857Y497795D01*
X794066Y497545D01*
X794316Y497378D01*
X794649Y497253D01*
X795024Y497211D01*
X795399Y497253D01*
X795732Y497378D01*
X795982Y497545D01*
X796191Y497795D01*
X796274Y498128D01*
X796191Y498461D01*
X795982Y498711D01*
X795732Y498878D01*
X795399Y499003D01*
X795024Y499045D01*
X794649Y499003D01*
X794316Y498878D01*
X794066Y498711D01*
X793857Y498461D01*
X793774Y498128D01*
G01X796274Y501228D02*
X793774D01*
X794274Y500728D01*
G01X796274D02*
Y501728D01*
G01X793774Y504328D02*
X793857Y503995D01*
X794066Y503745D01*
X794316Y503578D01*
X794649Y503453D01*
X795024Y503411D01*
X795399Y503453D01*
X795732Y503578D01*
X795982Y503745D01*
X796191Y503995D01*
X796274Y504328D01*
X796191Y504661D01*
X795982Y504911D01*
X795732Y505078D01*
X795399Y505203D01*
X795024Y505245D01*
X794649Y505203D01*
X794316Y505078D01*
X794066Y504911D01*
X793857Y504661D01*
X793774Y504328D01*
G01X803967Y487500D02*
Y490000D01*
X804967D01*
X805300Y489875D01*
X805550Y489583D01*
X805633Y489250D01*
X805550Y488917D01*
X805342Y488667D01*
X804967Y488542D01*
X803967D01*
G01X808817Y489792D02*
X808567Y489917D01*
X808275Y490000D01*
X807942D01*
X807567Y489875D01*
X807275Y489667D01*
X807067Y489417D01*
X806900Y489000D01*
X806858Y488625D01*
X806942Y488250D01*
X807067Y488000D01*
X807317Y487750D01*
X807608Y487583D01*
X807900Y487500D01*
X808192D01*
X808483Y487583D01*
X808733Y487708D01*
X808942Y487875D01*
G01X810208Y489583D02*
X810458Y489833D01*
X810750Y489958D01*
X811083Y490000D01*
X811500Y489917D01*
X811792Y489708D01*
X811875Y489458D01*
X811833Y489208D01*
X811667Y489000D01*
X810833Y488583D01*
X810458Y488292D01*
X810208Y487875D01*
X810125Y487500D01*
X811875D01*
G01X813308Y489583D02*
X813558Y489833D01*
X813850Y489958D01*
X814183Y490000D01*
X814600Y489917D01*
X814892Y489708D01*
X814975Y489458D01*
X814933Y489208D01*
X814767Y489000D01*
X813933Y488583D01*
X813558Y488292D01*
X813308Y487875D01*
X813225Y487500D01*
X814975D01*
G01X817700D02*
Y490000D01*
X816158Y488208D01*
X818242D01*
G01X800500Y487967D02*
X798000D01*
Y488967D01*
X798125Y489300D01*
X798417Y489550D01*
X798750Y489633D01*
X799083Y489550D01*
X799333Y489342D01*
X799458Y488967D01*
Y487967D01*
G01X798208Y492817D02*
X798083Y492567D01*
X798000Y492275D01*
Y491942D01*
X798125Y491567D01*
X798333Y491275D01*
X798583Y491067D01*
X799000Y490900D01*
X799375Y490858D01*
X799750Y490942D01*
X800000Y491067D01*
X800250Y491317D01*
X800417Y491608D01*
X800500Y491900D01*
Y492192D01*
X800417Y492483D01*
X800292Y492733D01*
X800125Y492942D01*
G01X798417Y494208D02*
X798167Y494458D01*
X798042Y494750D01*
X798000Y495083D01*
X798083Y495500D01*
X798292Y495792D01*
X798542Y495875D01*
X798792Y495833D01*
X799000Y495667D01*
X799417Y494833D01*
X799708Y494458D01*
X800125Y494208D01*
X800500Y494125D01*
Y495875D01*
G01X800000Y497183D02*
X800292Y497433D01*
X800458Y497767D01*
X800500Y498142D01*
X800458Y498475D01*
X800250Y498808D01*
X800000Y499017D01*
X799750Y499058D01*
X799458Y498975D01*
X799250Y498683D01*
X799167Y498392D01*
Y498017D01*
G01Y498392D02*
X799042Y498642D01*
X798833Y498850D01*
X798583Y498933D01*
X798333Y498850D01*
X798125Y498642D01*
X798000Y498267D01*
X798042Y497892D01*
X798208Y497517D01*
G01X800208Y500492D02*
X800417Y500783D01*
X800500Y501117D01*
X800417Y501450D01*
X800167Y501742D01*
X799792Y501950D01*
X799417Y502033D01*
X798958D01*
X798583Y501950D01*
X798250Y501742D01*
X798083Y501492D01*
X798000Y501200D01*
X798083Y500867D01*
X798250Y500617D01*
X798500Y500450D01*
X798833Y500367D01*
X799125Y500450D01*
X799417Y500658D01*
X799583Y500908D01*
X799625Y501200D01*
X799542Y501533D01*
X799333Y501783D01*
X798958Y502033D01*
G01X803241Y502078D02*
Y504578D01*
X804241D01*
X804574Y504453D01*
X804824Y504161D01*
X804907Y503828D01*
X804824Y503495D01*
X804616Y503245D01*
X804241Y503120D01*
X803241D01*
G01X808091Y504370D02*
X807841Y504495D01*
X807549Y504578D01*
X807216D01*
X806841Y504453D01*
X806549Y504245D01*
X806341Y503995D01*
X806174Y503578D01*
X806132Y503203D01*
X806216Y502828D01*
X806341Y502578D01*
X806591Y502328D01*
X806882Y502161D01*
X807174Y502078D01*
X807466D01*
X807757Y502161D01*
X808007Y502286D01*
X808216Y502453D01*
G01X809482Y504161D02*
X809732Y504411D01*
X810024Y504536D01*
X810357Y504578D01*
X810774Y504495D01*
X811066Y504286D01*
X811149Y504036D01*
X811107Y503786D01*
X810941Y503578D01*
X810107Y503161D01*
X809732Y502870D01*
X809482Y502453D01*
X809399Y502078D01*
X811149D01*
G01X812582Y504161D02*
X812832Y504411D01*
X813124Y504536D01*
X813457Y504578D01*
X813874Y504495D01*
X814166Y504286D01*
X814249Y504036D01*
X814207Y503786D01*
X814041Y503578D01*
X813207Y503161D01*
X812832Y502870D01*
X812582Y502453D01*
X812499Y502078D01*
X814249D01*
G01X816474D02*
X816766Y502120D01*
X817099Y502245D01*
X817307Y502453D01*
X817391Y502745D01*
X817307Y503036D01*
X817057Y503286D01*
X816682Y503411D01*
X816266D01*
X816016Y503495D01*
X815807Y503703D01*
X815724Y503995D01*
X815849Y504286D01*
X816141Y504495D01*
X816474Y504578D01*
X816807Y504495D01*
X817099Y504286D01*
X817224Y503995D01*
X817141Y503703D01*
X816932Y503495D01*
X816682Y503411D01*
X816266D01*
X815891Y503286D01*
X815641Y503036D01*
X815557Y502745D01*
X815641Y502453D01*
X815849Y502245D01*
X816182Y502120D01*
X816474Y502078D01*
G01X793425Y531333D02*
X793758Y531125D01*
X794133Y531000D01*
X794467D01*
X794800Y531125D01*
X795050Y531333D01*
X795175Y531625D01*
X795092Y531917D01*
X794883Y532167D01*
X794508Y532333D01*
X794008Y532417D01*
X793717Y532583D01*
X793592Y532875D01*
X793675Y533167D01*
X793883Y533375D01*
X794175Y533500D01*
X794467D01*
X794758Y533417D01*
X795008Y533208D01*
G01X796567Y531000D02*
Y533500D01*
X797608D01*
X797942Y533375D01*
X798150Y533208D01*
X798233Y532875D01*
X798150Y532542D01*
X797900Y532333D01*
X797608Y532208D01*
X796567D01*
G01X797608D02*
X798233Y531000D01*
G01X800417D02*
X800500Y531542D01*
X800625Y532000D01*
X800792Y532417D01*
X801000Y532875D01*
X801333Y533500D01*
X799667D01*
G01X802683Y531375D02*
X802933Y531167D01*
X803225Y531042D01*
X803600Y531000D01*
X803975Y531083D01*
X804267Y531250D01*
X804475Y531542D01*
X804517Y531875D01*
X804433Y532208D01*
X804225Y532417D01*
X803933Y532583D01*
X803642Y532625D01*
X803350Y532583D01*
X802975Y532417D01*
X803100Y533500D01*
X804225D01*
G01X806700Y531000D02*
X806992Y531042D01*
X807325Y531167D01*
X807533Y531375D01*
X807617Y531667D01*
X807533Y531958D01*
X807283Y532208D01*
X806908Y532333D01*
X806492D01*
X806242Y532417D01*
X806033Y532625D01*
X805950Y532917D01*
X806075Y533208D01*
X806367Y533417D01*
X806700Y533500D01*
X807033Y533417D01*
X807325Y533208D01*
X807450Y532917D01*
X807367Y532625D01*
X807158Y532417D01*
X806908Y532333D01*
X806492D01*
X806117Y532208D01*
X805867Y531958D01*
X805783Y531667D01*
X805867Y531375D01*
X806075Y531167D01*
X806408Y531042D01*
X806700Y531000D01*
G01X801200Y544500D02*
Y548500D01*
X793800D01*
G01X793425Y535833D02*
X793758Y535625D01*
X794133Y535500D01*
X794467D01*
X794800Y535625D01*
X795050Y535833D01*
X795175Y536125D01*
X795092Y536417D01*
X794883Y536667D01*
X794508Y536833D01*
X794008Y536917D01*
X793717Y537083D01*
X793592Y537375D01*
X793675Y537667D01*
X793883Y537875D01*
X794175Y538000D01*
X794467D01*
X794758Y537917D01*
X795008Y537708D01*
G01X796567Y535500D02*
Y538000D01*
X797608D01*
X797942Y537875D01*
X798150Y537708D01*
X798233Y537375D01*
X798150Y537042D01*
X797900Y536833D01*
X797608Y536708D01*
X796567D01*
G01X797608D02*
X798233Y535500D01*
G01X800417D02*
X800500Y536042D01*
X800625Y536500D01*
X800792Y536917D01*
X801000Y537375D01*
X801333Y538000D01*
X799667D01*
G01X802683Y535875D02*
X802933Y535667D01*
X803225Y535542D01*
X803600Y535500D01*
X803975Y535583D01*
X804267Y535750D01*
X804475Y536042D01*
X804517Y536375D01*
X804433Y536708D01*
X804225Y536917D01*
X803933Y537083D01*
X803642Y537125D01*
X803350Y537083D01*
X802975Y536917D01*
X803100Y538000D01*
X804225D01*
G01X805992Y535792D02*
X806283Y535583D01*
X806617Y535500D01*
X806950Y535583D01*
X807242Y535833D01*
X807450Y536208D01*
X807533Y536583D01*
Y537042D01*
X807450Y537417D01*
X807242Y537750D01*
X806992Y537917D01*
X806700Y538000D01*
X806367Y537917D01*
X806117Y537750D01*
X805950Y537500D01*
X805867Y537167D01*
X805950Y536875D01*
X806158Y536583D01*
X806408Y536417D01*
X806700Y536375D01*
X807033Y536458D01*
X807283Y536667D01*
X807533Y537042D01*
G01X793425Y539833D02*
X793758Y539625D01*
X794133Y539500D01*
X794467D01*
X794800Y539625D01*
X795050Y539833D01*
X795175Y540125D01*
X795092Y540417D01*
X794883Y540667D01*
X794508Y540833D01*
X794008Y540917D01*
X793717Y541083D01*
X793592Y541375D01*
X793675Y541667D01*
X793883Y541875D01*
X794175Y542000D01*
X794467D01*
X794758Y541917D01*
X795008Y541708D01*
G01X796567Y539500D02*
Y542000D01*
X797608D01*
X797942Y541875D01*
X798150Y541708D01*
X798233Y541375D01*
X798150Y541042D01*
X797900Y540833D01*
X797608Y540708D01*
X796567D01*
G01X797608D02*
X798233Y539500D01*
G01X800417D02*
X800500Y540042D01*
X800625Y540500D01*
X800792Y540917D01*
X801000Y541375D01*
X801333Y542000D01*
X799667D01*
G01X802808Y540542D02*
X803100Y540833D01*
X803350Y541000D01*
X803683Y541083D01*
X803975Y541000D01*
X804183Y540833D01*
X804350Y540583D01*
X804392Y540292D01*
X804350Y540042D01*
X804183Y539792D01*
X803933Y539583D01*
X803642Y539500D01*
X803308Y539583D01*
X803017Y539833D01*
X802850Y540208D01*
X802808Y540625D01*
X802892Y541167D01*
X803017Y541458D01*
X803225Y541750D01*
X803517Y541958D01*
X803808Y542000D01*
X804100Y541917D01*
X804308Y541708D01*
G01X806700Y542000D02*
X806367Y541917D01*
X806117Y541708D01*
X805950Y541458D01*
X805825Y541125D01*
X805783Y540750D01*
X805825Y540375D01*
X805950Y540042D01*
X806117Y539792D01*
X806367Y539583D01*
X806700Y539500D01*
X807033Y539583D01*
X807283Y539792D01*
X807450Y540042D01*
X807575Y540375D01*
X807617Y540750D01*
X807575Y541125D01*
X807450Y541458D01*
X807283Y541708D01*
X807033Y541917D01*
X806700Y542000D01*
G01X801200Y551500D02*
Y555500D01*
X793800D01*
G01X801200Y559000D02*
Y563000D01*
X793800D01*
G01X800019Y570301D02*
X800352Y570093D01*
X800727Y569968D01*
X801061D01*
X801394Y570093D01*
X801644Y570301D01*
X801769Y570593D01*
X801686Y570885D01*
X801477Y571135D01*
X801102Y571301D01*
X800602Y571385D01*
X800311Y571551D01*
X800186Y571843D01*
X800269Y572135D01*
X800477Y572343D01*
X800769Y572468D01*
X801061D01*
X801352Y572385D01*
X801602Y572176D01*
G01X803161Y569968D02*
Y572468D01*
X804202D01*
X804536Y572343D01*
X804744Y572176D01*
X804827Y571843D01*
X804744Y571510D01*
X804494Y571301D01*
X804202Y571176D01*
X803161D01*
G01X804202D02*
X804827Y569968D01*
G01X807011D02*
X807094Y570510D01*
X807219Y570968D01*
X807386Y571385D01*
X807594Y571843D01*
X807927Y572468D01*
X806261D01*
G01X809402Y571010D02*
X809694Y571301D01*
X809944Y571468D01*
X810277Y571551D01*
X810569Y571468D01*
X810777Y571301D01*
X810944Y571051D01*
X810986Y570760D01*
X810944Y570510D01*
X810777Y570260D01*
X810527Y570051D01*
X810236Y569968D01*
X809902Y570051D01*
X809611Y570301D01*
X809444Y570676D01*
X809402Y571093D01*
X809486Y571635D01*
X809611Y571926D01*
X809819Y572218D01*
X810111Y572426D01*
X810402Y572468D01*
X810694Y572385D01*
X810902Y572176D01*
G01X812502Y572051D02*
X812752Y572301D01*
X813044Y572426D01*
X813377Y572468D01*
X813794Y572385D01*
X814086Y572176D01*
X814169Y571926D01*
X814127Y571676D01*
X813961Y571468D01*
X813127Y571051D01*
X812752Y570760D01*
X812502Y570343D01*
X812419Y569968D01*
X814169D01*
G01X790394Y572468D02*
Y568468D01*
X797794D01*
G01X800019Y574801D02*
X800352Y574593D01*
X800727Y574468D01*
X801061D01*
X801394Y574593D01*
X801644Y574801D01*
X801769Y575093D01*
X801686Y575385D01*
X801477Y575635D01*
X801102Y575801D01*
X800602Y575885D01*
X800311Y576051D01*
X800186Y576343D01*
X800269Y576635D01*
X800477Y576843D01*
X800769Y576968D01*
X801061D01*
X801352Y576885D01*
X801602Y576676D01*
G01X803161Y574468D02*
Y576968D01*
X804202D01*
X804536Y576843D01*
X804744Y576676D01*
X804827Y576343D01*
X804744Y576010D01*
X804494Y575801D01*
X804202Y575676D01*
X803161D01*
G01X804202D02*
X804827Y574468D01*
G01X807011D02*
X807094Y575010D01*
X807219Y575468D01*
X807386Y575885D01*
X807594Y576343D01*
X807927Y576968D01*
X806261D01*
G01X809402Y575510D02*
X809694Y575801D01*
X809944Y575968D01*
X810277Y576051D01*
X810569Y575968D01*
X810777Y575801D01*
X810944Y575551D01*
X810986Y575260D01*
X810944Y575010D01*
X810777Y574760D01*
X810527Y574551D01*
X810236Y574468D01*
X809902Y574551D01*
X809611Y574801D01*
X809444Y575176D01*
X809402Y575593D01*
X809486Y576135D01*
X809611Y576426D01*
X809819Y576718D01*
X810111Y576926D01*
X810402Y576968D01*
X810694Y576885D01*
X810902Y576676D01*
G01X812377Y574968D02*
X812627Y574676D01*
X812961Y574510D01*
X813336Y574468D01*
X813669Y574510D01*
X814002Y574718D01*
X814211Y574968D01*
X814252Y575218D01*
X814169Y575510D01*
X813877Y575718D01*
X813586Y575801D01*
X813211D01*
G01X813586D02*
X813836Y575926D01*
X814044Y576135D01*
X814127Y576385D01*
X814044Y576635D01*
X813836Y576843D01*
X813461Y576968D01*
X813086Y576926D01*
X812711Y576760D01*
G01X790394Y576968D02*
Y572968D01*
X797794D01*
G01X800019Y579301D02*
X800352Y579093D01*
X800727Y578968D01*
X801061D01*
X801394Y579093D01*
X801644Y579301D01*
X801769Y579593D01*
X801686Y579885D01*
X801477Y580135D01*
X801102Y580301D01*
X800602Y580385D01*
X800311Y580551D01*
X800186Y580843D01*
X800269Y581135D01*
X800477Y581343D01*
X800769Y581468D01*
X801061D01*
X801352Y581385D01*
X801602Y581176D01*
G01X803161Y578968D02*
Y581468D01*
X804202D01*
X804536Y581343D01*
X804744Y581176D01*
X804827Y580843D01*
X804744Y580510D01*
X804494Y580301D01*
X804202Y580176D01*
X803161D01*
G01X804202D02*
X804827Y578968D01*
G01X807011D02*
X807094Y579510D01*
X807219Y579968D01*
X807386Y580385D01*
X807594Y580843D01*
X807927Y581468D01*
X806261D01*
G01X809402Y580010D02*
X809694Y580301D01*
X809944Y580468D01*
X810277Y580551D01*
X810569Y580468D01*
X810777Y580301D01*
X810944Y580051D01*
X810986Y579760D01*
X810944Y579510D01*
X810777Y579260D01*
X810527Y579051D01*
X810236Y578968D01*
X809902Y579051D01*
X809611Y579301D01*
X809444Y579676D01*
X809402Y580093D01*
X809486Y580635D01*
X809611Y580926D01*
X809819Y581218D01*
X810111Y581426D01*
X810402Y581468D01*
X810694Y581385D01*
X810902Y581176D01*
G01X813294Y578968D02*
Y581468D01*
X812794Y580968D01*
G01Y578968D02*
X813794D01*
G01X790394Y581468D02*
Y577468D01*
X797794D01*
G01X799875Y583333D02*
X800208Y583125D01*
X800583Y583000D01*
X800917D01*
X801250Y583125D01*
X801500Y583333D01*
X801625Y583625D01*
X801542Y583917D01*
X801333Y584167D01*
X800958Y584333D01*
X800458Y584417D01*
X800167Y584583D01*
X800042Y584875D01*
X800125Y585167D01*
X800333Y585375D01*
X800625Y585500D01*
X800917D01*
X801208Y585417D01*
X801458Y585208D01*
G01X804767Y585292D02*
X804517Y585417D01*
X804225Y585500D01*
X803892D01*
X803517Y585375D01*
X803225Y585167D01*
X803017Y584917D01*
X802850Y584500D01*
X802808Y584125D01*
X802892Y583750D01*
X803017Y583500D01*
X803267Y583250D01*
X803558Y583083D01*
X803850Y583000D01*
X804142D01*
X804433Y583083D01*
X804683Y583208D01*
X804892Y583375D01*
G01X806950Y583000D02*
Y585500D01*
X806450Y585000D01*
G01Y583000D02*
X807450D01*
G01X809258Y585083D02*
X809508Y585333D01*
X809800Y585458D01*
X810133Y585500D01*
X810550Y585417D01*
X810842Y585208D01*
X810925Y584958D01*
X810883Y584708D01*
X810717Y584500D01*
X809883Y584083D01*
X809508Y583792D01*
X809258Y583375D01*
X809175Y583000D01*
X810925D01*
G01X813150D02*
X813442Y583042D01*
X813775Y583167D01*
X813983Y583375D01*
X814067Y583667D01*
X813983Y583958D01*
X813733Y584208D01*
X813358Y584333D01*
X812942D01*
X812692Y584417D01*
X812483Y584625D01*
X812400Y584917D01*
X812525Y585208D01*
X812817Y585417D01*
X813150Y585500D01*
X813483Y585417D01*
X813775Y585208D01*
X813900Y584917D01*
X813817Y584625D01*
X813608Y584417D01*
X813358Y584333D01*
X812942D01*
X812567Y584208D01*
X812317Y583958D01*
X812233Y583667D01*
X812317Y583375D01*
X812525Y583167D01*
X812858Y583042D01*
X813150Y583000D01*
G01X815333Y583500D02*
X815583Y583208D01*
X815917Y583042D01*
X816292Y583000D01*
X816625Y583042D01*
X816958Y583250D01*
X817167Y583500D01*
X817208Y583750D01*
X817125Y584042D01*
X816833Y584250D01*
X816542Y584333D01*
X816167D01*
G01X816542D02*
X816792Y584458D01*
X817000Y584667D01*
X817083Y584917D01*
X817000Y585167D01*
X816792Y585375D01*
X816417Y585500D01*
X816042Y585458D01*
X815667Y585292D01*
G01X794000Y645900D02*
X793958Y645567D01*
X793792Y645275D01*
X793542Y645025D01*
X793250Y644858D01*
X792917Y644775D01*
X792583D01*
X792250Y644858D01*
X791958Y645025D01*
X791708Y645275D01*
X791542Y645567D01*
X791500Y645900D01*
X791542Y646233D01*
X791708Y646525D01*
X791958Y646775D01*
X792250Y646942D01*
X792583Y647025D01*
X792917D01*
X793250Y646942D01*
X793542Y646775D01*
X793792Y646525D01*
X793958Y646233D01*
X794000Y645900D01*
G01X793333Y646233D02*
X794000Y646733D01*
G01Y649000D02*
X791500D01*
X792000Y648500D01*
G01X794000D02*
Y649500D01*
G01X791917Y651308D02*
X791667Y651558D01*
X791542Y651850D01*
X791500Y652183D01*
X791583Y652600D01*
X791792Y652892D01*
X792042Y652975D01*
X792292Y652933D01*
X792500Y652767D01*
X792917Y651933D01*
X793208Y651558D01*
X793625Y651308D01*
X794000Y651225D01*
Y652975D01*
G01X805000Y654517D02*
X802500D01*
Y655558D01*
X802625Y655892D01*
X802792Y656100D01*
X803125Y656183D01*
X803458Y656100D01*
X803667Y655850D01*
X803792Y655558D01*
Y654517D01*
G01Y655558D02*
X805000Y656183D01*
G01X804625Y657533D02*
X804833Y657783D01*
X804958Y658075D01*
X805000Y658450D01*
X804917Y658825D01*
X804750Y659117D01*
X804458Y659325D01*
X804125Y659367D01*
X803792Y659283D01*
X803583Y659075D01*
X803417Y658783D01*
X803375Y658492D01*
X803417Y658200D01*
X803583Y657825D01*
X802500Y657950D01*
Y659075D01*
G01X805000Y661550D02*
X804958Y661842D01*
X804833Y662175D01*
X804625Y662383D01*
X804333Y662467D01*
X804042Y662383D01*
X803792Y662133D01*
X803667Y661758D01*
Y661342D01*
X803583Y661092D01*
X803375Y660883D01*
X803083Y660800D01*
X802792Y660925D01*
X802583Y661217D01*
X802500Y661550D01*
X802583Y661883D01*
X802792Y662175D01*
X803083Y662300D01*
X803375Y662217D01*
X803583Y662008D01*
X803667Y661758D01*
Y661342D01*
X803792Y660967D01*
X804042Y660717D01*
X804333Y660633D01*
X804625Y660717D01*
X804833Y660925D01*
X804958Y661258D01*
X805000Y661550D01*
G01X802500Y664650D02*
X802583Y664317D01*
X802792Y664067D01*
X803042Y663900D01*
X803375Y663775D01*
X803750Y663733D01*
X804125Y663775D01*
X804458Y663900D01*
X804708Y664067D01*
X804917Y664317D01*
X805000Y664650D01*
X804917Y664983D01*
X804708Y665233D01*
X804458Y665400D01*
X804125Y665525D01*
X803750Y665567D01*
X803375Y665525D01*
X803042Y665400D01*
X802792Y665233D01*
X802583Y664983D01*
X802500Y664650D01*
G01X790500Y656300D02*
X794500D01*
Y663700D01*
G01X798208Y656267D02*
X798083Y656017D01*
X798000Y655725D01*
Y655392D01*
X798125Y655017D01*
X798333Y654725D01*
X798583Y654517D01*
X799000Y654350D01*
X799375Y654308D01*
X799750Y654392D01*
X800000Y654517D01*
X800250Y654767D01*
X800417Y655058D01*
X800500Y655350D01*
Y655642D01*
X800417Y655933D01*
X800292Y656183D01*
X800125Y656392D01*
G01X800000Y657533D02*
X800292Y657783D01*
X800458Y658117D01*
X800500Y658492D01*
X800458Y658825D01*
X800250Y659158D01*
X800000Y659367D01*
X799750Y659408D01*
X799458Y659325D01*
X799250Y659033D01*
X799167Y658742D01*
Y658367D01*
G01Y658742D02*
X799042Y658992D01*
X798833Y659200D01*
X798583Y659283D01*
X798333Y659200D01*
X798125Y658992D01*
X798000Y658617D01*
X798042Y658242D01*
X798208Y657867D01*
G01X798417Y660758D02*
X798167Y661008D01*
X798042Y661300D01*
X798000Y661633D01*
X798083Y662050D01*
X798292Y662342D01*
X798542Y662425D01*
X798792Y662383D01*
X799000Y662217D01*
X799417Y661383D01*
X799708Y661008D01*
X800125Y660758D01*
X800500Y660675D01*
Y662425D01*
G01Y664650D02*
X798000D01*
X798500Y664150D01*
G01X800500D02*
Y665150D01*
G01X803500Y712517D02*
X801000D01*
Y713558D01*
X801125Y713892D01*
X801292Y714100D01*
X801625Y714183D01*
X801958Y714100D01*
X802167Y713850D01*
X802292Y713558D01*
Y712517D01*
G01Y713558D02*
X803500Y714183D01*
G01Y716950D02*
X801000D01*
X802792Y715408D01*
Y717492D01*
G01X803500Y719550D02*
X803458Y719842D01*
X803333Y720175D01*
X803125Y720383D01*
X802833Y720467D01*
X802542Y720383D01*
X802292Y720133D01*
X802167Y719758D01*
Y719342D01*
X802083Y719092D01*
X801875Y718883D01*
X801583Y718800D01*
X801292Y718925D01*
X801083Y719217D01*
X801000Y719550D01*
X801083Y719883D01*
X801292Y720175D01*
X801583Y720300D01*
X801875Y720217D01*
X802083Y720008D01*
X802167Y719758D01*
Y719342D01*
X802292Y718967D01*
X802542Y718717D01*
X802833Y718633D01*
X803125Y718717D01*
X803333Y718925D01*
X803458Y719258D01*
X803500Y719550D01*
G01Y723150D02*
X801000D01*
X802792Y721608D01*
Y723692D01*
G01X799500Y712517D02*
X797000D01*
Y713558D01*
X797125Y713892D01*
X797292Y714100D01*
X797625Y714183D01*
X797958Y714100D01*
X798167Y713850D01*
X798292Y713558D01*
Y712517D01*
G01Y713558D02*
X799500Y714183D01*
G01Y716950D02*
X797000D01*
X798792Y715408D01*
Y717492D01*
G01X799500Y719467D02*
X798958Y719550D01*
X798500Y719675D01*
X798083Y719842D01*
X797625Y720050D01*
X797000Y720383D01*
Y718717D01*
G01X799500Y722650D02*
X799458Y722942D01*
X799333Y723275D01*
X799125Y723483D01*
X798833Y723567D01*
X798542Y723483D01*
X798292Y723233D01*
X798167Y722858D01*
Y722442D01*
X798083Y722192D01*
X797875Y721983D01*
X797583Y721900D01*
X797292Y722025D01*
X797083Y722317D01*
X797000Y722650D01*
X797083Y722983D01*
X797292Y723275D01*
X797583Y723400D01*
X797875Y723317D01*
X798083Y723108D01*
X798167Y722858D01*
Y722442D01*
X798292Y722067D01*
X798542Y721817D01*
X798833Y721733D01*
X799125Y721817D01*
X799333Y722025D01*
X799458Y722358D01*
X799500Y722650D01*
G01X807500Y712517D02*
X805000D01*
Y713558D01*
X805125Y713892D01*
X805292Y714100D01*
X805625Y714183D01*
X805958Y714100D01*
X806167Y713850D01*
X806292Y713558D01*
Y712517D01*
G01Y713558D02*
X807500Y714183D01*
G01Y716950D02*
X805000D01*
X806792Y715408D01*
Y717492D01*
G01X807500Y719467D02*
X806958Y719550D01*
X806500Y719675D01*
X806083Y719842D01*
X805625Y720050D01*
X805000Y720383D01*
Y718717D01*
G01X807500Y722567D02*
X806958Y722650D01*
X806500Y722775D01*
X806083Y722942D01*
X805625Y723150D01*
X805000Y723483D01*
Y721817D01*
G01X792708Y714267D02*
X792583Y714017D01*
X792500Y713725D01*
Y713392D01*
X792625Y713017D01*
X792833Y712725D01*
X793083Y712517D01*
X793500Y712350D01*
X793875Y712308D01*
X794250Y712392D01*
X794500Y712517D01*
X794750Y712767D01*
X794917Y713058D01*
X795000Y713350D01*
Y713642D01*
X794917Y713933D01*
X794792Y714183D01*
X794625Y714392D01*
G01X794500Y715533D02*
X794792Y715783D01*
X794958Y716117D01*
X795000Y716492D01*
X794958Y716825D01*
X794750Y717158D01*
X794500Y717367D01*
X794250Y717408D01*
X793958Y717325D01*
X793750Y717033D01*
X793667Y716742D01*
Y716367D01*
G01Y716742D02*
X793542Y716992D01*
X793333Y717200D01*
X793083Y717283D01*
X792833Y717200D01*
X792625Y716992D01*
X792500Y716617D01*
X792542Y716242D01*
X792708Y715867D01*
G01X792500Y719550D02*
X792583Y719217D01*
X792792Y718967D01*
X793042Y718800D01*
X793375Y718675D01*
X793750Y718633D01*
X794125Y718675D01*
X794458Y718800D01*
X794708Y718967D01*
X794917Y719217D01*
X795000Y719550D01*
X794917Y719883D01*
X794708Y720133D01*
X794458Y720300D01*
X794125Y720425D01*
X793750Y720467D01*
X793375Y720425D01*
X793042Y720300D01*
X792792Y720133D01*
X792583Y719883D01*
X792500Y719550D01*
G01X795000Y723150D02*
X792500D01*
X794292Y721608D01*
Y723692D01*
G01X800000Y726300D02*
X804000D01*
Y733700D01*
G01X796000Y726300D02*
X800000D01*
Y733700D01*
G01X808000D02*
X804000D01*
Y726300D01*
G01X790208Y784267D02*
X790083Y784017D01*
X790000Y783725D01*
Y783392D01*
X790125Y783017D01*
X790333Y782725D01*
X790583Y782517D01*
X791000Y782350D01*
X791375Y782308D01*
X791750Y782392D01*
X792000Y782517D01*
X792250Y782767D01*
X792417Y783058D01*
X792500Y783350D01*
Y783642D01*
X792417Y783933D01*
X792292Y784183D01*
X792125Y784392D01*
G01X790417Y785658D02*
X790167Y785908D01*
X790042Y786200D01*
X790000Y786533D01*
X790083Y786950D01*
X790292Y787242D01*
X790542Y787325D01*
X790792Y787283D01*
X791000Y787117D01*
X791417Y786283D01*
X791708Y785908D01*
X792125Y785658D01*
X792500Y785575D01*
Y787325D01*
G01X791458Y788758D02*
X791167Y789050D01*
X791000Y789300D01*
X790917Y789633D01*
X791000Y789925D01*
X791167Y790133D01*
X791417Y790300D01*
X791708Y790342D01*
X791958Y790300D01*
X792208Y790133D01*
X792417Y789883D01*
X792500Y789592D01*
X792417Y789258D01*
X792167Y788967D01*
X791792Y788800D01*
X791375Y788758D01*
X790833Y788842D01*
X790542Y788967D01*
X790250Y789175D01*
X790042Y789467D01*
X790000Y789758D01*
X790083Y790050D01*
X790292Y790258D01*
G01X792000Y791733D02*
X792292Y791983D01*
X792458Y792317D01*
X792500Y792692D01*
X792458Y793025D01*
X792250Y793358D01*
X792000Y793567D01*
X791750Y793608D01*
X791458Y793525D01*
X791250Y793233D01*
X791167Y792942D01*
Y792567D01*
G01Y792942D02*
X791042Y793192D01*
X790833Y793400D01*
X790583Y793483D01*
X790333Y793400D01*
X790125Y793192D01*
X790000Y792817D01*
X790042Y792442D01*
X790208Y792067D01*
G01X792700Y858500D02*
Y848500D01*
G01X807200Y849000D02*
Y853000D01*
X799800D01*
G01X790500Y874700D02*
Y861300D01*
G01X796967Y864000D02*
Y866500D01*
X798008D01*
X798342Y866375D01*
X798550Y866208D01*
X798633Y865875D01*
X798550Y865542D01*
X798300Y865333D01*
X798008Y865208D01*
X796967D01*
G01X798008D02*
X798633Y864000D01*
G01X800900D02*
Y866500D01*
X800400Y866000D01*
G01Y864000D02*
X801400D01*
G01X803083Y864375D02*
X803333Y864167D01*
X803625Y864042D01*
X804000Y864000D01*
X804375Y864083D01*
X804667Y864250D01*
X804875Y864542D01*
X804917Y864875D01*
X804833Y865208D01*
X804625Y865417D01*
X804333Y865583D01*
X804042Y865625D01*
X803750Y865583D01*
X803375Y865417D01*
X803500Y866500D01*
X804625D01*
G01X807100Y864000D02*
X807392Y864042D01*
X807725Y864167D01*
X807933Y864375D01*
X808017Y864667D01*
X807933Y864958D01*
X807683Y865208D01*
X807308Y865333D01*
X806892D01*
X806642Y865417D01*
X806433Y865625D01*
X806350Y865917D01*
X806475Y866208D01*
X806767Y866417D01*
X807100Y866500D01*
X807433Y866417D01*
X807725Y866208D01*
X807850Y865917D01*
X807767Y865625D01*
X807558Y865417D01*
X807308Y865333D01*
X806892D01*
X806517Y865208D01*
X806267Y864958D01*
X806183Y864667D01*
X806267Y864375D01*
X806475Y864167D01*
X806808Y864042D01*
X807100Y864000D01*
G01X809283Y864375D02*
X809533Y864167D01*
X809825Y864042D01*
X810200Y864000D01*
X810575Y864083D01*
X810867Y864250D01*
X811075Y864542D01*
X811117Y864875D01*
X811033Y865208D01*
X810825Y865417D01*
X810533Y865583D01*
X810242Y865625D01*
X809950Y865583D01*
X809575Y865417D01*
X809700Y866500D01*
X810825D01*
G01X798817Y874792D02*
X798567Y874917D01*
X798275Y875000D01*
X797942D01*
X797567Y874875D01*
X797275Y874667D01*
X797067Y874417D01*
X796900Y874000D01*
X796858Y873625D01*
X796942Y873250D01*
X797067Y873000D01*
X797317Y872750D01*
X797608Y872583D01*
X797900Y872500D01*
X798192D01*
X798483Y872583D01*
X798733Y872708D01*
X798942Y872875D01*
G01X801000Y872500D02*
X801292Y872542D01*
X801625Y872667D01*
X801833Y872875D01*
X801917Y873167D01*
X801833Y873458D01*
X801583Y873708D01*
X801208Y873833D01*
X800792D01*
X800542Y873917D01*
X800333Y874125D01*
X800250Y874417D01*
X800375Y874708D01*
X800667Y874917D01*
X801000Y875000D01*
X801333Y874917D01*
X801625Y874708D01*
X801750Y874417D01*
X801667Y874125D01*
X801458Y873917D01*
X801208Y873833D01*
X800792D01*
X800417Y873708D01*
X800167Y873458D01*
X800083Y873167D01*
X800167Y872875D01*
X800375Y872667D01*
X800708Y872542D01*
X801000Y872500D01*
G01X803308Y874583D02*
X803558Y874833D01*
X803850Y874958D01*
X804183Y875000D01*
X804600Y874917D01*
X804892Y874708D01*
X804975Y874458D01*
X804933Y874208D01*
X804767Y874000D01*
X803933Y873583D01*
X803558Y873292D01*
X803308Y872875D01*
X803225Y872500D01*
X804975D01*
G01X798817Y870292D02*
X798567Y870417D01*
X798275Y870500D01*
X797942D01*
X797567Y870375D01*
X797275Y870167D01*
X797067Y869917D01*
X796900Y869500D01*
X796858Y869125D01*
X796942Y868750D01*
X797067Y868500D01*
X797317Y868250D01*
X797608Y868083D01*
X797900Y868000D01*
X798192D01*
X798483Y868083D01*
X798733Y868208D01*
X798942Y868375D01*
G01X801500Y868000D02*
Y870500D01*
X799958Y868708D01*
X802042D01*
G01X803308Y870083D02*
X803558Y870333D01*
X803850Y870458D01*
X804183Y870500D01*
X804600Y870417D01*
X804892Y870208D01*
X804975Y869958D01*
X804933Y869708D01*
X804767Y869500D01*
X803933Y869083D01*
X803558Y868792D01*
X803308Y868375D01*
X803225Y868000D01*
X804975D01*
G01X797500Y879467D02*
X795000D01*
Y880508D01*
X795125Y880842D01*
X795292Y881050D01*
X795625Y881133D01*
X795958Y881050D01*
X796167Y880800D01*
X796292Y880508D01*
Y879467D01*
G01Y880508D02*
X797500Y881133D01*
G01Y883400D02*
X795000D01*
X795500Y882900D01*
G01X797500D02*
Y883900D01*
G01X797125Y885583D02*
X797333Y885833D01*
X797458Y886125D01*
X797500Y886500D01*
X797417Y886875D01*
X797250Y887167D01*
X796958Y887375D01*
X796625Y887417D01*
X796292Y887333D01*
X796083Y887125D01*
X795917Y886833D01*
X795875Y886542D01*
X795917Y886250D01*
X796083Y885875D01*
X795000Y886000D01*
Y887125D01*
G01X797500Y889600D02*
X797458Y889892D01*
X797333Y890225D01*
X797125Y890433D01*
X796833Y890517D01*
X796542Y890433D01*
X796292Y890183D01*
X796167Y889808D01*
Y889392D01*
X796083Y889142D01*
X795875Y888933D01*
X795583Y888850D01*
X795292Y888975D01*
X795083Y889267D01*
X795000Y889600D01*
X795083Y889933D01*
X795292Y890225D01*
X795583Y890350D01*
X795875Y890267D01*
X796083Y890058D01*
X796167Y889808D01*
Y889392D01*
X796292Y889017D01*
X796542Y888767D01*
X796833Y888683D01*
X797125Y888767D01*
X797333Y888975D01*
X797458Y889308D01*
X797500Y889600D01*
G01Y892617D02*
X796958Y892700D01*
X796500Y892825D01*
X796083Y892992D01*
X795625Y893200D01*
X795000Y893533D01*
Y891867D01*
G01X802000Y879467D02*
X799500D01*
Y880508D01*
X799625Y880842D01*
X799792Y881050D01*
X800125Y881133D01*
X800458Y881050D01*
X800667Y880800D01*
X800792Y880508D01*
Y879467D01*
G01Y880508D02*
X802000Y881133D01*
G01Y883400D02*
X799500D01*
X800000Y882900D01*
G01X802000D02*
Y883900D01*
G01X801625Y885583D02*
X801833Y885833D01*
X801958Y886125D01*
X802000Y886500D01*
X801917Y886875D01*
X801750Y887167D01*
X801458Y887375D01*
X801125Y887417D01*
X800792Y887333D01*
X800583Y887125D01*
X800417Y886833D01*
X800375Y886542D01*
X800417Y886250D01*
X800583Y885875D01*
X799500Y886000D01*
Y887125D01*
G01X802000Y889600D02*
X801958Y889892D01*
X801833Y890225D01*
X801625Y890433D01*
X801333Y890517D01*
X801042Y890433D01*
X800792Y890183D01*
X800667Y889808D01*
Y889392D01*
X800583Y889142D01*
X800375Y888933D01*
X800083Y888850D01*
X799792Y888975D01*
X799583Y889267D01*
X799500Y889600D01*
X799583Y889933D01*
X799792Y890225D01*
X800083Y890350D01*
X800375Y890267D01*
X800583Y890058D01*
X800667Y889808D01*
Y889392D01*
X800792Y889017D01*
X801042Y888767D01*
X801333Y888683D01*
X801625Y888767D01*
X801833Y888975D01*
X801958Y889308D01*
X802000Y889600D01*
G01Y893200D02*
X799500D01*
X801292Y891658D01*
Y893742D01*
G01X806500Y879467D02*
X804000D01*
Y880508D01*
X804125Y880842D01*
X804292Y881050D01*
X804625Y881133D01*
X804958Y881050D01*
X805167Y880800D01*
X805292Y880508D01*
Y879467D01*
G01Y880508D02*
X806500Y881133D01*
G01X804417Y882608D02*
X804167Y882858D01*
X804042Y883150D01*
X804000Y883483D01*
X804083Y883900D01*
X804292Y884192D01*
X804542Y884275D01*
X804792Y884233D01*
X805000Y884067D01*
X805417Y883233D01*
X805708Y882858D01*
X806125Y882608D01*
X806500Y882525D01*
Y884275D01*
G01X804000Y886500D02*
X804083Y886167D01*
X804292Y885917D01*
X804542Y885750D01*
X804875Y885625D01*
X805250Y885583D01*
X805625Y885625D01*
X805958Y885750D01*
X806208Y885917D01*
X806417Y886167D01*
X806500Y886500D01*
X806417Y886833D01*
X806208Y887083D01*
X805958Y887250D01*
X805625Y887375D01*
X805250Y887417D01*
X804875Y887375D01*
X804542Y887250D01*
X804292Y887083D01*
X804083Y886833D01*
X804000Y886500D01*
G01X806125Y888683D02*
X806333Y888933D01*
X806458Y889225D01*
X806500Y889600D01*
X806417Y889975D01*
X806250Y890267D01*
X805958Y890475D01*
X805625Y890517D01*
X805292Y890433D01*
X805083Y890225D01*
X804917Y889933D01*
X804875Y889642D01*
X804917Y889350D01*
X805083Y888975D01*
X804000Y889100D01*
Y890225D01*
G01X806125Y891783D02*
X806333Y892033D01*
X806458Y892325D01*
X806500Y892700D01*
X806417Y893075D01*
X806250Y893367D01*
X805958Y893575D01*
X805625Y893617D01*
X805292Y893533D01*
X805083Y893325D01*
X804917Y893033D01*
X804875Y892742D01*
X804917Y892450D01*
X805083Y892075D01*
X804000Y892200D01*
Y893325D01*
G01X810667Y348925D02*
X810875Y349258D01*
X811000Y349633D01*
Y349967D01*
X810875Y350300D01*
X810667Y350550D01*
X810375Y350675D01*
X810083Y350592D01*
X809833Y350383D01*
X809667Y350008D01*
X809583Y349508D01*
X809417Y349217D01*
X809125Y349092D01*
X808833Y349175D01*
X808625Y349383D01*
X808500Y349675D01*
Y349967D01*
X808583Y350258D01*
X808792Y350508D01*
G01X811000Y352067D02*
X808500D01*
Y353108D01*
X808625Y353442D01*
X808792Y353650D01*
X809125Y353733D01*
X809458Y353650D01*
X809667Y353400D01*
X809792Y353108D01*
Y352067D01*
G01Y353108D02*
X811000Y353733D01*
G01Y356000D02*
X810958Y356292D01*
X810833Y356625D01*
X810625Y356833D01*
X810333Y356917D01*
X810042Y356833D01*
X809792Y356583D01*
X809667Y356208D01*
Y355792D01*
X809583Y355542D01*
X809375Y355333D01*
X809083Y355250D01*
X808792Y355375D01*
X808583Y355667D01*
X808500Y356000D01*
X808583Y356333D01*
X808792Y356625D01*
X809083Y356750D01*
X809375Y356667D01*
X809583Y356458D01*
X809667Y356208D01*
Y355792D01*
X809792Y355417D01*
X810042Y355167D01*
X810333Y355083D01*
X810625Y355167D01*
X810833Y355375D01*
X810958Y355708D01*
X811000Y356000D01*
G01X808917Y358308D02*
X808667Y358558D01*
X808542Y358850D01*
X808500Y359183D01*
X808583Y359600D01*
X808792Y359892D01*
X809042Y359975D01*
X809292Y359933D01*
X809500Y359767D01*
X809917Y358933D01*
X810208Y358558D01*
X810625Y358308D01*
X811000Y358225D01*
Y359975D01*
G01Y362117D02*
X810458Y362200D01*
X810000Y362325D01*
X809583Y362492D01*
X809125Y362700D01*
X808500Y363033D01*
Y361367D01*
G01X814067Y360500D02*
Y363000D01*
X815067D01*
X815400Y362875D01*
X815650Y362583D01*
X815733Y362250D01*
X815650Y361917D01*
X815442Y361667D01*
X815067Y361542D01*
X814067D01*
G01X818250Y361750D02*
X819083D01*
Y361000D01*
X818833Y360750D01*
X818542Y360583D01*
X818125Y360500D01*
X817708Y360583D01*
X817417Y360750D01*
X817167Y361000D01*
X817000Y361292D01*
X816917Y361625D01*
Y361917D01*
X817000Y362167D01*
X817167Y362458D01*
X817417Y362708D01*
X817667Y362875D01*
X818000Y363000D01*
X818292D01*
X818625Y362917D01*
X818875Y362750D01*
G01X820183Y360875D02*
X820433Y360667D01*
X820725Y360542D01*
X821100Y360500D01*
X821475Y360583D01*
X821767Y360750D01*
X821975Y361042D01*
X822017Y361375D01*
X821933Y361708D01*
X821725Y361917D01*
X821433Y362083D01*
X821142Y362125D01*
X820850Y362083D01*
X820475Y361917D01*
X820600Y363000D01*
X821725D01*
G01X814838Y417007D02*
X812338D01*
Y418007D01*
X812463Y418340D01*
X812755Y418590D01*
X813088Y418673D01*
X813421Y418590D01*
X813671Y418382D01*
X813796Y418007D01*
Y417007D01*
G01X812546Y421857D02*
X812421Y421607D01*
X812338Y421315D01*
Y420982D01*
X812463Y420607D01*
X812671Y420315D01*
X812921Y420107D01*
X813338Y419940D01*
X813713Y419898D01*
X814088Y419982D01*
X814338Y420107D01*
X814588Y420357D01*
X814755Y420648D01*
X814838Y420940D01*
Y421232D01*
X814755Y421523D01*
X814630Y421773D01*
X814463Y421982D01*
G01X812755Y423248D02*
X812505Y423498D01*
X812380Y423790D01*
X812338Y424123D01*
X812421Y424540D01*
X812630Y424832D01*
X812880Y424915D01*
X813130Y424873D01*
X813338Y424707D01*
X813755Y423873D01*
X814046Y423498D01*
X814463Y423248D01*
X814838Y423165D01*
Y424915D01*
G01X812755Y426348D02*
X812505Y426598D01*
X812380Y426890D01*
X812338Y427223D01*
X812421Y427640D01*
X812630Y427932D01*
X812880Y428015D01*
X813130Y427973D01*
X813338Y427807D01*
X813755Y426973D01*
X814046Y426598D01*
X814463Y426348D01*
X814838Y426265D01*
Y428015D01*
G01X813796Y429448D02*
X813505Y429740D01*
X813338Y429990D01*
X813255Y430323D01*
X813338Y430615D01*
X813505Y430823D01*
X813755Y430990D01*
X814046Y431032D01*
X814296Y430990D01*
X814546Y430823D01*
X814755Y430573D01*
X814838Y430282D01*
X814755Y429948D01*
X814505Y429657D01*
X814130Y429490D01*
X813713Y429448D01*
X813171Y429532D01*
X812880Y429657D01*
X812588Y429865D01*
X812380Y430157D01*
X812338Y430448D01*
X812421Y430740D01*
X812630Y430948D01*
G01X819500Y416967D02*
X817000D01*
Y417967D01*
X817125Y418300D01*
X817417Y418550D01*
X817750Y418633D01*
X818083Y418550D01*
X818333Y418342D01*
X818458Y417967D01*
Y416967D01*
G01X817208Y421817D02*
X817083Y421567D01*
X817000Y421275D01*
Y420942D01*
X817125Y420567D01*
X817333Y420275D01*
X817583Y420067D01*
X818000Y419900D01*
X818375Y419858D01*
X818750Y419942D01*
X819000Y420067D01*
X819250Y420317D01*
X819417Y420608D01*
X819500Y420900D01*
Y421192D01*
X819417Y421483D01*
X819292Y421733D01*
X819125Y421942D01*
G01X817417Y423208D02*
X817167Y423458D01*
X817042Y423750D01*
X817000Y424083D01*
X817083Y424500D01*
X817292Y424792D01*
X817542Y424875D01*
X817792Y424833D01*
X818000Y424667D01*
X818417Y423833D01*
X818708Y423458D01*
X819125Y423208D01*
X819500Y423125D01*
Y424875D01*
G01X817417Y426308D02*
X817167Y426558D01*
X817042Y426850D01*
X817000Y427183D01*
X817083Y427600D01*
X817292Y427892D01*
X817542Y427975D01*
X817792Y427933D01*
X818000Y427767D01*
X818417Y426933D01*
X818708Y426558D01*
X819125Y426308D01*
X819500Y426225D01*
Y427975D01*
G01Y430117D02*
X818958Y430200D01*
X818500Y430325D01*
X818083Y430492D01*
X817625Y430700D01*
X817000Y431033D01*
Y429367D01*
G01X823500Y412467D02*
X821000D01*
Y413467D01*
X821125Y413800D01*
X821417Y414050D01*
X821750Y414133D01*
X822083Y414050D01*
X822333Y413842D01*
X822458Y413467D01*
Y412467D01*
G01X823500Y415567D02*
X821000D01*
Y416608D01*
X821125Y416942D01*
X821292Y417150D01*
X821625Y417233D01*
X821958Y417150D01*
X822167Y416900D01*
X822292Y416608D01*
Y415567D01*
G01Y416608D02*
X823500Y417233D01*
G01Y419500D02*
X821000D01*
X821500Y419000D01*
G01X823500D02*
Y420000D01*
G01X821417Y421808D02*
X821167Y422058D01*
X821042Y422350D01*
X821000Y422683D01*
X821083Y423100D01*
X821292Y423392D01*
X821542Y423475D01*
X821792Y423433D01*
X822000Y423267D01*
X822417Y422433D01*
X822708Y422058D01*
X823125Y421808D01*
X823500Y421725D01*
Y423475D01*
G01X821417Y424908D02*
X821167Y425158D01*
X821042Y425450D01*
X821000Y425783D01*
X821083Y426200D01*
X821292Y426492D01*
X821542Y426575D01*
X821792Y426533D01*
X822000Y426367D01*
X822417Y425533D01*
X822708Y425158D01*
X823125Y424908D01*
X823500Y424825D01*
Y426575D01*
G01X820500Y402300D02*
X824500D01*
Y409700D01*
G01X809500Y416967D02*
X807000D01*
Y417967D01*
X807125Y418300D01*
X807417Y418550D01*
X807750Y418633D01*
X808083Y418550D01*
X808333Y418342D01*
X808458Y417967D01*
Y416967D01*
G01X807208Y421817D02*
X807083Y421567D01*
X807000Y421275D01*
Y420942D01*
X807125Y420567D01*
X807333Y420275D01*
X807583Y420067D01*
X808000Y419900D01*
X808375Y419858D01*
X808750Y419942D01*
X809000Y420067D01*
X809250Y420317D01*
X809417Y420608D01*
X809500Y420900D01*
Y421192D01*
X809417Y421483D01*
X809292Y421733D01*
X809125Y421942D01*
G01X807417Y423208D02*
X807167Y423458D01*
X807042Y423750D01*
X807000Y424083D01*
X807083Y424500D01*
X807292Y424792D01*
X807542Y424875D01*
X807792Y424833D01*
X808000Y424667D01*
X808417Y423833D01*
X808708Y423458D01*
X809125Y423208D01*
X809500Y423125D01*
Y424875D01*
G01X807417Y426308D02*
X807167Y426558D01*
X807042Y426850D01*
X807000Y427183D01*
X807083Y427600D01*
X807292Y427892D01*
X807542Y427975D01*
X807792Y427933D01*
X808000Y427767D01*
X808417Y426933D01*
X808708Y426558D01*
X809125Y426308D01*
X809500Y426225D01*
Y427975D01*
G01X809125Y429283D02*
X809333Y429533D01*
X809458Y429825D01*
X809500Y430200D01*
X809417Y430575D01*
X809250Y430867D01*
X808958Y431075D01*
X808625Y431117D01*
X808292Y431033D01*
X808083Y430825D01*
X807917Y430533D01*
X807875Y430242D01*
X807917Y429950D01*
X808083Y429575D01*
X807000Y429700D01*
Y430825D01*
G01X820000Y472067D02*
X817500D01*
Y473067D01*
X817625Y473400D01*
X817917Y473650D01*
X818250Y473733D01*
X818583Y473650D01*
X818833Y473442D01*
X818958Y473067D01*
Y472067D01*
G01X818750Y476250D02*
Y477083D01*
X819500D01*
X819750Y476833D01*
X819917Y476542D01*
X820000Y476125D01*
X819917Y475708D01*
X819750Y475417D01*
X819500Y475167D01*
X819208Y475000D01*
X818875Y474917D01*
X818583D01*
X818333Y475000D01*
X818042Y475167D01*
X817792Y475417D01*
X817625Y475667D01*
X817500Y476000D01*
Y476292D01*
X817583Y476625D01*
X817750Y476875D01*
G01X818958Y478308D02*
X818667Y478600D01*
X818500Y478850D01*
X818417Y479183D01*
X818500Y479475D01*
X818667Y479683D01*
X818917Y479850D01*
X819208Y479892D01*
X819458Y479850D01*
X819708Y479683D01*
X819917Y479433D01*
X820000Y479142D01*
X819917Y478808D01*
X819667Y478517D01*
X819292Y478350D01*
X818875Y478308D01*
X818333Y478392D01*
X818042Y478517D01*
X817750Y478725D01*
X817542Y479017D01*
X817500Y479308D01*
X817583Y479600D01*
X817792Y479808D01*
G01X813500Y507417D02*
X811000D01*
Y508417D01*
X811125Y508750D01*
X811417Y509000D01*
X811750Y509083D01*
X812083Y509000D01*
X812333Y508792D01*
X812458Y508417D01*
Y507417D01*
G01X813500Y510517D02*
X811000D01*
Y511558D01*
X811125Y511892D01*
X811292Y512100D01*
X811625Y512183D01*
X811958Y512100D01*
X812167Y511850D01*
X812292Y511558D01*
Y510517D01*
G01Y511558D02*
X813500Y512183D01*
G01X813208Y513742D02*
X813417Y514033D01*
X813500Y514367D01*
X813417Y514700D01*
X813167Y514992D01*
X812792Y515200D01*
X812417Y515283D01*
X811958D01*
X811583Y515200D01*
X811250Y514992D01*
X811083Y514742D01*
X811000Y514450D01*
X811083Y514117D01*
X811250Y513867D01*
X811500Y513700D01*
X811833Y513617D01*
X812125Y513700D01*
X812417Y513908D01*
X812583Y514158D01*
X812625Y514450D01*
X812542Y514783D01*
X812333Y515033D01*
X811958Y515283D01*
G01X811000Y517550D02*
X811083Y517217D01*
X811292Y516967D01*
X811542Y516800D01*
X811875Y516675D01*
X812250Y516633D01*
X812625Y516675D01*
X812958Y516800D01*
X813208Y516967D01*
X813417Y517217D01*
X813500Y517550D01*
X813417Y517883D01*
X813208Y518133D01*
X812958Y518300D01*
X812625Y518425D01*
X812250Y518467D01*
X811875Y518425D01*
X811542Y518300D01*
X811292Y518133D01*
X811083Y517883D01*
X811000Y517550D01*
G01X813500Y520650D02*
X811000D01*
X811500Y520150D01*
G01X813500D02*
Y521150D01*
G01X813000Y522833D02*
X813292Y523083D01*
X813458Y523417D01*
X813500Y523792D01*
X813458Y524125D01*
X813250Y524458D01*
X813000Y524667D01*
X812750Y524708D01*
X812458Y524625D01*
X812250Y524333D01*
X812167Y524042D01*
Y523667D01*
G01Y524042D02*
X812042Y524292D01*
X811833Y524500D01*
X811583Y524583D01*
X811333Y524500D01*
X811125Y524292D01*
X811000Y523917D01*
X811042Y523542D01*
X811208Y523167D01*
G01X811500Y712517D02*
X809000D01*
Y713558D01*
X809125Y713892D01*
X809292Y714100D01*
X809625Y714183D01*
X809958Y714100D01*
X810167Y713850D01*
X810292Y713558D01*
Y712517D01*
G01Y713558D02*
X811500Y714183D01*
G01Y716950D02*
X809000D01*
X810792Y715408D01*
Y717492D01*
G01X811500Y719550D02*
X811458Y719842D01*
X811333Y720175D01*
X811125Y720383D01*
X810833Y720467D01*
X810542Y720383D01*
X810292Y720133D01*
X810167Y719758D01*
Y719342D01*
X810083Y719092D01*
X809875Y718883D01*
X809583Y718800D01*
X809292Y718925D01*
X809083Y719217D01*
X809000Y719550D01*
X809083Y719883D01*
X809292Y720175D01*
X809583Y720300D01*
X809875Y720217D01*
X810083Y720008D01*
X810167Y719758D01*
Y719342D01*
X810292Y718967D01*
X810542Y718717D01*
X810833Y718633D01*
X811125Y718717D01*
X811333Y718925D01*
X811458Y719258D01*
X811500Y719550D01*
G01X811125Y721733D02*
X811333Y721983D01*
X811458Y722275D01*
X811500Y722650D01*
X811417Y723025D01*
X811250Y723317D01*
X810958Y723525D01*
X810625Y723567D01*
X810292Y723483D01*
X810083Y723275D01*
X809917Y722983D01*
X809875Y722692D01*
X809917Y722400D01*
X810083Y722025D01*
X809000Y722150D01*
Y723275D01*
G01X808000Y726300D02*
X812000D01*
Y733700D01*
G01X813517Y843500D02*
Y846000D01*
X814558D01*
X814892Y845875D01*
X815100Y845708D01*
X815183Y845375D01*
X815100Y845042D01*
X814850Y844833D01*
X814558Y844708D01*
X813517D01*
G01X814558D02*
X815183Y843500D01*
G01X817950D02*
Y846000D01*
X816408Y844208D01*
X818492D01*
G01X821050Y843500D02*
Y846000D01*
X819508Y844208D01*
X821592D01*
G01X822733Y844000D02*
X822983Y843708D01*
X823317Y843542D01*
X823692Y843500D01*
X824025Y843542D01*
X824358Y843750D01*
X824567Y844000D01*
X824608Y844250D01*
X824525Y844542D01*
X824233Y844750D01*
X823942Y844833D01*
X823567D01*
G01X823942D02*
X824192Y844958D01*
X824400Y845167D01*
X824483Y845417D01*
X824400Y845667D01*
X824192Y845875D01*
X823817Y846000D01*
X823442Y845958D01*
X823067Y845792D01*
G01X815317Y841792D02*
X815067Y841917D01*
X814775Y842000D01*
X814442D01*
X814067Y841875D01*
X813775Y841667D01*
X813567Y841417D01*
X813400Y841000D01*
X813358Y840625D01*
X813442Y840250D01*
X813567Y840000D01*
X813817Y839750D01*
X814108Y839583D01*
X814400Y839500D01*
X814692D01*
X814983Y839583D01*
X815233Y839708D01*
X815442Y839875D01*
G01X818000Y839500D02*
Y842000D01*
X816458Y840208D01*
X818542D01*
G01X819683Y840000D02*
X819933Y839708D01*
X820267Y839542D01*
X820642Y839500D01*
X820975Y839542D01*
X821308Y839750D01*
X821517Y840000D01*
X821558Y840250D01*
X821475Y840542D01*
X821183Y840750D01*
X820892Y840833D01*
X820517D01*
G01X820892D02*
X821142Y840958D01*
X821350Y841167D01*
X821433Y841417D01*
X821350Y841667D01*
X821142Y841875D01*
X820767Y842000D01*
X820392Y841958D01*
X820017Y841792D01*
G01X815800Y855500D02*
Y851500D01*
X823200D01*
G01X814517Y877500D02*
Y880000D01*
X815558D01*
X815892Y879875D01*
X816100Y879708D01*
X816183Y879375D01*
X816100Y879042D01*
X815850Y878833D01*
X815558Y878708D01*
X814517D01*
G01X815558D02*
X816183Y877500D01*
G01X817658Y878542D02*
X817950Y878833D01*
X818200Y879000D01*
X818533Y879083D01*
X818825Y879000D01*
X819033Y878833D01*
X819200Y878583D01*
X819242Y878292D01*
X819200Y878042D01*
X819033Y877792D01*
X818783Y877583D01*
X818492Y877500D01*
X818158Y877583D01*
X817867Y877833D01*
X817700Y878208D01*
X817658Y878625D01*
X817742Y879167D01*
X817867Y879458D01*
X818075Y879750D01*
X818367Y879958D01*
X818658Y880000D01*
X818950Y879917D01*
X819158Y879708D01*
G01X821550Y877500D02*
X821842Y877542D01*
X822175Y877667D01*
X822383Y877875D01*
X822467Y878167D01*
X822383Y878458D01*
X822133Y878708D01*
X821758Y878833D01*
X821342D01*
X821092Y878917D01*
X820883Y879125D01*
X820800Y879417D01*
X820925Y879708D01*
X821217Y879917D01*
X821550Y880000D01*
X821883Y879917D01*
X822175Y879708D01*
X822300Y879417D01*
X822217Y879125D01*
X822008Y878917D01*
X821758Y878833D01*
X821342D01*
X820967Y878708D01*
X820717Y878458D01*
X820633Y878167D01*
X820717Y877875D01*
X820925Y877667D01*
X821258Y877542D01*
X821550Y877500D01*
G01X823858Y878542D02*
X824150Y878833D01*
X824400Y879000D01*
X824733Y879083D01*
X825025Y879000D01*
X825233Y878833D01*
X825400Y878583D01*
X825442Y878292D01*
X825400Y878042D01*
X825233Y877792D01*
X824983Y877583D01*
X824692Y877500D01*
X824358Y877583D01*
X824067Y877833D01*
X823900Y878208D01*
X823858Y878625D01*
X823942Y879167D01*
X824067Y879458D01*
X824275Y879750D01*
X824567Y879958D01*
X824858Y880000D01*
X825150Y879917D01*
X825358Y879708D01*
G01X826700Y871000D02*
Y875000D01*
X819300D01*
G01X839555Y258067D02*
X837055D01*
Y259108D01*
X837180Y259442D01*
X837347Y259650D01*
X837680Y259733D01*
X838013Y259650D01*
X838222Y259400D01*
X838347Y259108D01*
Y258067D01*
G01Y259108D02*
X839555Y259733D01*
G01Y262000D02*
X837055D01*
X837555Y261500D01*
G01X839555D02*
Y262500D01*
G01Y265017D02*
X839013Y265100D01*
X838555Y265225D01*
X838138Y265392D01*
X837680Y265600D01*
X837055Y265933D01*
Y264267D01*
G01X840055Y275700D02*
X836055D01*
Y268300D01*
G01X830555Y258067D02*
X828055D01*
Y259108D01*
X828180Y259442D01*
X828347Y259650D01*
X828680Y259733D01*
X829013Y259650D01*
X829222Y259400D01*
X829347Y259108D01*
Y258067D01*
G01Y259108D02*
X830555Y259733D01*
G01Y262000D02*
X828055D01*
X828555Y261500D01*
G01X830555D02*
Y262500D01*
G01X830263Y264392D02*
X830472Y264683D01*
X830555Y265017D01*
X830472Y265350D01*
X830222Y265642D01*
X829847Y265850D01*
X829472Y265933D01*
X829013D01*
X828638Y265850D01*
X828305Y265642D01*
X828138Y265392D01*
X828055Y265100D01*
X828138Y264767D01*
X828305Y264517D01*
X828555Y264350D01*
X828888Y264267D01*
X829180Y264350D01*
X829472Y264558D01*
X829638Y264808D01*
X829680Y265100D01*
X829597Y265433D01*
X829388Y265683D01*
X829013Y265933D01*
G01X827055Y268300D02*
X831055D01*
Y275700D01*
G01X835055Y258067D02*
X832555D01*
Y259108D01*
X832680Y259442D01*
X832847Y259650D01*
X833180Y259733D01*
X833513Y259650D01*
X833722Y259400D01*
X833847Y259108D01*
Y258067D01*
G01Y259108D02*
X835055Y259733D01*
G01Y262000D02*
X832555D01*
X833055Y261500D01*
G01X835055D02*
Y262500D01*
G01X834555Y264183D02*
X834847Y264433D01*
X835013Y264767D01*
X835055Y265142D01*
X835013Y265475D01*
X834805Y265808D01*
X834555Y266017D01*
X834305Y266058D01*
X834013Y265975D01*
X833805Y265683D01*
X833722Y265392D01*
Y265017D01*
G01Y265392D02*
X833597Y265642D01*
X833388Y265850D01*
X833138Y265933D01*
X832888Y265850D01*
X832680Y265642D01*
X832555Y265267D01*
X832597Y264892D01*
X832763Y264517D01*
G01X835555Y275700D02*
X831555D01*
Y268300D01*
G01X832875Y345333D02*
X833208Y345125D01*
X833583Y345000D01*
X833917D01*
X834250Y345125D01*
X834500Y345333D01*
X834625Y345625D01*
X834542Y345917D01*
X834333Y346167D01*
X833958Y346333D01*
X833458Y346417D01*
X833167Y346583D01*
X833042Y346875D01*
X833125Y347167D01*
X833333Y347375D01*
X833625Y347500D01*
X833917D01*
X834208Y347417D01*
X834458Y347208D01*
G01X837767Y347292D02*
X837517Y347417D01*
X837225Y347500D01*
X836892D01*
X836517Y347375D01*
X836225Y347167D01*
X836017Y346917D01*
X835850Y346500D01*
X835808Y346125D01*
X835892Y345750D01*
X836017Y345500D01*
X836267Y345250D01*
X836558Y345083D01*
X836850Y345000D01*
X837142D01*
X837433Y345083D01*
X837683Y345208D01*
X837892Y345375D01*
G01X839950Y345000D02*
Y347500D01*
X839450Y347000D01*
G01Y345000D02*
X840450D01*
G01X843050Y347500D02*
X842717Y347417D01*
X842467Y347208D01*
X842300Y346958D01*
X842175Y346625D01*
X842133Y346250D01*
X842175Y345875D01*
X842300Y345542D01*
X842467Y345292D01*
X842717Y345083D01*
X843050Y345000D01*
X843383Y345083D01*
X843633Y345292D01*
X843800Y345542D01*
X843925Y345875D01*
X843967Y346250D01*
X843925Y346625D01*
X843800Y346958D01*
X843633Y347208D01*
X843383Y347417D01*
X843050Y347500D01*
G01X845442Y345292D02*
X845733Y345083D01*
X846067Y345000D01*
X846400Y345083D01*
X846692Y345333D01*
X846900Y345708D01*
X846983Y346083D01*
Y346542D01*
X846900Y346917D01*
X846692Y347250D01*
X846442Y347417D01*
X846150Y347500D01*
X845817Y347417D01*
X845567Y347250D01*
X845400Y347000D01*
X845317Y346667D01*
X845400Y346375D01*
X845608Y346083D01*
X845858Y345917D01*
X846150Y345875D01*
X846483Y345958D01*
X846733Y346167D01*
X846983Y346542D01*
G01X849250Y345000D02*
X849542Y345042D01*
X849875Y345167D01*
X850083Y345375D01*
X850167Y345667D01*
X850083Y345958D01*
X849833Y346208D01*
X849458Y346333D01*
X849042D01*
X848792Y346417D01*
X848583Y346625D01*
X848500Y346917D01*
X848625Y347208D01*
X848917Y347417D01*
X849250Y347500D01*
X849583Y347417D01*
X849875Y347208D01*
X850000Y346917D01*
X849917Y346625D01*
X849708Y346417D01*
X849458Y346333D01*
X849042D01*
X848667Y346208D01*
X848417Y345958D01*
X848333Y345667D01*
X848417Y345375D01*
X848625Y345167D01*
X848958Y345042D01*
X849250Y345000D01*
G01X829467Y367500D02*
Y370000D01*
X830467D01*
X830800Y369875D01*
X831050Y369583D01*
X831133Y369250D01*
X831050Y368917D01*
X830842Y368667D01*
X830467Y368542D01*
X829467D01*
G01X834317Y369792D02*
X834067Y369917D01*
X833775Y370000D01*
X833442D01*
X833067Y369875D01*
X832775Y369667D01*
X832567Y369417D01*
X832400Y369000D01*
X832358Y368625D01*
X832442Y368250D01*
X832567Y368000D01*
X832817Y367750D01*
X833108Y367583D01*
X833400Y367500D01*
X833692D01*
X833983Y367583D01*
X834233Y367708D01*
X834442Y367875D01*
G01X836500Y367500D02*
Y370000D01*
X836000Y369500D01*
G01Y367500D02*
X837000D01*
G01X840100D02*
Y370000D01*
X838558Y368208D01*
X840642D01*
G01X842700Y370000D02*
X842367Y369917D01*
X842117Y369708D01*
X841950Y369458D01*
X841825Y369125D01*
X841783Y368750D01*
X841825Y368375D01*
X841950Y368042D01*
X842117Y367792D01*
X842367Y367583D01*
X842700Y367500D01*
X843033Y367583D01*
X843283Y367792D01*
X843450Y368042D01*
X843575Y368375D01*
X843617Y368750D01*
X843575Y369125D01*
X843450Y369458D01*
X843283Y369708D01*
X843033Y369917D01*
X842700Y370000D01*
G01X829467Y376000D02*
Y378500D01*
X830467D01*
X830800Y378375D01*
X831050Y378083D01*
X831133Y377750D01*
X831050Y377417D01*
X830842Y377167D01*
X830467Y377042D01*
X829467D01*
G01X834317Y378292D02*
X834067Y378417D01*
X833775Y378500D01*
X833442D01*
X833067Y378375D01*
X832775Y378167D01*
X832567Y377917D01*
X832400Y377500D01*
X832358Y377125D01*
X832442Y376750D01*
X832567Y376500D01*
X832817Y376250D01*
X833108Y376083D01*
X833400Y376000D01*
X833692D01*
X833983Y376083D01*
X834233Y376208D01*
X834442Y376375D01*
G01X836500Y376000D02*
Y378500D01*
X836000Y378000D01*
G01Y376000D02*
X837000D01*
G01X838683Y376500D02*
X838933Y376208D01*
X839267Y376042D01*
X839642Y376000D01*
X839975Y376042D01*
X840308Y376250D01*
X840517Y376500D01*
X840558Y376750D01*
X840475Y377042D01*
X840183Y377250D01*
X839892Y377333D01*
X839517D01*
G01X839892D02*
X840142Y377458D01*
X840350Y377667D01*
X840433Y377917D01*
X840350Y378167D01*
X840142Y378375D01*
X839767Y378500D01*
X839392Y378458D01*
X839017Y378292D01*
G01X841992Y376292D02*
X842283Y376083D01*
X842617Y376000D01*
X842950Y376083D01*
X843242Y376333D01*
X843450Y376708D01*
X843533Y377083D01*
Y377542D01*
X843450Y377917D01*
X843242Y378250D01*
X842992Y378417D01*
X842700Y378500D01*
X842367Y378417D01*
X842117Y378250D01*
X841950Y378000D01*
X841867Y377667D01*
X841950Y377375D01*
X842158Y377083D01*
X842408Y376917D01*
X842700Y376875D01*
X843033Y376958D01*
X843283Y377167D01*
X843533Y377542D01*
G01X828967Y382500D02*
Y385000D01*
X829967D01*
X830300Y384875D01*
X830550Y384583D01*
X830633Y384250D01*
X830550Y383917D01*
X830342Y383667D01*
X829967Y383542D01*
X828967D01*
G01X833817Y384792D02*
X833567Y384917D01*
X833275Y385000D01*
X832942D01*
X832567Y384875D01*
X832275Y384667D01*
X832067Y384417D01*
X831900Y384000D01*
X831858Y383625D01*
X831942Y383250D01*
X832067Y383000D01*
X832317Y382750D01*
X832608Y382583D01*
X832900Y382500D01*
X833192D01*
X833483Y382583D01*
X833733Y382708D01*
X833942Y382875D01*
G01X836000Y382500D02*
Y385000D01*
X835500Y384500D01*
G01Y382500D02*
X836500D01*
G01X838183Y383000D02*
X838433Y382708D01*
X838767Y382542D01*
X839142Y382500D01*
X839475Y382542D01*
X839808Y382750D01*
X840017Y383000D01*
X840058Y383250D01*
X839975Y383542D01*
X839683Y383750D01*
X839392Y383833D01*
X839017D01*
G01X839392D02*
X839642Y383958D01*
X839850Y384167D01*
X839933Y384417D01*
X839850Y384667D01*
X839642Y384875D01*
X839267Y385000D01*
X838892Y384958D01*
X838517Y384792D01*
G01X842200Y382500D02*
X842492Y382542D01*
X842825Y382667D01*
X843033Y382875D01*
X843117Y383167D01*
X843033Y383458D01*
X842783Y383708D01*
X842408Y383833D01*
X841992D01*
X841742Y383917D01*
X841533Y384125D01*
X841450Y384417D01*
X841575Y384708D01*
X841867Y384917D01*
X842200Y385000D01*
X842533Y384917D01*
X842825Y384708D01*
X842950Y384417D01*
X842867Y384125D01*
X842658Y383917D01*
X842408Y383833D01*
X841992D01*
X841617Y383708D01*
X841367Y383458D01*
X841283Y383167D01*
X841367Y382875D01*
X841575Y382667D01*
X841908Y382542D01*
X842200Y382500D01*
G01X834331Y396460D02*
X831331D01*
G01X837924Y415428D02*
X832924D01*
Y410428D01*
G01X831500Y415467D02*
X829000D01*
Y416467D01*
X829125Y416800D01*
X829417Y417050D01*
X829750Y417133D01*
X830083Y417050D01*
X830333Y416842D01*
X830458Y416467D01*
Y415467D01*
G01X831500Y418567D02*
X829000D01*
Y419608D01*
X829125Y419942D01*
X829292Y420150D01*
X829625Y420233D01*
X829958Y420150D01*
X830167Y419900D01*
X830292Y419608D01*
Y418567D01*
G01Y419608D02*
X831500Y420233D01*
G01Y422500D02*
X829000D01*
X829500Y422000D01*
G01X831500D02*
Y423000D01*
G01X829417Y424808D02*
X829167Y425058D01*
X829042Y425350D01*
X829000Y425683D01*
X829083Y426100D01*
X829292Y426392D01*
X829542Y426475D01*
X829792Y426433D01*
X830000Y426267D01*
X830417Y425433D01*
X830708Y425058D01*
X831125Y424808D01*
X831500Y424725D01*
Y426475D01*
G01X831000Y427783D02*
X831292Y428033D01*
X831458Y428367D01*
X831500Y428742D01*
X831458Y429075D01*
X831250Y429408D01*
X831000Y429617D01*
X830750Y429658D01*
X830458Y429575D01*
X830250Y429283D01*
X830167Y428992D01*
Y428617D01*
G01Y428992D02*
X830042Y429242D01*
X829833Y429450D01*
X829583Y429533D01*
X829333Y429450D01*
X829125Y429242D01*
X829000Y428867D01*
X829042Y428492D01*
X829208Y428117D01*
G01X828500Y405300D02*
X832500D01*
Y412700D01*
G01X827500Y412467D02*
X825000D01*
Y413467D01*
X825125Y413800D01*
X825417Y414050D01*
X825750Y414133D01*
X826083Y414050D01*
X826333Y413842D01*
X826458Y413467D01*
Y412467D01*
G01X825208Y417317D02*
X825083Y417067D01*
X825000Y416775D01*
Y416442D01*
X825125Y416067D01*
X825333Y415775D01*
X825583Y415567D01*
X826000Y415400D01*
X826375Y415358D01*
X826750Y415442D01*
X827000Y415567D01*
X827250Y415817D01*
X827417Y416108D01*
X827500Y416400D01*
Y416692D01*
X827417Y416983D01*
X827292Y417233D01*
X827125Y417442D01*
G01X827500Y419500D02*
X825000D01*
X825500Y419000D01*
G01X827500D02*
Y420000D01*
G01Y423100D02*
X825000D01*
X826792Y421558D01*
Y423642D01*
G01X827500Y425700D02*
X825000D01*
X825500Y425200D01*
G01X827500D02*
Y426200D01*
G01X826200Y448500D02*
Y456500D01*
X843800D01*
Y448500D01*
X826200D01*
G01X826417Y459000D02*
Y461500D01*
X827417D01*
X827750Y461375D01*
X828000Y461083D01*
X828083Y460750D01*
X828000Y460417D01*
X827792Y460167D01*
X827417Y460042D01*
X826417D01*
G01X829517Y459000D02*
Y461500D01*
X830558D01*
X830892Y461375D01*
X831100Y461208D01*
X831183Y460875D01*
X831100Y460542D01*
X830850Y460333D01*
X830558Y460208D01*
X829517D01*
G01X830558D02*
X831183Y459000D01*
G01X832742Y459292D02*
X833033Y459083D01*
X833367Y459000D01*
X833700Y459083D01*
X833992Y459333D01*
X834200Y459708D01*
X834283Y460083D01*
Y460542D01*
X834200Y460917D01*
X833992Y461250D01*
X833742Y461417D01*
X833450Y461500D01*
X833117Y461417D01*
X832867Y461250D01*
X832700Y461000D01*
X832617Y460667D01*
X832700Y460375D01*
X832908Y460083D01*
X833158Y459917D01*
X833450Y459875D01*
X833783Y459958D01*
X834033Y460167D01*
X834283Y460542D01*
G01X836550Y461500D02*
X836217Y461417D01*
X835967Y461208D01*
X835800Y460958D01*
X835675Y460625D01*
X835633Y460250D01*
X835675Y459875D01*
X835800Y459542D01*
X835967Y459292D01*
X836217Y459083D01*
X836550Y459000D01*
X836883Y459083D01*
X837133Y459292D01*
X837300Y459542D01*
X837425Y459875D01*
X837467Y460250D01*
X837425Y460625D01*
X837300Y460958D01*
X837133Y461208D01*
X836883Y461417D01*
X836550Y461500D01*
G01X839650D02*
X839317Y461417D01*
X839067Y461208D01*
X838900Y460958D01*
X838775Y460625D01*
X838733Y460250D01*
X838775Y459875D01*
X838900Y459542D01*
X839067Y459292D01*
X839317Y459083D01*
X839650Y459000D01*
X839983Y459083D01*
X840233Y459292D01*
X840400Y459542D01*
X840525Y459875D01*
X840567Y460250D01*
X840525Y460625D01*
X840400Y460958D01*
X840233Y461208D01*
X839983Y461417D01*
X839650Y461500D01*
G01X842042Y459292D02*
X842333Y459083D01*
X842667Y459000D01*
X843000Y459083D01*
X843292Y459333D01*
X843500Y459708D01*
X843583Y460083D01*
Y460542D01*
X843500Y460917D01*
X843292Y461250D01*
X843042Y461417D01*
X842750Y461500D01*
X842417Y461417D01*
X842167Y461250D01*
X842000Y461000D01*
X841917Y460667D01*
X842000Y460375D01*
X842208Y460083D01*
X842458Y459917D01*
X842750Y459875D01*
X843083Y459958D01*
X843333Y460167D01*
X843583Y460542D01*
G01X835317Y639292D02*
X835067Y639417D01*
X834775Y639500D01*
X834442D01*
X834067Y639375D01*
X833775Y639167D01*
X833567Y638917D01*
X833400Y638500D01*
X833358Y638125D01*
X833442Y637750D01*
X833567Y637500D01*
X833817Y637250D01*
X834108Y637083D01*
X834400Y637000D01*
X834692D01*
X834983Y637083D01*
X835233Y637208D01*
X835442Y637375D01*
G01X837500Y637000D02*
X837792Y637042D01*
X838125Y637167D01*
X838333Y637375D01*
X838417Y637667D01*
X838333Y637958D01*
X838083Y638208D01*
X837708Y638333D01*
X837292D01*
X837042Y638417D01*
X836833Y638625D01*
X836750Y638917D01*
X836875Y639208D01*
X837167Y639417D01*
X837500Y639500D01*
X837833Y639417D01*
X838125Y639208D01*
X838250Y638917D01*
X838167Y638625D01*
X837958Y638417D01*
X837708Y638333D01*
X837292D01*
X836917Y638208D01*
X836667Y637958D01*
X836583Y637667D01*
X836667Y637375D01*
X836875Y637167D01*
X837208Y637042D01*
X837500Y637000D01*
G01X840517D02*
X840600Y637542D01*
X840725Y638000D01*
X840892Y638417D01*
X841100Y638875D01*
X841433Y639500D01*
X839767D01*
G01X836500Y686517D02*
X834000D01*
Y687558D01*
X834125Y687892D01*
X834292Y688100D01*
X834625Y688183D01*
X834958Y688100D01*
X835167Y687850D01*
X835292Y687558D01*
Y686517D01*
G01Y687558D02*
X836500Y688183D01*
G01Y690950D02*
X834000D01*
X835792Y689408D01*
Y691492D01*
G01X836208Y692842D02*
X836417Y693133D01*
X836500Y693467D01*
X836417Y693800D01*
X836167Y694092D01*
X835792Y694300D01*
X835417Y694383D01*
X834958D01*
X834583Y694300D01*
X834250Y694092D01*
X834083Y693842D01*
X834000Y693550D01*
X834083Y693217D01*
X834250Y692967D01*
X834500Y692800D01*
X834833Y692717D01*
X835125Y692800D01*
X835417Y693008D01*
X835583Y693258D01*
X835625Y693550D01*
X835542Y693883D01*
X835333Y694133D01*
X834958Y694383D01*
G01X836125Y695733D02*
X836333Y695983D01*
X836458Y696275D01*
X836500Y696650D01*
X836417Y697025D01*
X836250Y697317D01*
X835958Y697525D01*
X835625Y697567D01*
X835292Y697483D01*
X835083Y697275D01*
X834917Y696983D01*
X834875Y696692D01*
X834917Y696400D01*
X835083Y696025D01*
X834000Y696150D01*
Y697275D01*
G01X838468Y684784D02*
X864468D01*
G01X838468Y697784D02*
Y684784D01*
G01X864468Y697784D02*
X838468D01*
G01X825017Y713000D02*
Y715500D01*
X826058D01*
X826392Y715375D01*
X826600Y715208D01*
X826683Y714875D01*
X826600Y714542D01*
X826350Y714333D01*
X826058Y714208D01*
X825017D01*
G01X826058D02*
X826683Y713000D01*
G01X829450D02*
Y715500D01*
X827908Y713708D01*
X829992D01*
G01X831342Y713292D02*
X831633Y713083D01*
X831967Y713000D01*
X832300Y713083D01*
X832592Y713333D01*
X832800Y713708D01*
X832883Y714083D01*
Y714542D01*
X832800Y714917D01*
X832592Y715250D01*
X832342Y715417D01*
X832050Y715500D01*
X831717Y715417D01*
X831467Y715250D01*
X831300Y715000D01*
X831217Y714667D01*
X831300Y714375D01*
X831508Y714083D01*
X831758Y713917D01*
X832050Y713875D01*
X832383Y713958D01*
X832633Y714167D01*
X832883Y714542D01*
G01X835650Y713000D02*
Y715500D01*
X834108Y713708D01*
X836192D01*
G01X831267Y721292D02*
X831017Y721417D01*
X830725Y721500D01*
X830392D01*
X830017Y721375D01*
X829725Y721167D01*
X829517Y720917D01*
X829350Y720500D01*
X829308Y720125D01*
X829392Y719750D01*
X829517Y719500D01*
X829767Y719250D01*
X830058Y719083D01*
X830350Y719000D01*
X830642D01*
X830933Y719083D01*
X831183Y719208D01*
X831392Y719375D01*
G01X832533Y719500D02*
X832783Y719208D01*
X833117Y719042D01*
X833492Y719000D01*
X833825Y719042D01*
X834158Y719250D01*
X834367Y719500D01*
X834408Y719750D01*
X834325Y720042D01*
X834033Y720250D01*
X833742Y720333D01*
X833367D01*
G01X833742D02*
X833992Y720458D01*
X834200Y720667D01*
X834283Y720917D01*
X834200Y721167D01*
X833992Y721375D01*
X833617Y721500D01*
X833242Y721458D01*
X832867Y721292D01*
G01X836550Y721500D02*
X836217Y721417D01*
X835967Y721208D01*
X835800Y720958D01*
X835675Y720625D01*
X835633Y720250D01*
X835675Y719875D01*
X835800Y719542D01*
X835967Y719292D01*
X836217Y719083D01*
X836550Y719000D01*
X836883Y719083D01*
X837133Y719292D01*
X837300Y719542D01*
X837425Y719875D01*
X837467Y720250D01*
X837425Y720625D01*
X837300Y720958D01*
X837133Y721208D01*
X836883Y721417D01*
X836550Y721500D01*
G01X838733Y719375D02*
X838983Y719167D01*
X839275Y719042D01*
X839650Y719000D01*
X840025Y719083D01*
X840317Y719250D01*
X840525Y719542D01*
X840567Y719875D01*
X840483Y720208D01*
X840275Y720417D01*
X839983Y720583D01*
X839692Y720625D01*
X839400Y720583D01*
X839025Y720417D01*
X839150Y721500D01*
X840275D01*
G01X836875Y733833D02*
X837208Y733625D01*
X837583Y733500D01*
X837917D01*
X838250Y733625D01*
X838500Y733833D01*
X838625Y734125D01*
X838542Y734417D01*
X838333Y734667D01*
X837958Y734833D01*
X837458Y734917D01*
X837167Y735083D01*
X837042Y735375D01*
X837125Y735667D01*
X837333Y735875D01*
X837625Y736000D01*
X837917D01*
X838208Y735917D01*
X838458Y735708D01*
G01X841767Y735792D02*
X841517Y735917D01*
X841225Y736000D01*
X840892D01*
X840517Y735875D01*
X840225Y735667D01*
X840017Y735417D01*
X839850Y735000D01*
X839808Y734625D01*
X839892Y734250D01*
X840017Y734000D01*
X840267Y733750D01*
X840558Y733583D01*
X840850Y733500D01*
X841142D01*
X841433Y733583D01*
X841683Y733708D01*
X841892Y733875D01*
G01X843950Y733500D02*
Y736000D01*
X843450Y735500D01*
G01Y733500D02*
X844450D01*
G01X846133Y734000D02*
X846383Y733708D01*
X846717Y733542D01*
X847092Y733500D01*
X847425Y733542D01*
X847758Y733750D01*
X847967Y734000D01*
X848008Y734250D01*
X847925Y734542D01*
X847633Y734750D01*
X847342Y734833D01*
X846967D01*
G01X847342D02*
X847592Y734958D01*
X847800Y735167D01*
X847883Y735417D01*
X847800Y735667D01*
X847592Y735875D01*
X847217Y736000D01*
X846842Y735958D01*
X846467Y735792D01*
G01X850150Y736000D02*
X849817Y735917D01*
X849567Y735708D01*
X849400Y735458D01*
X849275Y735125D01*
X849233Y734750D01*
X849275Y734375D01*
X849400Y734042D01*
X849567Y733792D01*
X849817Y733583D01*
X850150Y733500D01*
X850483Y733583D01*
X850733Y733792D01*
X850900Y734042D01*
X851025Y734375D01*
X851067Y734750D01*
X851025Y735125D01*
X850900Y735458D01*
X850733Y735708D01*
X850483Y735917D01*
X850150Y736000D01*
G01X852542Y733792D02*
X852833Y733583D01*
X853167Y733500D01*
X853500Y733583D01*
X853792Y733833D01*
X854000Y734208D01*
X854083Y734583D01*
Y735042D01*
X854000Y735417D01*
X853792Y735750D01*
X853542Y735917D01*
X853250Y736000D01*
X852917Y735917D01*
X852667Y735750D01*
X852500Y735500D01*
X852417Y735167D01*
X852500Y734875D01*
X852708Y734583D01*
X852958Y734417D01*
X853250Y734375D01*
X853583Y734458D01*
X853833Y734667D01*
X854083Y735042D01*
G01X831933Y841000D02*
Y839208D01*
X832100Y838833D01*
X832433Y838583D01*
X832850Y838500D01*
X833267Y838583D01*
X833600Y838833D01*
X833767Y839208D01*
Y841000D01*
G01X835950Y838500D02*
Y841000D01*
X835450Y840500D01*
G01Y838500D02*
X836450D01*
G01X838967D02*
X839050Y839042D01*
X839175Y839500D01*
X839342Y839917D01*
X839550Y840375D01*
X839883Y841000D01*
X838217D01*
G01X842067Y838500D02*
X842150Y839042D01*
X842275Y839500D01*
X842442Y839917D01*
X842650Y840375D01*
X842983Y841000D01*
X841317D01*
G01X829300Y844000D02*
Y854000D01*
G01X842700Y844000D02*
X829300D01*
G01X842200Y861000D02*
X828800D01*
G01D02*
Y871000D01*
G01X829300Y854000D02*
X842700D01*
G01X840700Y856000D02*
Y860000D01*
X833300D01*
G01X831433Y880500D02*
Y878708D01*
X831600Y878333D01*
X831933Y878083D01*
X832350Y878000D01*
X832767Y878083D01*
X833100Y878333D01*
X833267Y878708D01*
Y880500D01*
G01X835450Y878000D02*
Y880500D01*
X834950Y880000D01*
G01Y878000D02*
X835950D01*
G01X838467D02*
X838550Y878542D01*
X838675Y879000D01*
X838842Y879417D01*
X839050Y879875D01*
X839383Y880500D01*
X837717D01*
G01X840858Y879042D02*
X841150Y879333D01*
X841400Y879500D01*
X841733Y879583D01*
X842025Y879500D01*
X842233Y879333D01*
X842400Y879083D01*
X842442Y878792D01*
X842400Y878542D01*
X842233Y878292D01*
X841983Y878083D01*
X841692Y878000D01*
X841358Y878083D01*
X841067Y878333D01*
X840900Y878708D01*
X840858Y879125D01*
X840942Y879667D01*
X841067Y879958D01*
X841275Y880250D01*
X841567Y880458D01*
X841858Y880500D01*
X842150Y880417D01*
X842358Y880208D01*
G01X828800Y871000D02*
X842200D01*
G01X848555Y258067D02*
X846055D01*
Y259108D01*
X846180Y259442D01*
X846347Y259650D01*
X846680Y259733D01*
X847013Y259650D01*
X847222Y259400D01*
X847347Y259108D01*
Y258067D01*
G01Y259108D02*
X848555Y259733D01*
G01Y262000D02*
X846055D01*
X846555Y261500D01*
G01X848555D02*
Y262500D01*
G01Y265100D02*
X848513Y265392D01*
X848388Y265725D01*
X848180Y265933D01*
X847888Y266017D01*
X847597Y265933D01*
X847347Y265683D01*
X847222Y265308D01*
Y264892D01*
X847138Y264642D01*
X846930Y264433D01*
X846638Y264350D01*
X846347Y264475D01*
X846138Y264767D01*
X846055Y265100D01*
X846138Y265433D01*
X846347Y265725D01*
X846638Y265850D01*
X846930Y265767D01*
X847138Y265558D01*
X847222Y265308D01*
Y264892D01*
X847347Y264517D01*
X847597Y264267D01*
X847888Y264183D01*
X848180Y264267D01*
X848388Y264475D01*
X848513Y264808D01*
X848555Y265100D01*
G01X849055Y275700D02*
X845055D01*
Y268300D01*
G01X853055Y258067D02*
X850555D01*
Y259108D01*
X850680Y259442D01*
X850847Y259650D01*
X851180Y259733D01*
X851513Y259650D01*
X851722Y259400D01*
X851847Y259108D01*
Y258067D01*
G01Y259108D02*
X853055Y259733D01*
G01Y262000D02*
X850555D01*
X851055Y261500D01*
G01X853055D02*
Y262500D01*
G01X852013Y264308D02*
X851722Y264600D01*
X851555Y264850D01*
X851472Y265183D01*
X851555Y265475D01*
X851722Y265683D01*
X851972Y265850D01*
X852263Y265892D01*
X852513Y265850D01*
X852763Y265683D01*
X852972Y265433D01*
X853055Y265142D01*
X852972Y264808D01*
X852722Y264517D01*
X852347Y264350D01*
X851930Y264308D01*
X851388Y264392D01*
X851097Y264517D01*
X850805Y264725D01*
X850597Y265017D01*
X850555Y265308D01*
X850638Y265600D01*
X850847Y265808D01*
G01X853555Y275700D02*
X849555D01*
Y268300D01*
G01X857555Y258067D02*
X855055D01*
Y259108D01*
X855180Y259442D01*
X855347Y259650D01*
X855680Y259733D01*
X856013Y259650D01*
X856222Y259400D01*
X856347Y259108D01*
Y258067D01*
G01Y259108D02*
X857555Y259733D01*
G01Y262000D02*
X855055D01*
X855555Y261500D01*
G01X857555D02*
Y262500D01*
G01X855472Y264308D02*
X855222Y264558D01*
X855097Y264850D01*
X855055Y265183D01*
X855138Y265600D01*
X855347Y265892D01*
X855597Y265975D01*
X855847Y265933D01*
X856055Y265767D01*
X856472Y264933D01*
X856763Y264558D01*
X857180Y264308D01*
X857555Y264225D01*
Y265975D01*
G01X858055Y275700D02*
X854055D01*
Y268300D01*
G01X844055Y258067D02*
X841555D01*
Y259108D01*
X841680Y259442D01*
X841847Y259650D01*
X842180Y259733D01*
X842513Y259650D01*
X842722Y259400D01*
X842847Y259108D01*
Y258067D01*
G01Y259108D02*
X844055Y259733D01*
G01Y262000D02*
X841555D01*
X842055Y261500D01*
G01X844055D02*
Y262500D01*
G01Y265600D02*
X841555D01*
X843347Y264058D01*
Y266142D01*
G01X844555Y275700D02*
X840555D01*
Y268300D01*
G01X854987Y350805D02*
X855195Y351138D01*
X855320Y351513D01*
Y351847D01*
X855195Y352180D01*
X854987Y352430D01*
X854695Y352555D01*
X854403Y352472D01*
X854153Y352263D01*
X853987Y351888D01*
X853903Y351388D01*
X853737Y351097D01*
X853445Y350972D01*
X853153Y351055D01*
X852945Y351263D01*
X852820Y351555D01*
Y351847D01*
X852903Y352138D01*
X853112Y352388D01*
G01X855320Y353947D02*
X852820D01*
Y354988D01*
X852945Y355322D01*
X853112Y355530D01*
X853445Y355613D01*
X853778Y355530D01*
X853987Y355280D01*
X854112Y354988D01*
Y353947D01*
G01Y354988D02*
X855320Y355613D01*
G01X855028Y357172D02*
X855237Y357463D01*
X855320Y357797D01*
X855237Y358130D01*
X854987Y358422D01*
X854612Y358630D01*
X854237Y358713D01*
X853778D01*
X853403Y358630D01*
X853070Y358422D01*
X852903Y358172D01*
X852820Y357880D01*
X852903Y357547D01*
X853070Y357297D01*
X853320Y357130D01*
X853653Y357047D01*
X853945Y357130D01*
X854237Y357338D01*
X854403Y357588D01*
X854445Y357880D01*
X854362Y358213D01*
X854153Y358463D01*
X853778Y358713D01*
G01X853237Y360188D02*
X852987Y360438D01*
X852862Y360730D01*
X852820Y361063D01*
X852903Y361480D01*
X853112Y361772D01*
X853362Y361855D01*
X853612Y361813D01*
X853820Y361647D01*
X854237Y360813D01*
X854528Y360438D01*
X854945Y360188D01*
X855320Y360105D01*
Y361855D01*
G01Y363997D02*
X854778Y364080D01*
X854320Y364205D01*
X853903Y364372D01*
X853445Y364580D01*
X852820Y364913D01*
Y363247D01*
G01X849987Y350805D02*
X850195Y351138D01*
X850320Y351513D01*
Y351847D01*
X850195Y352180D01*
X849987Y352430D01*
X849695Y352555D01*
X849403Y352472D01*
X849153Y352263D01*
X848987Y351888D01*
X848903Y351388D01*
X848737Y351097D01*
X848445Y350972D01*
X848153Y351055D01*
X847945Y351263D01*
X847820Y351555D01*
Y351847D01*
X847903Y352138D01*
X848112Y352388D01*
G01X850320Y353947D02*
X847820D01*
Y354988D01*
X847945Y355322D01*
X848112Y355530D01*
X848445Y355613D01*
X848778Y355530D01*
X848987Y355280D01*
X849112Y354988D01*
Y353947D01*
G01Y354988D02*
X850320Y355613D01*
G01X850028Y357172D02*
X850237Y357463D01*
X850320Y357797D01*
X850237Y358130D01*
X849987Y358422D01*
X849612Y358630D01*
X849237Y358713D01*
X848778D01*
X848403Y358630D01*
X848070Y358422D01*
X847903Y358172D01*
X847820Y357880D01*
X847903Y357547D01*
X848070Y357297D01*
X848320Y357130D01*
X848653Y357047D01*
X848945Y357130D01*
X849237Y357338D01*
X849403Y357588D01*
X849445Y357880D01*
X849362Y358213D01*
X849153Y358463D01*
X848778Y358713D01*
G01X848237Y360188D02*
X847987Y360438D01*
X847862Y360730D01*
X847820Y361063D01*
X847903Y361480D01*
X848112Y361772D01*
X848362Y361855D01*
X848612Y361813D01*
X848820Y361647D01*
X849237Y360813D01*
X849528Y360438D01*
X849945Y360188D01*
X850320Y360105D01*
Y361855D01*
G01Y364080D02*
X850278Y364372D01*
X850153Y364705D01*
X849945Y364913D01*
X849653Y364997D01*
X849362Y364913D01*
X849112Y364663D01*
X848987Y364288D01*
Y363872D01*
X848903Y363622D01*
X848695Y363413D01*
X848403Y363330D01*
X848112Y363455D01*
X847903Y363747D01*
X847820Y364080D01*
X847903Y364413D01*
X848112Y364705D01*
X848403Y364830D01*
X848695Y364747D01*
X848903Y364538D01*
X848987Y364288D01*
Y363872D01*
X849112Y363497D01*
X849362Y363247D01*
X849653Y363163D01*
X849945Y363247D01*
X850153Y363455D01*
X850278Y363788D01*
X850320Y364080D01*
G01X851892Y389135D02*
Y387135D01*
G01X841656Y414021D02*
Y416021D01*
G01X845500Y430467D02*
X843000D01*
Y431467D01*
X843125Y431800D01*
X843417Y432050D01*
X843750Y432133D01*
X844083Y432050D01*
X844333Y431842D01*
X844458Y431467D01*
Y430467D01*
G01X843208Y435317D02*
X843083Y435067D01*
X843000Y434775D01*
Y434442D01*
X843125Y434067D01*
X843333Y433775D01*
X843583Y433567D01*
X844000Y433400D01*
X844375Y433358D01*
X844750Y433442D01*
X845000Y433567D01*
X845250Y433817D01*
X845417Y434108D01*
X845500Y434400D01*
Y434692D01*
X845417Y434983D01*
X845292Y435233D01*
X845125Y435442D01*
G01X845500Y437500D02*
X843000D01*
X843500Y437000D01*
G01X845500D02*
Y438000D01*
G01Y441100D02*
X843000D01*
X844792Y439558D01*
Y441642D01*
G01X845500Y443617D02*
X844958Y443700D01*
X844500Y443825D01*
X844083Y443992D01*
X843625Y444200D01*
X843000Y444533D01*
Y442867D01*
G01X853500Y441517D02*
X851000D01*
Y442558D01*
X851125Y442892D01*
X851292Y443100D01*
X851625Y443183D01*
X851958Y443100D01*
X852167Y442850D01*
X852292Y442558D01*
Y441517D01*
G01Y442558D02*
X853500Y443183D01*
G01X853125Y444533D02*
X853333Y444783D01*
X853458Y445075D01*
X853500Y445450D01*
X853417Y445825D01*
X853250Y446117D01*
X852958Y446325D01*
X852625Y446367D01*
X852292Y446283D01*
X852083Y446075D01*
X851917Y445783D01*
X851875Y445492D01*
X851917Y445200D01*
X852083Y444825D01*
X851000Y444950D01*
Y446075D01*
G01X853208Y447842D02*
X853417Y448133D01*
X853500Y448467D01*
X853417Y448800D01*
X853167Y449092D01*
X852792Y449300D01*
X852417Y449383D01*
X851958D01*
X851583Y449300D01*
X851250Y449092D01*
X851083Y448842D01*
X851000Y448550D01*
X851083Y448217D01*
X851250Y447967D01*
X851500Y447800D01*
X851833Y447717D01*
X852125Y447800D01*
X852417Y448008D01*
X852583Y448258D01*
X852625Y448550D01*
X852542Y448883D01*
X852333Y449133D01*
X851958Y449383D01*
G01X853500Y451650D02*
X853458Y451942D01*
X853333Y452275D01*
X853125Y452483D01*
X852833Y452567D01*
X852542Y452483D01*
X852292Y452233D01*
X852167Y451858D01*
Y451442D01*
X852083Y451192D01*
X851875Y450983D01*
X851583Y450900D01*
X851292Y451025D01*
X851083Y451317D01*
X851000Y451650D01*
X851083Y451983D01*
X851292Y452275D01*
X851583Y452400D01*
X851875Y452317D01*
X852083Y452108D01*
X852167Y451858D01*
Y451442D01*
X852292Y451067D01*
X852542Y450817D01*
X852833Y450733D01*
X853125Y450817D01*
X853333Y451025D01*
X853458Y451358D01*
X853500Y451650D01*
G01X849500Y439967D02*
X847000D01*
Y440967D01*
X847125Y441300D01*
X847417Y441550D01*
X847750Y441633D01*
X848083Y441550D01*
X848333Y441342D01*
X848458Y440967D01*
Y439967D01*
G01X847208Y444817D02*
X847083Y444567D01*
X847000Y444275D01*
Y443942D01*
X847125Y443567D01*
X847333Y443275D01*
X847583Y443067D01*
X848000Y442900D01*
X848375Y442858D01*
X848750Y442942D01*
X849000Y443067D01*
X849250Y443317D01*
X849417Y443608D01*
X849500Y443900D01*
Y444192D01*
X849417Y444483D01*
X849292Y444733D01*
X849125Y444942D01*
G01X849500Y447000D02*
X847000D01*
X847500Y446500D01*
G01X849500D02*
Y447500D01*
G01Y450600D02*
X847000D01*
X848792Y449058D01*
Y451142D01*
G01X849208Y452492D02*
X849417Y452783D01*
X849500Y453117D01*
X849417Y453450D01*
X849167Y453742D01*
X848792Y453950D01*
X848417Y454033D01*
X847958D01*
X847583Y453950D01*
X847250Y453742D01*
X847083Y453492D01*
X847000Y453200D01*
X847083Y452867D01*
X847250Y452617D01*
X847500Y452450D01*
X847833Y452367D01*
X848125Y452450D01*
X848417Y452658D01*
X848583Y452908D01*
X848625Y453200D01*
X848542Y453533D01*
X848333Y453783D01*
X847958Y454033D01*
G01X853433Y631000D02*
Y629208D01*
X853600Y628833D01*
X853933Y628583D01*
X854350Y628500D01*
X854767Y628583D01*
X855100Y628833D01*
X855267Y629208D01*
Y631000D01*
G01X857450Y628500D02*
Y631000D01*
X856950Y630500D01*
G01Y628500D02*
X857950D01*
G01X860550D02*
X860842Y628542D01*
X861175Y628667D01*
X861383Y628875D01*
X861467Y629167D01*
X861383Y629458D01*
X861133Y629708D01*
X860758Y629833D01*
X860342D01*
X860092Y629917D01*
X859883Y630125D01*
X859800Y630417D01*
X859925Y630708D01*
X860217Y630917D01*
X860550Y631000D01*
X860883Y630917D01*
X861175Y630708D01*
X861300Y630417D01*
X861217Y630125D01*
X861008Y629917D01*
X860758Y629833D01*
X860342D01*
X859967Y629708D01*
X859717Y629458D01*
X859633Y629167D01*
X859717Y628875D01*
X859925Y628667D01*
X860258Y628542D01*
X860550Y628500D01*
G01X862858Y630583D02*
X863108Y630833D01*
X863400Y630958D01*
X863733Y631000D01*
X864150Y630917D01*
X864442Y630708D01*
X864525Y630458D01*
X864483Y630208D01*
X864317Y630000D01*
X863483Y629583D01*
X863108Y629292D01*
X862858Y628875D01*
X862775Y628500D01*
X864525D01*
G01X852517Y621000D02*
Y623500D01*
X853558D01*
X853892Y623375D01*
X854100Y623208D01*
X854183Y622875D01*
X854100Y622542D01*
X853850Y622333D01*
X853558Y622208D01*
X852517D01*
G01X853558D02*
X854183Y621000D01*
G01X855533Y621375D02*
X855783Y621167D01*
X856075Y621042D01*
X856450Y621000D01*
X856825Y621083D01*
X857117Y621250D01*
X857325Y621542D01*
X857367Y621875D01*
X857283Y622208D01*
X857075Y622417D01*
X856783Y622583D01*
X856492Y622625D01*
X856200Y622583D01*
X855825Y622417D01*
X855950Y623500D01*
X857075D01*
G01X859467Y621000D02*
X859550Y621542D01*
X859675Y622000D01*
X859842Y622417D01*
X860050Y622875D01*
X860383Y623500D01*
X858717D01*
G01X862567Y621000D02*
X862650Y621542D01*
X862775Y622000D01*
X862942Y622417D01*
X863150Y622875D01*
X863483Y623500D01*
X861817D01*
G01X855300Y657500D02*
Y667500D01*
G01X868700Y657500D02*
X855300D01*
G01X847208Y650317D02*
X847083Y650067D01*
X847000Y649775D01*
Y649442D01*
X847125Y649067D01*
X847333Y648775D01*
X847583Y648567D01*
X848000Y648400D01*
X848375Y648358D01*
X848750Y648442D01*
X849000Y648567D01*
X849250Y648817D01*
X849417Y649108D01*
X849500Y649400D01*
Y649692D01*
X849417Y649983D01*
X849292Y650233D01*
X849125Y650442D01*
G01X849500Y652500D02*
X849458Y652792D01*
X849333Y653125D01*
X849125Y653333D01*
X848833Y653417D01*
X848542Y653333D01*
X848292Y653083D01*
X848167Y652708D01*
Y652292D01*
X848083Y652042D01*
X847875Y651833D01*
X847583Y651750D01*
X847292Y651875D01*
X847083Y652167D01*
X847000Y652500D01*
X847083Y652833D01*
X847292Y653125D01*
X847583Y653250D01*
X847875Y653167D01*
X848083Y652958D01*
X848167Y652708D01*
Y652292D01*
X848292Y651917D01*
X848542Y651667D01*
X848833Y651583D01*
X849125Y651667D01*
X849333Y651875D01*
X849458Y652208D01*
X849500Y652500D01*
G01Y656100D02*
X847000D01*
X848792Y654558D01*
Y656642D01*
G01X855300Y667500D02*
X868700D01*
G01X841517Y708500D02*
Y711000D01*
X842558D01*
X842892Y710875D01*
X843100Y710708D01*
X843183Y710375D01*
X843100Y710042D01*
X842850Y709833D01*
X842558Y709708D01*
X841517D01*
G01X842558D02*
X843183Y708500D01*
G01X844533Y708875D02*
X844783Y708667D01*
X845075Y708542D01*
X845450Y708500D01*
X845825Y708583D01*
X846117Y708750D01*
X846325Y709042D01*
X846367Y709375D01*
X846283Y709708D01*
X846075Y709917D01*
X845783Y710083D01*
X845492Y710125D01*
X845200Y710083D01*
X844825Y709917D01*
X844950Y711000D01*
X846075D01*
G01X848550D02*
X848217Y710917D01*
X847967Y710708D01*
X847800Y710458D01*
X847675Y710125D01*
X847633Y709750D01*
X847675Y709375D01*
X847800Y709042D01*
X847967Y708792D01*
X848217Y708583D01*
X848550Y708500D01*
X848883Y708583D01*
X849133Y708792D01*
X849300Y709042D01*
X849425Y709375D01*
X849467Y709750D01*
X849425Y710125D01*
X849300Y710458D01*
X849133Y710708D01*
X848883Y710917D01*
X848550Y711000D01*
G01X851650Y708500D02*
Y711000D01*
X851150Y710500D01*
G01Y708500D02*
X852150D01*
G01X862200Y709000D02*
Y713000D01*
X854800D01*
G01X841658Y703812D02*
Y706312D01*
X842699D01*
X843033Y706187D01*
X843241Y706020D01*
X843324Y705687D01*
X843241Y705354D01*
X842991Y705145D01*
X842699Y705020D01*
X841658D01*
G01X842699D02*
X843324Y703812D01*
G01X844674Y704187D02*
X844924Y703979D01*
X845216Y703854D01*
X845591Y703812D01*
X845966Y703895D01*
X846258Y704062D01*
X846466Y704354D01*
X846508Y704687D01*
X846424Y705020D01*
X846216Y705229D01*
X845924Y705395D01*
X845633Y705437D01*
X845341Y705395D01*
X844966Y705229D01*
X845091Y706312D01*
X846216D01*
G01X848691D02*
X848358Y706229D01*
X848108Y706020D01*
X847941Y705770D01*
X847816Y705437D01*
X847774Y705062D01*
X847816Y704687D01*
X847941Y704354D01*
X848108Y704104D01*
X848358Y703895D01*
X848691Y703812D01*
X849024Y703895D01*
X849274Y704104D01*
X849441Y704354D01*
X849566Y704687D01*
X849608Y705062D01*
X849566Y705437D01*
X849441Y705770D01*
X849274Y706020D01*
X849024Y706229D01*
X848691Y706312D01*
G01X851791D02*
X851458Y706229D01*
X851208Y706020D01*
X851041Y705770D01*
X850916Y705437D01*
X850874Y705062D01*
X850916Y704687D01*
X851041Y704354D01*
X851208Y704104D01*
X851458Y703895D01*
X851791Y703812D01*
X852124Y703895D01*
X852374Y704104D01*
X852541Y704354D01*
X852666Y704687D01*
X852708Y705062D01*
X852666Y705437D01*
X852541Y705770D01*
X852374Y706020D01*
X852124Y706229D01*
X851791Y706312D01*
G01X854941Y708312D02*
Y704312D01*
X862341D01*
G01X845800Y717500D02*
Y713500D01*
X853200D01*
G01X842700Y854000D02*
Y844000D01*
G01X842200Y871000D02*
Y861000D01*
G01X844017Y857000D02*
Y859500D01*
X845058D01*
X845392Y859375D01*
X845600Y859208D01*
X845683Y858875D01*
X845600Y858542D01*
X845350Y858333D01*
X845058Y858208D01*
X844017D01*
G01X845058D02*
X845683Y857000D01*
G01X847158Y858042D02*
X847450Y858333D01*
X847700Y858500D01*
X848033Y858583D01*
X848325Y858500D01*
X848533Y858333D01*
X848700Y858083D01*
X848742Y857792D01*
X848700Y857542D01*
X848533Y857292D01*
X848283Y857083D01*
X847992Y857000D01*
X847658Y857083D01*
X847367Y857333D01*
X847200Y857708D01*
X847158Y858125D01*
X847242Y858667D01*
X847367Y858958D01*
X847575Y859250D01*
X847867Y859458D01*
X848158Y859500D01*
X848450Y859417D01*
X848658Y859208D01*
G01X851050Y857000D02*
X851342Y857042D01*
X851675Y857167D01*
X851883Y857375D01*
X851967Y857667D01*
X851883Y857958D01*
X851633Y858208D01*
X851258Y858333D01*
X850842D01*
X850592Y858417D01*
X850383Y858625D01*
X850300Y858917D01*
X850425Y859208D01*
X850717Y859417D01*
X851050Y859500D01*
X851383Y859417D01*
X851675Y859208D01*
X851800Y858917D01*
X851717Y858625D01*
X851508Y858417D01*
X851258Y858333D01*
X850842D01*
X850467Y858208D01*
X850217Y857958D01*
X850133Y857667D01*
X850217Y857375D01*
X850425Y857167D01*
X850758Y857042D01*
X851050Y857000D01*
G01X853233Y857375D02*
X853483Y857167D01*
X853775Y857042D01*
X854150Y857000D01*
X854525Y857083D01*
X854817Y857250D01*
X855025Y857542D01*
X855067Y857875D01*
X854983Y858208D01*
X854775Y858417D01*
X854483Y858583D01*
X854192Y858625D01*
X853900Y858583D01*
X853525Y858417D01*
X853650Y859500D01*
X854775D01*
G01X846317Y875292D02*
X846067Y875417D01*
X845775Y875500D01*
X845442D01*
X845067Y875375D01*
X844775Y875167D01*
X844567Y874917D01*
X844400Y874500D01*
X844358Y874125D01*
X844442Y873750D01*
X844567Y873500D01*
X844817Y873250D01*
X845108Y873083D01*
X845400Y873000D01*
X845692D01*
X845983Y873083D01*
X846233Y873208D01*
X846442Y873375D01*
G01X848500Y873000D02*
X848792Y873042D01*
X849125Y873167D01*
X849333Y873375D01*
X849417Y873667D01*
X849333Y873958D01*
X849083Y874208D01*
X848708Y874333D01*
X848292D01*
X848042Y874417D01*
X847833Y874625D01*
X847750Y874917D01*
X847875Y875208D01*
X848167Y875417D01*
X848500Y875500D01*
X848833Y875417D01*
X849125Y875208D01*
X849250Y874917D01*
X849167Y874625D01*
X848958Y874417D01*
X848708Y874333D01*
X848292D01*
X847917Y874208D01*
X847667Y873958D01*
X847583Y873667D01*
X847667Y873375D01*
X847875Y873167D01*
X848208Y873042D01*
X848500Y873000D01*
G01X850683Y873500D02*
X850933Y873208D01*
X851267Y873042D01*
X851642Y873000D01*
X851975Y873042D01*
X852308Y873250D01*
X852517Y873500D01*
X852558Y873750D01*
X852475Y874042D01*
X852183Y874250D01*
X851892Y874333D01*
X851517D01*
G01X851892D02*
X852142Y874458D01*
X852350Y874667D01*
X852433Y874917D01*
X852350Y875167D01*
X852142Y875375D01*
X851767Y875500D01*
X851392Y875458D01*
X851017Y875292D01*
G01X862017Y68000D02*
Y70500D01*
X863058D01*
X863392Y70375D01*
X863600Y70208D01*
X863683Y69875D01*
X863600Y69542D01*
X863350Y69333D01*
X863058Y69208D01*
X862017D01*
G01X863058D02*
X863683Y68000D01*
G01X865033Y68375D02*
X865283Y68167D01*
X865575Y68042D01*
X865950Y68000D01*
X866325Y68083D01*
X866617Y68250D01*
X866825Y68542D01*
X866867Y68875D01*
X866783Y69208D01*
X866575Y69417D01*
X866283Y69583D01*
X865992Y69625D01*
X865700Y69583D01*
X865325Y69417D01*
X865450Y70500D01*
X866575D01*
G01X869550Y68000D02*
Y70500D01*
X868008Y68708D01*
X870092D01*
G01X871233Y68500D02*
X871483Y68208D01*
X871817Y68042D01*
X872192Y68000D01*
X872525Y68042D01*
X872858Y68250D01*
X873067Y68500D01*
X873108Y68750D01*
X873025Y69042D01*
X872733Y69250D01*
X872442Y69333D01*
X872067D01*
G01X872442D02*
X872692Y69458D01*
X872900Y69667D01*
X872983Y69917D01*
X872900Y70167D01*
X872692Y70375D01*
X872317Y70500D01*
X871942Y70458D01*
X871567Y70292D01*
G01X861967Y72500D02*
Y75000D01*
X863008D01*
X863342Y74875D01*
X863550Y74708D01*
X863633Y74375D01*
X863550Y74042D01*
X863300Y73833D01*
X863008Y73708D01*
X861967D01*
G01X863008D02*
X863633Y72500D01*
G01X864983Y72875D02*
X865233Y72667D01*
X865525Y72542D01*
X865900Y72500D01*
X866275Y72583D01*
X866567Y72750D01*
X866775Y73042D01*
X866817Y73375D01*
X866733Y73708D01*
X866525Y73917D01*
X866233Y74083D01*
X865942Y74125D01*
X865650Y74083D01*
X865275Y73917D01*
X865400Y75000D01*
X866525D01*
G01X868917Y72500D02*
X869000Y73042D01*
X869125Y73500D01*
X869292Y73917D01*
X869500Y74375D01*
X869833Y75000D01*
X868167D01*
G01X872017Y72500D02*
X872100Y73042D01*
X872225Y73500D01*
X872392Y73917D01*
X872600Y74375D01*
X872933Y75000D01*
X871267D01*
G01X875700Y72500D02*
Y75000D01*
X874158Y73208D01*
X876242D01*
G01X860000Y85450D02*
X859958Y85117D01*
X859792Y84825D01*
X859542Y84575D01*
X859250Y84408D01*
X858917Y84325D01*
X858583D01*
X858250Y84408D01*
X857958Y84575D01*
X857708Y84825D01*
X857542Y85117D01*
X857500Y85450D01*
X857542Y85783D01*
X857708Y86075D01*
X857958Y86325D01*
X858250Y86492D01*
X858583Y86575D01*
X858917D01*
X859250Y86492D01*
X859542Y86325D01*
X859792Y86075D01*
X859958Y85783D01*
X860000Y85450D01*
G01X859333Y85783D02*
X860000Y86283D01*
G01X858958Y87758D02*
X858667Y88050D01*
X858500Y88300D01*
X858417Y88633D01*
X858500Y88925D01*
X858667Y89133D01*
X858917Y89300D01*
X859208Y89342D01*
X859458Y89300D01*
X859708Y89133D01*
X859917Y88883D01*
X860000Y88592D01*
X859917Y88258D01*
X859667Y87967D01*
X859292Y87800D01*
X858875Y87758D01*
X858333Y87842D01*
X858042Y87967D01*
X857750Y88175D01*
X857542Y88467D01*
X857500Y88758D01*
X857583Y89050D01*
X857792Y89258D01*
G01X863487Y79126D02*
X876487D01*
G01X863487Y93126D02*
Y79126D01*
G01X876487Y93126D02*
X863487D01*
G01X878200Y99500D02*
Y103500D01*
X870800D01*
G01X868500Y106200D02*
X864500D01*
Y98800D01*
G01X859719Y110424D02*
Y112924D01*
X860760D01*
X861094Y112799D01*
X861302Y112632D01*
X861385Y112299D01*
X861302Y111966D01*
X861052Y111757D01*
X860760Y111632D01*
X859719D01*
G01X860760D02*
X861385Y110424D01*
G01X863569D02*
X863652Y110966D01*
X863777Y111424D01*
X863944Y111841D01*
X864152Y112299D01*
X864485Y112924D01*
X862819D01*
G01X866752Y110424D02*
X867044Y110466D01*
X867377Y110591D01*
X867585Y110799D01*
X867669Y111091D01*
X867585Y111382D01*
X867335Y111632D01*
X866960Y111757D01*
X866544D01*
X866294Y111841D01*
X866085Y112049D01*
X866002Y112341D01*
X866127Y112632D01*
X866419Y112841D01*
X866752Y112924D01*
X867085Y112841D01*
X867377Y112632D01*
X867502Y112341D01*
X867419Y112049D01*
X867210Y111841D01*
X866960Y111757D01*
X866544D01*
X866169Y111632D01*
X865919Y111382D01*
X865835Y111091D01*
X865919Y110799D01*
X866127Y110591D01*
X866460Y110466D01*
X866752Y110424D01*
G01X869144Y110716D02*
X869435Y110507D01*
X869769Y110424D01*
X870102Y110507D01*
X870394Y110757D01*
X870602Y111132D01*
X870685Y111507D01*
Y111966D01*
X870602Y112341D01*
X870394Y112674D01*
X870144Y112841D01*
X869852Y112924D01*
X869519Y112841D01*
X869269Y112674D01*
X869102Y112424D01*
X869019Y112091D01*
X869102Y111799D01*
X869310Y111507D01*
X869560Y111341D01*
X869852Y111299D01*
X870185Y111382D01*
X870435Y111591D01*
X870685Y111966D01*
G01X872952Y112924D02*
X872619Y112841D01*
X872369Y112632D01*
X872202Y112382D01*
X872077Y112049D01*
X872035Y111674D01*
X872077Y111299D01*
X872202Y110966D01*
X872369Y110716D01*
X872619Y110507D01*
X872952Y110424D01*
X873285Y110507D01*
X873535Y110716D01*
X873702Y110966D01*
X873827Y111299D01*
X873869Y111674D01*
X873827Y112049D01*
X873702Y112382D01*
X873535Y112632D01*
X873285Y112841D01*
X872952Y112924D01*
G01X866555Y258067D02*
X864055D01*
Y259108D01*
X864180Y259442D01*
X864347Y259650D01*
X864680Y259733D01*
X865013Y259650D01*
X865222Y259400D01*
X865347Y259108D01*
Y258067D01*
G01Y259108D02*
X866555Y259733D01*
G01Y262000D02*
X864055D01*
X864555Y261500D01*
G01X866555D02*
Y262500D01*
G01X866180Y264183D02*
X866388Y264433D01*
X866513Y264725D01*
X866555Y265100D01*
X866472Y265475D01*
X866305Y265767D01*
X866013Y265975D01*
X865680Y266017D01*
X865347Y265933D01*
X865138Y265725D01*
X864972Y265433D01*
X864930Y265142D01*
X864972Y264850D01*
X865138Y264475D01*
X864055Y264600D01*
Y265725D01*
G01X867055Y275700D02*
X863055D01*
Y268300D01*
G01X862055Y258067D02*
X859555D01*
Y259108D01*
X859680Y259442D01*
X859847Y259650D01*
X860180Y259733D01*
X860513Y259650D01*
X860722Y259400D01*
X860847Y259108D01*
Y258067D01*
G01Y259108D02*
X862055Y259733D01*
G01Y262000D02*
X859555D01*
X860055Y261500D01*
G01X862055D02*
Y262500D01*
G01Y265100D02*
X859555D01*
X860055Y264600D01*
G01X862055D02*
Y265600D01*
G01X862555Y275700D02*
X858555D01*
Y268300D01*
G01X868220Y350830D02*
Y350680D01*
X866970Y349430D01*
X865770Y350630D01*
Y350880D01*
G01X858220Y350830D02*
X875420D01*
Y340930D01*
X858220D01*
Y350830D01*
G01X870820Y362080D02*
X866820D01*
Y354680D01*
G01X865820Y362080D02*
X861820D01*
Y354680D01*
G01X869467Y385000D02*
Y387500D01*
X870467D01*
X870800Y387375D01*
X871050Y387083D01*
X871133Y386750D01*
X871050Y386417D01*
X870842Y386167D01*
X870467Y386042D01*
X869467D01*
G01X872567Y385000D02*
Y387500D01*
X873608D01*
X873942Y387375D01*
X874150Y387208D01*
X874233Y386875D01*
X874150Y386542D01*
X873900Y386333D01*
X873608Y386208D01*
X872567D01*
G01X873608D02*
X874233Y385000D01*
G01X876500D02*
Y387500D01*
X876000Y387000D01*
G01Y385000D02*
X877000D01*
G01X878808Y387083D02*
X879058Y387333D01*
X879350Y387458D01*
X879683Y387500D01*
X880100Y387417D01*
X880392Y387208D01*
X880475Y386958D01*
X880433Y386708D01*
X880267Y386500D01*
X879433Y386083D01*
X879058Y385792D01*
X878808Y385375D01*
X878725Y385000D01*
X880475D01*
G01X882700Y387500D02*
X882367Y387417D01*
X882117Y387208D01*
X881950Y386958D01*
X881825Y386625D01*
X881783Y386250D01*
X881825Y385875D01*
X881950Y385542D01*
X882117Y385292D01*
X882367Y385083D01*
X882700Y385000D01*
X883033Y385083D01*
X883283Y385292D01*
X883450Y385542D01*
X883575Y385875D01*
X883617Y386250D01*
X883575Y386625D01*
X883450Y386958D01*
X883283Y387208D01*
X883033Y387417D01*
X882700Y387500D01*
G01X883300Y383500D02*
Y375500D01*
X865700D01*
Y383500D01*
X883300D01*
G01X865000Y393017D02*
X862500D01*
Y394017D01*
X862625Y394350D01*
X862917Y394600D01*
X863250Y394683D01*
X863583Y394600D01*
X863833Y394392D01*
X863958Y394017D01*
Y393017D01*
G01X862500Y396033D02*
X864292D01*
X864667Y396200D01*
X864917Y396533D01*
X865000Y396950D01*
X864917Y397367D01*
X864667Y397700D01*
X864292Y397867D01*
X862500D01*
G01X865000Y400050D02*
X862500D01*
X863000Y399550D01*
G01X865000D02*
Y400550D01*
G01X862500Y403150D02*
X862583Y402817D01*
X862792Y402567D01*
X863042Y402400D01*
X863375Y402275D01*
X863750Y402233D01*
X864125Y402275D01*
X864458Y402400D01*
X864708Y402567D01*
X864917Y402817D01*
X865000Y403150D01*
X864917Y403483D01*
X864708Y403733D01*
X864458Y403900D01*
X864125Y404025D01*
X863750Y404067D01*
X863375Y404025D01*
X863042Y403900D01*
X862792Y403733D01*
X862583Y403483D01*
X862500Y403150D01*
G01X855624Y387728D02*
X860624D01*
Y392728D01*
G01Y410428D02*
Y415428D01*
X855624D01*
G01X859217Y406696D02*
X862217D01*
G01X875200Y412000D02*
Y416000D01*
X867800D01*
G01X875200Y402500D02*
Y406500D01*
X867800D01*
G01X869000Y438200D02*
X865000D01*
Y430800D01*
G01X864500Y438200D02*
X860500D01*
Y430800D01*
G01X858000Y439967D02*
X855500D01*
Y440967D01*
X855625Y441300D01*
X855917Y441550D01*
X856250Y441633D01*
X856583Y441550D01*
X856833Y441342D01*
X856958Y440967D01*
Y439967D01*
G01X858000Y443067D02*
X855500D01*
Y444108D01*
X855625Y444442D01*
X855792Y444650D01*
X856125Y444733D01*
X856458Y444650D01*
X856667Y444400D01*
X856792Y444108D01*
Y443067D01*
G01Y444108D02*
X858000Y444733D01*
G01Y447000D02*
X855500D01*
X856000Y446500D01*
G01X858000D02*
Y447500D01*
G01X855917Y449308D02*
X855667Y449558D01*
X855542Y449850D01*
X855500Y450183D01*
X855583Y450600D01*
X855792Y450892D01*
X856042Y450975D01*
X856292Y450933D01*
X856500Y450767D01*
X856917Y449933D01*
X857208Y449558D01*
X857625Y449308D01*
X858000Y449225D01*
Y450975D01*
G01X856958Y452408D02*
X856667Y452700D01*
X856500Y452950D01*
X856417Y453283D01*
X856500Y453575D01*
X856667Y453783D01*
X856917Y453950D01*
X857208Y453992D01*
X857458Y453950D01*
X857708Y453783D01*
X857917Y453533D01*
X858000Y453242D01*
X857917Y452908D01*
X857667Y452617D01*
X857292Y452450D01*
X856875Y452408D01*
X856333Y452492D01*
X856042Y452617D01*
X855750Y452825D01*
X855542Y453117D01*
X855500Y453408D01*
X855583Y453700D01*
X855792Y453908D01*
G01X865500Y455400D02*
X865458Y455067D01*
X865292Y454775D01*
X865042Y454525D01*
X864750Y454358D01*
X864417Y454275D01*
X864083D01*
X863750Y454358D01*
X863458Y454525D01*
X863208Y454775D01*
X863042Y455067D01*
X863000Y455400D01*
X863042Y455733D01*
X863208Y456025D01*
X863458Y456275D01*
X863750Y456442D01*
X864083Y456525D01*
X864417D01*
X864750Y456442D01*
X865042Y456275D01*
X865292Y456025D01*
X865458Y455733D01*
X865500Y455400D01*
G01X864833Y455733D02*
X865500Y456233D01*
G01X865208Y457792D02*
X865417Y458083D01*
X865500Y458417D01*
X865417Y458750D01*
X865167Y459042D01*
X864792Y459250D01*
X864417Y459333D01*
X863958D01*
X863583Y459250D01*
X863250Y459042D01*
X863083Y458792D01*
X863000Y458500D01*
X863083Y458167D01*
X863250Y457917D01*
X863500Y457750D01*
X863833Y457667D01*
X864125Y457750D01*
X864417Y457958D01*
X864583Y458208D01*
X864625Y458500D01*
X864542Y458833D01*
X864333Y459083D01*
X863958Y459333D01*
G01X865500Y461517D02*
X864958Y461600D01*
X864500Y461725D01*
X864083Y461892D01*
X863625Y462100D01*
X863000Y462433D01*
Y460767D01*
G01X868000Y451000D02*
X881000D01*
G01X868000Y465000D02*
Y451000D01*
G01X881000Y465000D02*
X868000D01*
G01X871200Y465500D02*
Y469500D01*
X863800D01*
G01X863100Y473200D02*
X873900D01*
G01X863100Y480800D02*
Y473200D01*
G01X873900Y480800D02*
X863100D01*
G01X861517Y483000D02*
Y485500D01*
X862558D01*
X862892Y485375D01*
X863100Y485208D01*
X863183Y484875D01*
X863100Y484542D01*
X862850Y484333D01*
X862558Y484208D01*
X861517D01*
G01X862558D02*
X863183Y483000D01*
G01X864658Y484042D02*
X864950Y484333D01*
X865200Y484500D01*
X865533Y484583D01*
X865825Y484500D01*
X866033Y484333D01*
X866200Y484083D01*
X866242Y483792D01*
X866200Y483542D01*
X866033Y483292D01*
X865783Y483083D01*
X865492Y483000D01*
X865158Y483083D01*
X864867Y483333D01*
X864700Y483708D01*
X864658Y484125D01*
X864742Y484667D01*
X864867Y484958D01*
X865075Y485250D01*
X865367Y485458D01*
X865658Y485500D01*
X865950Y485417D01*
X866158Y485208D01*
G01X868550Y485500D02*
X868217Y485417D01*
X867967Y485208D01*
X867800Y484958D01*
X867675Y484625D01*
X867633Y484250D01*
X867675Y483875D01*
X867800Y483542D01*
X867967Y483292D01*
X868217Y483083D01*
X868550Y483000D01*
X868883Y483083D01*
X869133Y483292D01*
X869300Y483542D01*
X869425Y483875D01*
X869467Y484250D01*
X869425Y484625D01*
X869300Y484958D01*
X869133Y485208D01*
X868883Y485417D01*
X868550Y485500D01*
G01X872150Y483000D02*
Y485500D01*
X870608Y483708D01*
X872692D01*
G01X869000Y489400D02*
X868958Y489067D01*
X868792Y488775D01*
X868542Y488525D01*
X868250Y488358D01*
X867917Y488275D01*
X867583D01*
X867250Y488358D01*
X866958Y488525D01*
X866708Y488775D01*
X866542Y489067D01*
X866500Y489400D01*
X866542Y489733D01*
X866708Y490025D01*
X866958Y490275D01*
X867250Y490442D01*
X867583Y490525D01*
X867917D01*
X868250Y490442D01*
X868542Y490275D01*
X868792Y490025D01*
X868958Y489733D01*
X869000Y489400D01*
G01X868333Y489733D02*
X869000Y490233D01*
G01Y492500D02*
X868958Y492792D01*
X868833Y493125D01*
X868625Y493333D01*
X868333Y493417D01*
X868042Y493333D01*
X867792Y493083D01*
X867667Y492708D01*
Y492292D01*
X867583Y492042D01*
X867375Y491833D01*
X867083Y491750D01*
X866792Y491875D01*
X866583Y492167D01*
X866500Y492500D01*
X866583Y492833D01*
X866792Y493125D01*
X867083Y493250D01*
X867375Y493167D01*
X867583Y492958D01*
X867667Y492708D01*
Y492292D01*
X867792Y491917D01*
X868042Y491667D01*
X868333Y491583D01*
X868625Y491667D01*
X868833Y491875D01*
X868958Y492208D01*
X869000Y492500D01*
G01X866500Y495600D02*
X866583Y495267D01*
X866792Y495017D01*
X867042Y494850D01*
X867375Y494725D01*
X867750Y494683D01*
X868125Y494725D01*
X868458Y494850D01*
X868708Y495017D01*
X868917Y495267D01*
X869000Y495600D01*
X868917Y495933D01*
X868708Y496183D01*
X868458Y496350D01*
X868125Y496475D01*
X867750Y496517D01*
X867375Y496475D01*
X867042Y496350D01*
X866792Y496183D01*
X866583Y495933D01*
X866500Y495600D01*
G01X870500Y626222D02*
Y612222D01*
G01D02*
X883500D01*
G01X860017Y607500D02*
Y610000D01*
X861058D01*
X861392Y609875D01*
X861600Y609708D01*
X861683Y609375D01*
X861600Y609042D01*
X861350Y608833D01*
X861058Y608708D01*
X860017D01*
G01X861058D02*
X861683Y607500D01*
G01X863033Y607875D02*
X863283Y607667D01*
X863575Y607542D01*
X863950Y607500D01*
X864325Y607583D01*
X864617Y607750D01*
X864825Y608042D01*
X864867Y608375D01*
X864783Y608708D01*
X864575Y608917D01*
X864283Y609083D01*
X863992Y609125D01*
X863700Y609083D01*
X863325Y608917D01*
X863450Y610000D01*
X864575D01*
G01X867050Y607500D02*
X867342Y607542D01*
X867675Y607667D01*
X867883Y607875D01*
X867967Y608167D01*
X867883Y608458D01*
X867633Y608708D01*
X867258Y608833D01*
X866842D01*
X866592Y608917D01*
X866383Y609125D01*
X866300Y609417D01*
X866425Y609708D01*
X866717Y609917D01*
X867050Y610000D01*
X867383Y609917D01*
X867675Y609708D01*
X867800Y609417D01*
X867717Y609125D01*
X867508Y608917D01*
X867258Y608833D01*
X866842D01*
X866467Y608708D01*
X866217Y608458D01*
X866133Y608167D01*
X866217Y607875D01*
X866425Y607667D01*
X866758Y607542D01*
X867050Y607500D01*
G01X870150D02*
Y610000D01*
X869650Y609500D01*
G01Y607500D02*
X870650D01*
G01X865500Y611800D02*
X869500D01*
Y619200D01*
G01X883500Y626222D02*
X870500D01*
G01X865500Y619300D02*
X869500D01*
Y626700D01*
G01X869200Y633800D02*
Y645200D01*
G01X855800Y633800D02*
X869200D01*
G01X855800Y645200D02*
Y633800D01*
G01X869200Y645200D02*
X855800D01*
G01X868700Y667500D02*
Y657500D01*
G01X859433Y672500D02*
Y670708D01*
X859600Y670333D01*
X859933Y670083D01*
X860350Y670000D01*
X860767Y670083D01*
X861100Y670333D01*
X861267Y670708D01*
Y672500D01*
G01X863450Y670000D02*
Y672500D01*
X862950Y672000D01*
G01Y670000D02*
X863950D01*
G01X866467D02*
X866550Y670542D01*
X866675Y671000D01*
X866842Y671417D01*
X867050Y671875D01*
X867383Y672500D01*
X865717D01*
G01X869650Y670000D02*
X869942Y670042D01*
X870275Y670167D01*
X870483Y670375D01*
X870567Y670667D01*
X870483Y670958D01*
X870233Y671208D01*
X869858Y671333D01*
X869442D01*
X869192Y671417D01*
X868983Y671625D01*
X868900Y671917D01*
X869025Y672208D01*
X869317Y672417D01*
X869650Y672500D01*
X869983Y672417D01*
X870275Y672208D01*
X870400Y671917D01*
X870317Y671625D01*
X870108Y671417D01*
X869858Y671333D01*
X869442D01*
X869067Y671208D01*
X868817Y670958D01*
X868733Y670667D01*
X868817Y670375D01*
X869025Y670167D01*
X869358Y670042D01*
X869650Y670000D01*
G01X871500Y674300D02*
X875500D01*
Y681700D01*
G01X864468Y684784D02*
Y697784D01*
G01X865796Y684711D02*
X877196D01*
G01X865796Y698111D02*
Y684711D01*
G01X877196Y698111D02*
X865796D01*
G01X875468Y706984D02*
X871468D01*
Y699584D01*
G01X863468Y704584D02*
X867468D01*
Y711984D01*
G01X871468Y706984D02*
X867468D01*
Y699584D01*
G01X878800Y736100D02*
X859600D01*
Y724900D01*
X878800D01*
Y736100D01*
X878400D01*
G01X869983Y750000D02*
Y748208D01*
X870150Y747833D01*
X870483Y747583D01*
X870900Y747500D01*
X871317Y747583D01*
X871650Y747833D01*
X871817Y748208D01*
Y750000D01*
G01X873083Y748000D02*
X873333Y747708D01*
X873667Y747542D01*
X874042Y747500D01*
X874375Y747542D01*
X874708Y747750D01*
X874917Y748000D01*
X874958Y748250D01*
X874875Y748542D01*
X874583Y748750D01*
X874292Y748833D01*
X873917D01*
G01X874292D02*
X874542Y748958D01*
X874750Y749167D01*
X874833Y749417D01*
X874750Y749667D01*
X874542Y749875D01*
X874167Y750000D01*
X873792Y749958D01*
X873417Y749792D01*
G01X876308Y748542D02*
X876600Y748833D01*
X876850Y749000D01*
X877183Y749083D01*
X877475Y749000D01*
X877683Y748833D01*
X877850Y748583D01*
X877892Y748292D01*
X877850Y748042D01*
X877683Y747792D01*
X877433Y747583D01*
X877142Y747500D01*
X876808Y747583D01*
X876517Y747833D01*
X876350Y748208D01*
X876308Y748625D01*
X876392Y749167D01*
X876517Y749458D01*
X876725Y749750D01*
X877017Y749958D01*
X877308Y750000D01*
X877600Y749917D01*
X877808Y749708D01*
G01X890000Y39900D02*
X889958Y39567D01*
X889792Y39275D01*
X889542Y39025D01*
X889250Y38858D01*
X888917Y38775D01*
X888583D01*
X888250Y38858D01*
X887958Y39025D01*
X887708Y39275D01*
X887542Y39567D01*
X887500Y39900D01*
X887542Y40233D01*
X887708Y40525D01*
X887958Y40775D01*
X888250Y40942D01*
X888583Y41025D01*
X888917D01*
X889250Y40942D01*
X889542Y40775D01*
X889792Y40525D01*
X889958Y40233D01*
X890000Y39900D01*
G01X889333Y40233D02*
X890000Y40733D01*
G01Y43000D02*
X887500D01*
X888000Y42500D01*
G01X890000D02*
Y43500D01*
G01X889500Y45183D02*
X889792Y45433D01*
X889958Y45767D01*
X890000Y46142D01*
X889958Y46475D01*
X889750Y46808D01*
X889500Y47017D01*
X889250Y47058D01*
X888958Y46975D01*
X888750Y46683D01*
X888667Y46392D01*
Y46017D01*
G01Y46392D02*
X888542Y46642D01*
X888333Y46850D01*
X888083Y46933D01*
X887833Y46850D01*
X887625Y46642D01*
X887500Y46267D01*
X887542Y45892D01*
X887708Y45517D01*
G01X882500Y50000D02*
X896500D01*
G01X882500Y63000D02*
Y50000D01*
G01X901500Y64000D02*
X882500D01*
G01D02*
Y77000D01*
G01X896500Y63000D02*
X882500D01*
G01Y77000D02*
X901500D01*
G01Y78000D02*
X882500D01*
G01D02*
Y91000D01*
G01X876487Y79126D02*
Y93126D01*
G01X881500Y93200D02*
X877500D01*
Y85800D01*
G01X882500Y91000D02*
X901500D01*
G01X878467Y95000D02*
Y97500D01*
X879508D01*
X879842Y97375D01*
X880050Y97208D01*
X880133Y96875D01*
X880050Y96542D01*
X879800Y96333D01*
X879508Y96208D01*
X878467D01*
G01X879508D02*
X880133Y95000D01*
G01X882317D02*
X882400Y95542D01*
X882525Y96000D01*
X882692Y96417D01*
X882900Y96875D01*
X883233Y97500D01*
X881567D01*
G01X885500Y95000D02*
X885792Y95042D01*
X886125Y95167D01*
X886333Y95375D01*
X886417Y95667D01*
X886333Y95958D01*
X886083Y96208D01*
X885708Y96333D01*
X885292D01*
X885042Y96417D01*
X884833Y96625D01*
X884750Y96917D01*
X884875Y97208D01*
X885167Y97417D01*
X885500Y97500D01*
X885833Y97417D01*
X886125Y97208D01*
X886250Y96917D01*
X886167Y96625D01*
X885958Y96417D01*
X885708Y96333D01*
X885292D01*
X884917Y96208D01*
X884667Y95958D01*
X884583Y95667D01*
X884667Y95375D01*
X884875Y95167D01*
X885208Y95042D01*
X885500Y95000D01*
G01X887892Y95292D02*
X888183Y95083D01*
X888517Y95000D01*
X888850Y95083D01*
X889142Y95333D01*
X889350Y95708D01*
X889433Y96083D01*
Y96542D01*
X889350Y96917D01*
X889142Y97250D01*
X888892Y97417D01*
X888600Y97500D01*
X888267Y97417D01*
X888017Y97250D01*
X887850Y97000D01*
X887767Y96667D01*
X887850Y96375D01*
X888058Y96083D01*
X888308Y95917D01*
X888600Y95875D01*
X888933Y95958D01*
X889183Y96167D01*
X889433Y96542D01*
G01X890908Y97083D02*
X891158Y97333D01*
X891450Y97458D01*
X891783Y97500D01*
X892200Y97417D01*
X892492Y97208D01*
X892575Y96958D01*
X892533Y96708D01*
X892367Y96500D01*
X891533Y96083D01*
X891158Y95792D01*
X890908Y95375D01*
X890825Y95000D01*
X892575D01*
G01X881467Y100000D02*
Y102500D01*
X882508D01*
X882842Y102375D01*
X883050Y102208D01*
X883133Y101875D01*
X883050Y101542D01*
X882800Y101333D01*
X882508Y101208D01*
X881467D01*
G01X882508D02*
X883133Y100000D01*
G01X885317D02*
X885400Y100542D01*
X885525Y101000D01*
X885692Y101417D01*
X885900Y101875D01*
X886233Y102500D01*
X884567D01*
G01X888500Y100000D02*
X888792Y100042D01*
X889125Y100167D01*
X889333Y100375D01*
X889417Y100667D01*
X889333Y100958D01*
X889083Y101208D01*
X888708Y101333D01*
X888292D01*
X888042Y101417D01*
X887833Y101625D01*
X887750Y101917D01*
X887875Y102208D01*
X888167Y102417D01*
X888500Y102500D01*
X888833Y102417D01*
X889125Y102208D01*
X889250Y101917D01*
X889167Y101625D01*
X888958Y101417D01*
X888708Y101333D01*
X888292D01*
X887917Y101208D01*
X887667Y100958D01*
X887583Y100667D01*
X887667Y100375D01*
X887875Y100167D01*
X888208Y100042D01*
X888500Y100000D01*
G01X891600D02*
X891892Y100042D01*
X892225Y100167D01*
X892433Y100375D01*
X892517Y100667D01*
X892433Y100958D01*
X892183Y101208D01*
X891808Y101333D01*
X891392D01*
X891142Y101417D01*
X890933Y101625D01*
X890850Y101917D01*
X890975Y102208D01*
X891267Y102417D01*
X891600Y102500D01*
X891933Y102417D01*
X892225Y102208D01*
X892350Y101917D01*
X892267Y101625D01*
X892058Y101417D01*
X891808Y101333D01*
X891392D01*
X891017Y101208D01*
X890767Y100958D01*
X890683Y100667D01*
X890767Y100375D01*
X890975Y100167D01*
X891308Y100042D01*
X891600Y100000D01*
G01X893992Y100292D02*
X894283Y100083D01*
X894617Y100000D01*
X894950Y100083D01*
X895242Y100333D01*
X895450Y100708D01*
X895533Y101083D01*
Y101542D01*
X895450Y101917D01*
X895242Y102250D01*
X894992Y102417D01*
X894700Y102500D01*
X894367Y102417D01*
X894117Y102250D01*
X893950Y102000D01*
X893867Y101667D01*
X893950Y101375D01*
X894158Y101083D01*
X894408Y100917D01*
X894700Y100875D01*
X895033Y100958D01*
X895283Y101167D01*
X895533Y101542D01*
G01X887925Y336333D02*
X888258Y336125D01*
X888633Y336000D01*
X888967D01*
X889300Y336125D01*
X889550Y336333D01*
X889675Y336625D01*
X889592Y336917D01*
X889383Y337167D01*
X889008Y337333D01*
X888508Y337417D01*
X888217Y337583D01*
X888092Y337875D01*
X888175Y338167D01*
X888383Y338375D01*
X888675Y338500D01*
X888967D01*
X889258Y338417D01*
X889508Y338208D01*
G01X891067Y336000D02*
Y338500D01*
X892108D01*
X892442Y338375D01*
X892650Y338208D01*
X892733Y337875D01*
X892650Y337542D01*
X892400Y337333D01*
X892108Y337208D01*
X891067D01*
G01X892108D02*
X892733Y336000D01*
G01X894292Y336292D02*
X894583Y336083D01*
X894917Y336000D01*
X895250Y336083D01*
X895542Y336333D01*
X895750Y336708D01*
X895833Y337083D01*
Y337542D01*
X895750Y337917D01*
X895542Y338250D01*
X895292Y338417D01*
X895000Y338500D01*
X894667Y338417D01*
X894417Y338250D01*
X894250Y338000D01*
X894167Y337667D01*
X894250Y337375D01*
X894458Y337083D01*
X894708Y336917D01*
X895000Y336875D01*
X895333Y336958D01*
X895583Y337167D01*
X895833Y337542D01*
G01X897308Y338083D02*
X897558Y338333D01*
X897850Y338458D01*
X898183Y338500D01*
X898600Y338417D01*
X898892Y338208D01*
X898975Y337958D01*
X898933Y337708D01*
X898767Y337500D01*
X897933Y337083D01*
X897558Y336792D01*
X897308Y336375D01*
X897225Y336000D01*
X898975D01*
G01X900283Y336375D02*
X900533Y336167D01*
X900825Y336042D01*
X901200Y336000D01*
X901575Y336083D01*
X901867Y336250D01*
X902075Y336542D01*
X902117Y336875D01*
X902033Y337208D01*
X901825Y337417D01*
X901533Y337583D01*
X901242Y337625D01*
X900950Y337583D01*
X900575Y337417D01*
X900700Y338500D01*
X901825D01*
G01X887925Y332333D02*
X888258Y332125D01*
X888633Y332000D01*
X888967D01*
X889300Y332125D01*
X889550Y332333D01*
X889675Y332625D01*
X889592Y332917D01*
X889383Y333167D01*
X889008Y333333D01*
X888508Y333417D01*
X888217Y333583D01*
X888092Y333875D01*
X888175Y334167D01*
X888383Y334375D01*
X888675Y334500D01*
X888967D01*
X889258Y334417D01*
X889508Y334208D01*
G01X891067Y332000D02*
Y334500D01*
X892108D01*
X892442Y334375D01*
X892650Y334208D01*
X892733Y333875D01*
X892650Y333542D01*
X892400Y333333D01*
X892108Y333208D01*
X891067D01*
G01X892108D02*
X892733Y332000D01*
G01X894292Y332292D02*
X894583Y332083D01*
X894917Y332000D01*
X895250Y332083D01*
X895542Y332333D01*
X895750Y332708D01*
X895833Y333083D01*
Y333542D01*
X895750Y333917D01*
X895542Y334250D01*
X895292Y334417D01*
X895000Y334500D01*
X894667Y334417D01*
X894417Y334250D01*
X894250Y334000D01*
X894167Y333667D01*
X894250Y333375D01*
X894458Y333083D01*
X894708Y332917D01*
X895000Y332875D01*
X895333Y332958D01*
X895583Y333167D01*
X895833Y333542D01*
G01X897308Y334083D02*
X897558Y334333D01*
X897850Y334458D01*
X898183Y334500D01*
X898600Y334417D01*
X898892Y334208D01*
X898975Y333958D01*
X898933Y333708D01*
X898767Y333500D01*
X897933Y333083D01*
X897558Y332792D01*
X897308Y332375D01*
X897225Y332000D01*
X898975D01*
G01X900408Y333042D02*
X900700Y333333D01*
X900950Y333500D01*
X901283Y333583D01*
X901575Y333500D01*
X901783Y333333D01*
X901950Y333083D01*
X901992Y332792D01*
X901950Y332542D01*
X901783Y332292D01*
X901533Y332083D01*
X901242Y332000D01*
X900908Y332083D01*
X900617Y332333D01*
X900450Y332708D01*
X900408Y333125D01*
X900492Y333667D01*
X900617Y333958D01*
X900825Y334250D01*
X901117Y334458D01*
X901408Y334500D01*
X901700Y334417D01*
X901908Y334208D01*
G01X876800Y336500D02*
Y332500D01*
X884200D01*
G01X889767Y329792D02*
X889517Y329917D01*
X889225Y330000D01*
X888892D01*
X888517Y329875D01*
X888225Y329667D01*
X888017Y329417D01*
X887850Y329000D01*
X887808Y328625D01*
X887892Y328250D01*
X888017Y328000D01*
X888267Y327750D01*
X888558Y327583D01*
X888850Y327500D01*
X889142D01*
X889433Y327583D01*
X889683Y327708D01*
X889892Y327875D01*
G01X891033Y328000D02*
X891283Y327708D01*
X891617Y327542D01*
X891992Y327500D01*
X892325Y327542D01*
X892658Y327750D01*
X892867Y328000D01*
X892908Y328250D01*
X892825Y328542D01*
X892533Y328750D01*
X892242Y328833D01*
X891867D01*
G01X892242D02*
X892492Y328958D01*
X892700Y329167D01*
X892783Y329417D01*
X892700Y329667D01*
X892492Y329875D01*
X892117Y330000D01*
X891742Y329958D01*
X891367Y329792D01*
G01X895050Y327500D02*
Y330000D01*
X894550Y329500D01*
G01Y327500D02*
X895550D01*
G01X898150D02*
Y330000D01*
X897650Y329500D01*
G01Y327500D02*
X898650D01*
G01X876800Y340500D02*
Y336500D01*
X884200D01*
G01X888487Y341255D02*
X888695Y341588D01*
X888820Y341963D01*
Y342297D01*
X888695Y342630D01*
X888487Y342880D01*
X888195Y343005D01*
X887903Y342922D01*
X887653Y342713D01*
X887487Y342338D01*
X887403Y341838D01*
X887237Y341547D01*
X886945Y341422D01*
X886653Y341505D01*
X886445Y341713D01*
X886320Y342005D01*
Y342297D01*
X886403Y342588D01*
X886612Y342838D01*
G01X886528Y346147D02*
X886403Y345897D01*
X886320Y345605D01*
Y345272D01*
X886445Y344897D01*
X886653Y344605D01*
X886903Y344397D01*
X887320Y344230D01*
X887695Y344188D01*
X888070Y344272D01*
X888320Y344397D01*
X888570Y344647D01*
X888737Y344938D01*
X888820Y345230D01*
Y345522D01*
X888737Y345813D01*
X888612Y346063D01*
X888445Y346272D01*
G01X888820Y348330D02*
X886320D01*
X886820Y347830D01*
G01X888820D02*
Y348830D01*
G01X886737Y350638D02*
X886487Y350888D01*
X886362Y351180D01*
X886320Y351513D01*
X886403Y351930D01*
X886612Y352222D01*
X886862Y352305D01*
X887112Y352263D01*
X887320Y352097D01*
X887737Y351263D01*
X888028Y350888D01*
X888445Y350638D01*
X888820Y350555D01*
Y352305D01*
G01X888528Y353822D02*
X888737Y354113D01*
X888820Y354447D01*
X888737Y354780D01*
X888487Y355072D01*
X888112Y355280D01*
X887737Y355363D01*
X887278D01*
X886903Y355280D01*
X886570Y355072D01*
X886403Y354822D01*
X886320Y354530D01*
X886403Y354197D01*
X886570Y353947D01*
X886820Y353780D01*
X887153Y353697D01*
X887445Y353780D01*
X887737Y353988D01*
X887903Y354238D01*
X887945Y354530D01*
X887862Y354863D01*
X887653Y355113D01*
X887278Y355363D01*
G01X888820Y357547D02*
X888278Y357630D01*
X887820Y357755D01*
X887403Y357922D01*
X886945Y358130D01*
X886320Y358463D01*
Y356797D01*
G01X874500Y355433D02*
X876292D01*
X876667Y355600D01*
X876917Y355933D01*
X877000Y356350D01*
X876917Y356767D01*
X876667Y357100D01*
X876292Y357267D01*
X874500D01*
G01X877000Y359450D02*
X874500D01*
X875000Y358950D01*
G01X877000D02*
Y359950D01*
G01Y362550D02*
X876958Y362842D01*
X876833Y363175D01*
X876625Y363383D01*
X876333Y363467D01*
X876042Y363383D01*
X875792Y363133D01*
X875667Y362758D01*
Y362342D01*
X875583Y362092D01*
X875375Y361883D01*
X875083Y361800D01*
X874792Y361925D01*
X874583Y362217D01*
X874500Y362550D01*
X874583Y362883D01*
X874792Y363175D01*
X875083Y363300D01*
X875375Y363217D01*
X875583Y363008D01*
X875667Y362758D01*
Y362342D01*
X875792Y361967D01*
X876042Y361717D01*
X876333Y361633D01*
X876625Y361717D01*
X876833Y361925D01*
X876958Y362258D01*
X877000Y362550D01*
G01Y366150D02*
X874500D01*
X876292Y364608D01*
Y366692D01*
G01X879467Y414000D02*
Y416500D01*
X880467D01*
X880800Y416375D01*
X881050Y416083D01*
X881133Y415750D01*
X881050Y415417D01*
X880842Y415167D01*
X880467Y415042D01*
X879467D01*
G01X882567Y414000D02*
Y416500D01*
X883608D01*
X883942Y416375D01*
X884150Y416208D01*
X884233Y415875D01*
X884150Y415542D01*
X883900Y415333D01*
X883608Y415208D01*
X882567D01*
G01X883608D02*
X884233Y414000D01*
G01X886500D02*
Y416500D01*
X886000Y416000D01*
G01Y414000D02*
X887000D01*
G01X888808Y416083D02*
X889058Y416333D01*
X889350Y416458D01*
X889683Y416500D01*
X890100Y416417D01*
X890392Y416208D01*
X890475Y415958D01*
X890433Y415708D01*
X890267Y415500D01*
X889433Y415083D01*
X889058Y414792D01*
X888808Y414375D01*
X888725Y414000D01*
X890475D01*
G01X893200D02*
Y416500D01*
X891658Y414708D01*
X893742D01*
G01X879467Y404500D02*
Y407000D01*
X880467D01*
X880800Y406875D01*
X881050Y406583D01*
X881133Y406250D01*
X881050Y405917D01*
X880842Y405667D01*
X880467Y405542D01*
X879467D01*
G01X882567Y404500D02*
Y407000D01*
X883608D01*
X883942Y406875D01*
X884150Y406708D01*
X884233Y406375D01*
X884150Y406042D01*
X883900Y405833D01*
X883608Y405708D01*
X882567D01*
G01X883608D02*
X884233Y404500D01*
G01X886500D02*
Y407000D01*
X886000Y406500D01*
G01Y404500D02*
X887000D01*
G01X888808Y406583D02*
X889058Y406833D01*
X889350Y406958D01*
X889683Y407000D01*
X890100Y406917D01*
X890392Y406708D01*
X890475Y406458D01*
X890433Y406208D01*
X890267Y406000D01*
X889433Y405583D01*
X889058Y405292D01*
X888808Y404875D01*
X888725Y404500D01*
X890475D01*
G01X891783Y404875D02*
X892033Y404667D01*
X892325Y404542D01*
X892700Y404500D01*
X893075Y404583D01*
X893367Y404750D01*
X893575Y405042D01*
X893617Y405375D01*
X893533Y405708D01*
X893325Y405917D01*
X893033Y406083D01*
X892742Y406125D01*
X892450Y406083D01*
X892075Y405917D01*
X892200Y407000D01*
X893325D01*
G01X879467Y409500D02*
Y412000D01*
X880467D01*
X880800Y411875D01*
X881050Y411583D01*
X881133Y411250D01*
X881050Y410917D01*
X880842Y410667D01*
X880467Y410542D01*
X879467D01*
G01X884317Y411792D02*
X884067Y411917D01*
X883775Y412000D01*
X883442D01*
X883067Y411875D01*
X882775Y411667D01*
X882567Y411417D01*
X882400Y411000D01*
X882358Y410625D01*
X882442Y410250D01*
X882567Y410000D01*
X882817Y409750D01*
X883108Y409583D01*
X883400Y409500D01*
X883692D01*
X883983Y409583D01*
X884233Y409708D01*
X884442Y409875D01*
G01X886500Y409500D02*
Y412000D01*
X886000Y411500D01*
G01Y409500D02*
X887000D01*
G01X890100D02*
Y412000D01*
X888558Y410208D01*
X890642D01*
G01X892700Y409500D02*
X892992Y409542D01*
X893325Y409667D01*
X893533Y409875D01*
X893617Y410167D01*
X893533Y410458D01*
X893283Y410708D01*
X892908Y410833D01*
X892492D01*
X892242Y410917D01*
X892033Y411125D01*
X891950Y411417D01*
X892075Y411708D01*
X892367Y411917D01*
X892700Y412000D01*
X893033Y411917D01*
X893325Y411708D01*
X893450Y411417D01*
X893367Y411125D01*
X893158Y410917D01*
X892908Y410833D01*
X892492D01*
X892117Y410708D01*
X891867Y410458D01*
X891783Y410167D01*
X891867Y409875D01*
X892075Y409667D01*
X892408Y409542D01*
X892700Y409500D01*
G01X886500Y437017D02*
X884000D01*
Y438058D01*
X884125Y438392D01*
X884292Y438600D01*
X884625Y438683D01*
X884958Y438600D01*
X885167Y438350D01*
X885292Y438058D01*
Y437017D01*
G01Y438058D02*
X886500Y438683D01*
G01X885458Y440158D02*
X885167Y440450D01*
X885000Y440700D01*
X884917Y441033D01*
X885000Y441325D01*
X885167Y441533D01*
X885417Y441700D01*
X885708Y441742D01*
X885958Y441700D01*
X886208Y441533D01*
X886417Y441283D01*
X886500Y440992D01*
X886417Y440658D01*
X886167Y440367D01*
X885792Y440200D01*
X885375Y440158D01*
X884833Y440242D01*
X884542Y440367D01*
X884250Y440575D01*
X884042Y440867D01*
X884000Y441158D01*
X884083Y441450D01*
X884292Y441658D01*
G01X884000Y444050D02*
X884083Y443717D01*
X884292Y443467D01*
X884542Y443300D01*
X884875Y443175D01*
X885250Y443133D01*
X885625Y443175D01*
X885958Y443300D01*
X886208Y443467D01*
X886417Y443717D01*
X886500Y444050D01*
X886417Y444383D01*
X886208Y444633D01*
X885958Y444800D01*
X885625Y444925D01*
X885250Y444967D01*
X884875Y444925D01*
X884542Y444800D01*
X884292Y444633D01*
X884083Y444383D01*
X884000Y444050D01*
G01X886125Y446233D02*
X886333Y446483D01*
X886458Y446775D01*
X886500Y447150D01*
X886417Y447525D01*
X886250Y447817D01*
X885958Y448025D01*
X885625Y448067D01*
X885292Y447983D01*
X885083Y447775D01*
X884917Y447483D01*
X884875Y447192D01*
X884917Y446900D01*
X885083Y446525D01*
X884000Y446650D01*
Y447775D01*
G01X873000Y438800D02*
X877000D01*
Y446200D01*
G01X877500Y438800D02*
X881500D01*
Y446200D01*
G01X881000Y451000D02*
Y465000D01*
G01X879200Y465500D02*
Y469500D01*
X871800D01*
G01X873900Y473200D02*
Y480800D01*
G01X874967Y483000D02*
Y485500D01*
X875967D01*
X876300Y485375D01*
X876550Y485083D01*
X876633Y484750D01*
X876550Y484417D01*
X876342Y484167D01*
X875967Y484042D01*
X874967D01*
G01X878067Y483000D02*
Y485500D01*
X879108D01*
X879442Y485375D01*
X879650Y485208D01*
X879733Y484875D01*
X879650Y484542D01*
X879400Y484333D01*
X879108Y484208D01*
X878067D01*
G01X879108D02*
X879733Y483000D01*
G01X882000D02*
Y485500D01*
X881500Y485000D01*
G01Y483000D02*
X882500D01*
G01X885017D02*
X885100Y483542D01*
X885225Y484000D01*
X885392Y484417D01*
X885600Y484875D01*
X885933Y485500D01*
X884267D01*
G01X888200Y483000D02*
X888492Y483042D01*
X888825Y483167D01*
X889033Y483375D01*
X889117Y483667D01*
X889033Y483958D01*
X888783Y484208D01*
X888408Y484333D01*
X887992D01*
X887742Y484417D01*
X887533Y484625D01*
X887450Y484917D01*
X887575Y485208D01*
X887867Y485417D01*
X888200Y485500D01*
X888533Y485417D01*
X888825Y485208D01*
X888950Y484917D01*
X888867Y484625D01*
X888658Y484417D01*
X888408Y484333D01*
X887992D01*
X887617Y484208D01*
X887367Y483958D01*
X887283Y483667D01*
X887367Y483375D01*
X887575Y483167D01*
X887908Y483042D01*
X888200Y483000D01*
G01X878500Y473300D02*
X882500D01*
Y480700D01*
G01X881000Y487017D02*
X878500D01*
Y488058D01*
X878625Y488392D01*
X878792Y488600D01*
X879125Y488683D01*
X879458Y488600D01*
X879667Y488350D01*
X879792Y488058D01*
Y487017D01*
G01Y488058D02*
X881000Y488683D01*
G01X879958Y490158D02*
X879667Y490450D01*
X879500Y490700D01*
X879417Y491033D01*
X879500Y491325D01*
X879667Y491533D01*
X879917Y491700D01*
X880208Y491742D01*
X880458Y491700D01*
X880708Y491533D01*
X880917Y491283D01*
X881000Y490992D01*
X880917Y490658D01*
X880667Y490367D01*
X880292Y490200D01*
X879875Y490158D01*
X879333Y490242D01*
X879042Y490367D01*
X878750Y490575D01*
X878542Y490867D01*
X878500Y491158D01*
X878583Y491450D01*
X878792Y491658D01*
G01X878500Y494050D02*
X878583Y493717D01*
X878792Y493467D01*
X879042Y493300D01*
X879375Y493175D01*
X879750Y493133D01*
X880125Y493175D01*
X880458Y493300D01*
X880708Y493467D01*
X880917Y493717D01*
X881000Y494050D01*
X880917Y494383D01*
X880708Y494633D01*
X880458Y494800D01*
X880125Y494925D01*
X879750Y494967D01*
X879375Y494925D01*
X879042Y494800D01*
X878792Y494633D01*
X878583Y494383D01*
X878500Y494050D01*
G01X879958Y496358D02*
X879667Y496650D01*
X879500Y496900D01*
X879417Y497233D01*
X879500Y497525D01*
X879667Y497733D01*
X879917Y497900D01*
X880208Y497942D01*
X880458Y497900D01*
X880708Y497733D01*
X880917Y497483D01*
X881000Y497192D01*
X880917Y496858D01*
X880667Y496567D01*
X880292Y496400D01*
X879875Y496358D01*
X879333Y496442D01*
X879042Y496567D01*
X878750Y496775D01*
X878542Y497067D01*
X878500Y497358D01*
X878583Y497650D01*
X878792Y497858D01*
G01X875000Y605700D02*
X874667Y605742D01*
X874375Y605908D01*
X874125Y606158D01*
X873958Y606450D01*
X873875Y606783D01*
Y607117D01*
X873958Y607450D01*
X874125Y607742D01*
X874375Y607992D01*
X874667Y608158D01*
X875000Y608200D01*
X875333Y608158D01*
X875625Y607992D01*
X875875Y607742D01*
X876042Y607450D01*
X876125Y607117D01*
Y606783D01*
X876042Y606450D01*
X875875Y606158D01*
X875625Y605908D01*
X875333Y605742D01*
X875000Y605700D01*
G01X875333Y606367D02*
X875833Y605700D01*
G01X878100D02*
Y608200D01*
X877600Y607700D01*
G01Y605700D02*
X878600D01*
G01X881117D02*
X881200Y606242D01*
X881325Y606700D01*
X881492Y607117D01*
X881700Y607575D01*
X882033Y608200D01*
X880367D01*
G01X883500Y612222D02*
Y626222D01*
G01X886817Y637792D02*
X886567Y637917D01*
X886275Y638000D01*
X885942D01*
X885567Y637875D01*
X885275Y637667D01*
X885067Y637417D01*
X884900Y637000D01*
X884858Y636625D01*
X884942Y636250D01*
X885067Y636000D01*
X885317Y635750D01*
X885608Y635583D01*
X885900Y635500D01*
X886192D01*
X886483Y635583D01*
X886733Y635708D01*
X886942Y635875D01*
G01X889000Y635500D02*
X889292Y635542D01*
X889625Y635667D01*
X889833Y635875D01*
X889917Y636167D01*
X889833Y636458D01*
X889583Y636708D01*
X889208Y636833D01*
X888792D01*
X888542Y636917D01*
X888333Y637125D01*
X888250Y637417D01*
X888375Y637708D01*
X888667Y637917D01*
X889000Y638000D01*
X889333Y637917D01*
X889625Y637708D01*
X889750Y637417D01*
X889667Y637125D01*
X889458Y636917D01*
X889208Y636833D01*
X888792D01*
X888417Y636708D01*
X888167Y636458D01*
X888083Y636167D01*
X888167Y635875D01*
X888375Y635667D01*
X888708Y635542D01*
X889000Y635500D01*
G01X892100D02*
X892392Y635542D01*
X892725Y635667D01*
X892933Y635875D01*
X893017Y636167D01*
X892933Y636458D01*
X892683Y636708D01*
X892308Y636833D01*
X891892D01*
X891642Y636917D01*
X891433Y637125D01*
X891350Y637417D01*
X891475Y637708D01*
X891767Y637917D01*
X892100Y638000D01*
X892433Y637917D01*
X892725Y637708D01*
X892850Y637417D01*
X892767Y637125D01*
X892558Y636917D01*
X892308Y636833D01*
X891892D01*
X891517Y636708D01*
X891267Y636458D01*
X891183Y636167D01*
X891267Y635875D01*
X891475Y635667D01*
X891808Y635542D01*
X892100Y635500D01*
G01X879017Y678500D02*
Y681000D01*
X880058D01*
X880392Y680875D01*
X880600Y680708D01*
X880683Y680375D01*
X880600Y680042D01*
X880350Y679833D01*
X880058Y679708D01*
X879017D01*
G01X880058D02*
X880683Y678500D01*
G01X883450D02*
Y681000D01*
X881908Y679208D01*
X883992D01*
G01X885342Y678792D02*
X885633Y678583D01*
X885967Y678500D01*
X886300Y678583D01*
X886592Y678833D01*
X886800Y679208D01*
X886883Y679583D01*
Y680042D01*
X886800Y680417D01*
X886592Y680750D01*
X886342Y680917D01*
X886050Y681000D01*
X885717Y680917D01*
X885467Y680750D01*
X885300Y680500D01*
X885217Y680167D01*
X885300Y679875D01*
X885508Y679583D01*
X885758Y679417D01*
X886050Y679375D01*
X886383Y679458D01*
X886633Y679667D01*
X886883Y680042D01*
G01X888358Y679542D02*
X888650Y679833D01*
X888900Y680000D01*
X889233Y680083D01*
X889525Y680000D01*
X889733Y679833D01*
X889900Y679583D01*
X889942Y679292D01*
X889900Y679042D01*
X889733Y678792D01*
X889483Y678583D01*
X889192Y678500D01*
X888858Y678583D01*
X888567Y678833D01*
X888400Y679208D01*
X888358Y679625D01*
X888442Y680167D01*
X888567Y680458D01*
X888775Y680750D01*
X889067Y680958D01*
X889358Y681000D01*
X889650Y680917D01*
X889858Y680708D01*
G01X883500Y688400D02*
X883458Y688067D01*
X883292Y687775D01*
X883042Y687525D01*
X882750Y687358D01*
X882417Y687275D01*
X882083D01*
X881750Y687358D01*
X881458Y687525D01*
X881208Y687775D01*
X881042Y688067D01*
X881000Y688400D01*
X881042Y688733D01*
X881208Y689025D01*
X881458Y689275D01*
X881750Y689442D01*
X882083Y689525D01*
X882417D01*
X882750Y689442D01*
X883042Y689275D01*
X883292Y689025D01*
X883458Y688733D01*
X883500Y688400D01*
G01X882833Y688733D02*
X883500Y689233D01*
G01Y691500D02*
X881000D01*
X881500Y691000D01*
G01X883500D02*
Y692000D01*
G01Y694600D02*
X883458Y694892D01*
X883333Y695225D01*
X883125Y695433D01*
X882833Y695517D01*
X882542Y695433D01*
X882292Y695183D01*
X882167Y694808D01*
Y694392D01*
X882083Y694142D01*
X881875Y693933D01*
X881583Y693850D01*
X881292Y693975D01*
X881083Y694267D01*
X881000Y694600D01*
X881083Y694933D01*
X881292Y695225D01*
X881583Y695350D01*
X881875Y695267D01*
X882083Y695058D01*
X882167Y694808D01*
Y694392D01*
X882292Y694017D01*
X882542Y693767D01*
X882833Y693683D01*
X883125Y693767D01*
X883333Y693975D01*
X883458Y694308D01*
X883500Y694600D01*
G01X877196Y684711D02*
Y698111D01*
G01X887017Y713000D02*
Y715500D01*
X888058D01*
X888392Y715375D01*
X888600Y715208D01*
X888683Y714875D01*
X888600Y714542D01*
X888350Y714333D01*
X888058Y714208D01*
X887017D01*
G01X888058D02*
X888683Y713000D01*
G01X891450D02*
Y715500D01*
X889908Y713708D01*
X891992D01*
G01X893342Y713292D02*
X893633Y713083D01*
X893967Y713000D01*
X894300Y713083D01*
X894592Y713333D01*
X894800Y713708D01*
X894883Y714083D01*
Y714542D01*
X894800Y714917D01*
X894592Y715250D01*
X894342Y715417D01*
X894050Y715500D01*
X893717Y715417D01*
X893467Y715250D01*
X893300Y715000D01*
X893217Y714667D01*
X893300Y714375D01*
X893508Y714083D01*
X893758Y713917D01*
X894050Y713875D01*
X894383Y713958D01*
X894633Y714167D01*
X894883Y714542D01*
G01X897067Y713000D02*
X897150Y713542D01*
X897275Y714000D01*
X897442Y714417D01*
X897650Y714875D01*
X897983Y715500D01*
X896317D01*
G01X884468Y704301D02*
X881968D01*
Y705342D01*
X882093Y705676D01*
X882260Y705884D01*
X882593Y705967D01*
X882926Y705884D01*
X883135Y705634D01*
X883260Y705342D01*
Y704301D01*
G01Y705342D02*
X884468Y705967D01*
G01Y708734D02*
X881968D01*
X883760Y707192D01*
Y709276D01*
G01X884176Y710626D02*
X884385Y710917D01*
X884468Y711251D01*
X884385Y711584D01*
X884135Y711876D01*
X883760Y712084D01*
X883385Y712167D01*
X882926D01*
X882551Y712084D01*
X882218Y711876D01*
X882051Y711626D01*
X881968Y711334D01*
X882051Y711001D01*
X882218Y710751D01*
X882468Y710584D01*
X882801Y710501D01*
X883093Y710584D01*
X883385Y710792D01*
X883551Y711042D01*
X883593Y711334D01*
X883510Y711667D01*
X883301Y711917D01*
X882926Y712167D01*
G01X883968Y713517D02*
X884260Y713767D01*
X884426Y714101D01*
X884468Y714476D01*
X884426Y714809D01*
X884218Y715142D01*
X883968Y715351D01*
X883718Y715392D01*
X883426Y715309D01*
X883218Y715017D01*
X883135Y714726D01*
Y714351D01*
G01Y714726D02*
X883010Y714976D01*
X882801Y715184D01*
X882551Y715267D01*
X882301Y715184D01*
X882093Y714976D01*
X881968Y714601D01*
X882010Y714226D01*
X882176Y713851D01*
G01X888468Y699301D02*
X885968D01*
Y700342D01*
X886093Y700676D01*
X886260Y700884D01*
X886593Y700967D01*
X886926Y700884D01*
X887135Y700634D01*
X887260Y700342D01*
Y699301D01*
G01Y700342D02*
X888468Y700967D01*
G01Y703734D02*
X885968D01*
X887760Y702192D01*
Y704276D01*
G01X888176Y705626D02*
X888385Y705917D01*
X888468Y706251D01*
X888385Y706584D01*
X888135Y706876D01*
X887760Y707084D01*
X887385Y707167D01*
X886926D01*
X886551Y707084D01*
X886218Y706876D01*
X886051Y706626D01*
X885968Y706334D01*
X886051Y706001D01*
X886218Y705751D01*
X886468Y705584D01*
X886801Y705501D01*
X887093Y705584D01*
X887385Y705792D01*
X887551Y706042D01*
X887593Y706334D01*
X887510Y706667D01*
X887301Y706917D01*
X886926Y707167D01*
G01X888176Y708726D02*
X888385Y709017D01*
X888468Y709351D01*
X888385Y709684D01*
X888135Y709976D01*
X887760Y710184D01*
X887385Y710267D01*
X886926D01*
X886551Y710184D01*
X886218Y709976D01*
X886051Y709726D01*
X885968Y709434D01*
X886051Y709101D01*
X886218Y708851D01*
X886468Y708684D01*
X886801Y708601D01*
X887093Y708684D01*
X887385Y708892D01*
X887551Y709142D01*
X887593Y709434D01*
X887510Y709767D01*
X887301Y710017D01*
X886926Y710267D01*
G01X878700Y728500D02*
X876600Y730300D01*
X878700Y732500D01*
G01X896500Y50000D02*
Y63000D01*
G01X903000Y50000D02*
X916000D01*
G01X903000Y64000D02*
Y50000D01*
G01X901500Y77000D02*
Y64000D01*
G01X916000D02*
X903000D01*
G01X901500Y91000D02*
Y78000D01*
G01X891000Y437017D02*
X888500D01*
Y438058D01*
X888625Y438392D01*
X888792Y438600D01*
X889125Y438683D01*
X889458Y438600D01*
X889667Y438350D01*
X889792Y438058D01*
Y437017D01*
G01Y438058D02*
X891000Y438683D01*
G01X889958Y440158D02*
X889667Y440450D01*
X889500Y440700D01*
X889417Y441033D01*
X889500Y441325D01*
X889667Y441533D01*
X889917Y441700D01*
X890208Y441742D01*
X890458Y441700D01*
X890708Y441533D01*
X890917Y441283D01*
X891000Y440992D01*
X890917Y440658D01*
X890667Y440367D01*
X890292Y440200D01*
X889875Y440158D01*
X889333Y440242D01*
X889042Y440367D01*
X888750Y440575D01*
X888542Y440867D01*
X888500Y441158D01*
X888583Y441450D01*
X888792Y441658D01*
G01X888500Y444050D02*
X888583Y443717D01*
X888792Y443467D01*
X889042Y443300D01*
X889375Y443175D01*
X889750Y443133D01*
X890125Y443175D01*
X890458Y443300D01*
X890708Y443467D01*
X890917Y443717D01*
X891000Y444050D01*
X890917Y444383D01*
X890708Y444633D01*
X890458Y444800D01*
X890125Y444925D01*
X889750Y444967D01*
X889375Y444925D01*
X889042Y444800D01*
X888792Y444633D01*
X888583Y444383D01*
X888500Y444050D01*
G01X890500Y446233D02*
X890792Y446483D01*
X890958Y446817D01*
X891000Y447192D01*
X890958Y447525D01*
X890750Y447858D01*
X890500Y448067D01*
X890250Y448108D01*
X889958Y448025D01*
X889750Y447733D01*
X889667Y447442D01*
Y447067D01*
G01Y447442D02*
X889542Y447692D01*
X889333Y447900D01*
X889083Y447983D01*
X888833Y447900D01*
X888625Y447692D01*
X888500Y447317D01*
X888542Y446942D01*
X888708Y446567D01*
G01X892468Y699301D02*
X889968D01*
Y700342D01*
X890093Y700676D01*
X890260Y700884D01*
X890593Y700967D01*
X890926Y700884D01*
X891135Y700634D01*
X891260Y700342D01*
Y699301D01*
G01Y700342D02*
X892468Y700967D01*
G01Y703734D02*
X889968D01*
X891760Y702192D01*
Y704276D01*
G01X892176Y705626D02*
X892385Y705917D01*
X892468Y706251D01*
X892385Y706584D01*
X892135Y706876D01*
X891760Y707084D01*
X891385Y707167D01*
X890926D01*
X890551Y707084D01*
X890218Y706876D01*
X890051Y706626D01*
X889968Y706334D01*
X890051Y706001D01*
X890218Y705751D01*
X890468Y705584D01*
X890801Y705501D01*
X891093Y705584D01*
X891385Y705792D01*
X891551Y706042D01*
X891593Y706334D01*
X891510Y706667D01*
X891301Y706917D01*
X890926Y707167D01*
G01X892468Y709434D02*
X892426Y709726D01*
X892301Y710059D01*
X892093Y710267D01*
X891801Y710351D01*
X891510Y710267D01*
X891260Y710017D01*
X891135Y709642D01*
Y709226D01*
X891051Y708976D01*
X890843Y708767D01*
X890551Y708684D01*
X890260Y708809D01*
X890051Y709101D01*
X889968Y709434D01*
X890051Y709767D01*
X890260Y710059D01*
X890551Y710184D01*
X890843Y710101D01*
X891051Y709892D01*
X891135Y709642D01*
Y709226D01*
X891260Y708851D01*
X891510Y708601D01*
X891801Y708517D01*
X892093Y708601D01*
X892301Y708809D01*
X892426Y709142D01*
X892468Y709434D01*
G01X920500Y36017D02*
X918000D01*
Y37058D01*
X918125Y37392D01*
X918292Y37600D01*
X918625Y37683D01*
X918958Y37600D01*
X919167Y37350D01*
X919292Y37058D01*
Y36017D01*
G01Y37058D02*
X920500Y37683D01*
G01X920125Y39033D02*
X920333Y39283D01*
X920458Y39575D01*
X920500Y39950D01*
X920417Y40325D01*
X920250Y40617D01*
X919958Y40825D01*
X919625Y40867D01*
X919292Y40783D01*
X919083Y40575D01*
X918917Y40283D01*
X918875Y39992D01*
X918917Y39700D01*
X919083Y39325D01*
X918000Y39450D01*
Y40575D01*
G01X920500Y43550D02*
X918000D01*
X919792Y42008D01*
Y44092D01*
G01X920500Y46650D02*
X918000D01*
X919792Y45108D01*
Y47192D01*
G01X911000Y42450D02*
X910958Y42117D01*
X910792Y41825D01*
X910542Y41575D01*
X910250Y41408D01*
X909917Y41325D01*
X909583D01*
X909250Y41408D01*
X908958Y41575D01*
X908708Y41825D01*
X908542Y42117D01*
X908500Y42450D01*
X908542Y42783D01*
X908708Y43075D01*
X908958Y43325D01*
X909250Y43492D01*
X909583Y43575D01*
X909917D01*
X910250Y43492D01*
X910542Y43325D01*
X910792Y43075D01*
X910958Y42783D01*
X911000Y42450D01*
G01X910333Y42783D02*
X911000Y43283D01*
G01X910708Y44842D02*
X910917Y45133D01*
X911000Y45467D01*
X910917Y45800D01*
X910667Y46092D01*
X910292Y46300D01*
X909917Y46383D01*
X909458D01*
X909083Y46300D01*
X908750Y46092D01*
X908583Y45842D01*
X908500Y45550D01*
X908583Y45217D01*
X908750Y44967D01*
X909000Y44800D01*
X909333Y44717D01*
X909625Y44800D01*
X909917Y45008D01*
X910083Y45258D01*
X910125Y45550D01*
X910042Y45883D01*
X909833Y46133D01*
X909458Y46383D01*
G01X916000Y50000D02*
Y64000D01*
G01X921000Y57200D02*
X917000D01*
Y49800D01*
G01X922700Y68500D02*
Y72500D01*
X915300D01*
G01X914200Y68500D02*
Y72500D01*
X906800D01*
G01X908425Y86833D02*
X908758Y86625D01*
X909133Y86500D01*
X909467D01*
X909800Y86625D01*
X910050Y86833D01*
X910175Y87125D01*
X910092Y87417D01*
X909883Y87667D01*
X909508Y87833D01*
X909008Y87917D01*
X908717Y88083D01*
X908592Y88375D01*
X908675Y88667D01*
X908883Y88875D01*
X909175Y89000D01*
X909467D01*
X909758Y88917D01*
X910008Y88708D01*
G01X911567Y86500D02*
Y89000D01*
X912608D01*
X912942Y88875D01*
X913150Y88708D01*
X913233Y88375D01*
X913150Y88042D01*
X912900Y87833D01*
X912608Y87708D01*
X911567D01*
G01X912608D02*
X913233Y86500D01*
G01X915500D02*
X915792Y86542D01*
X916125Y86667D01*
X916333Y86875D01*
X916417Y87167D01*
X916333Y87458D01*
X916083Y87708D01*
X915708Y87833D01*
X915292D01*
X915042Y87917D01*
X914833Y88125D01*
X914750Y88417D01*
X914875Y88708D01*
X915167Y88917D01*
X915500Y89000D01*
X915833Y88917D01*
X916125Y88708D01*
X916250Y88417D01*
X916167Y88125D01*
X915958Y87917D01*
X915708Y87833D01*
X915292D01*
X914917Y87708D01*
X914667Y87458D01*
X914583Y87167D01*
X914667Y86875D01*
X914875Y86667D01*
X915208Y86542D01*
X915500Y86500D01*
G01X918600Y89000D02*
X918267Y88917D01*
X918017Y88708D01*
X917850Y88458D01*
X917725Y88125D01*
X917683Y87750D01*
X917725Y87375D01*
X917850Y87042D01*
X918017Y86792D01*
X918267Y86583D01*
X918600Y86500D01*
X918933Y86583D01*
X919183Y86792D01*
X919350Y87042D01*
X919475Y87375D01*
X919517Y87750D01*
X919475Y88125D01*
X919350Y88458D01*
X919183Y88708D01*
X918933Y88917D01*
X918600Y89000D01*
G01X921617Y86500D02*
X921700Y87042D01*
X921825Y87500D01*
X921992Y87917D01*
X922200Y88375D01*
X922533Y89000D01*
X920867D01*
G01X909517Y75500D02*
Y78000D01*
X910558D01*
X910892Y77875D01*
X911100Y77708D01*
X911183Y77375D01*
X911100Y77042D01*
X910850Y76833D01*
X910558Y76708D01*
X909517D01*
G01X910558D02*
X911183Y75500D01*
G01X912533Y75875D02*
X912783Y75667D01*
X913075Y75542D01*
X913450Y75500D01*
X913825Y75583D01*
X914117Y75750D01*
X914325Y76042D01*
X914367Y76375D01*
X914283Y76708D01*
X914075Y76917D01*
X913783Y77083D01*
X913492Y77125D01*
X913200Y77083D01*
X912825Y76917D01*
X912950Y78000D01*
X914075D01*
G01X915758Y77583D02*
X916008Y77833D01*
X916300Y77958D01*
X916633Y78000D01*
X917050Y77917D01*
X917342Y77708D01*
X917425Y77458D01*
X917383Y77208D01*
X917217Y77000D01*
X916383Y76583D01*
X916008Y76292D01*
X915758Y75875D01*
X915675Y75500D01*
X917425D01*
G01X918942Y75792D02*
X919233Y75583D01*
X919567Y75500D01*
X919900Y75583D01*
X920192Y75833D01*
X920400Y76208D01*
X920483Y76583D01*
Y77042D01*
X920400Y77417D01*
X920192Y77750D01*
X919942Y77917D01*
X919650Y78000D01*
X919317Y77917D01*
X919067Y77750D01*
X918900Y77500D01*
X918817Y77167D01*
X918900Y76875D01*
X919108Y76583D01*
X919358Y76417D01*
X919650Y76375D01*
X919983Y76458D01*
X920233Y76667D01*
X920483Y77042D01*
G01X908375Y81833D02*
X908708Y81625D01*
X909083Y81500D01*
X909417D01*
X909750Y81625D01*
X910000Y81833D01*
X910125Y82125D01*
X910042Y82417D01*
X909833Y82667D01*
X909458Y82833D01*
X908958Y82917D01*
X908667Y83083D01*
X908542Y83375D01*
X908625Y83667D01*
X908833Y83875D01*
X909125Y84000D01*
X909417D01*
X909708Y83917D01*
X909958Y83708D01*
G01X913267Y83792D02*
X913017Y83917D01*
X912725Y84000D01*
X912392D01*
X912017Y83875D01*
X911725Y83667D01*
X911517Y83417D01*
X911350Y83000D01*
X911308Y82625D01*
X911392Y82250D01*
X911517Y82000D01*
X911767Y81750D01*
X912058Y81583D01*
X912350Y81500D01*
X912642D01*
X912933Y81583D01*
X913183Y81708D01*
X913392Y81875D01*
G01X915450Y81500D02*
Y84000D01*
X914950Y83500D01*
G01Y81500D02*
X915950D01*
G01X918550D02*
Y84000D01*
X918050Y83500D01*
G01Y81500D02*
X919050D01*
G01X920858Y83583D02*
X921108Y83833D01*
X921400Y83958D01*
X921733Y84000D01*
X922150Y83917D01*
X922442Y83708D01*
X922525Y83458D01*
X922483Y83208D01*
X922317Y83000D01*
X921483Y82583D01*
X921108Y82292D01*
X920858Y81875D01*
X920775Y81500D01*
X922525D01*
G01X923833Y82000D02*
X924083Y81708D01*
X924417Y81542D01*
X924792Y81500D01*
X925125Y81542D01*
X925458Y81750D01*
X925667Y82000D01*
X925708Y82250D01*
X925625Y82542D01*
X925333Y82750D01*
X925042Y82833D01*
X924667D01*
G01X925042D02*
X925292Y82958D01*
X925500Y83167D01*
X925583Y83417D01*
X925500Y83667D01*
X925292Y83875D01*
X924917Y84000D01*
X924542Y83958D01*
X924167Y83792D01*
G01X922300Y54500D02*
Y64500D01*
G01X935700Y54500D02*
X922300D01*
G01X935700Y64500D02*
Y54500D01*
G01X927267Y48292D02*
X927017Y48417D01*
X926725Y48500D01*
X926392D01*
X926017Y48375D01*
X925725Y48167D01*
X925517Y47917D01*
X925350Y47500D01*
X925308Y47125D01*
X925392Y46750D01*
X925517Y46500D01*
X925767Y46250D01*
X926058Y46083D01*
X926350Y46000D01*
X926642D01*
X926933Y46083D01*
X927183Y46208D01*
X927392Y46375D01*
G01X928658Y48083D02*
X928908Y48333D01*
X929200Y48458D01*
X929533Y48500D01*
X929950Y48417D01*
X930242Y48208D01*
X930325Y47958D01*
X930283Y47708D01*
X930117Y47500D01*
X929283Y47083D01*
X928908Y46792D01*
X928658Y46375D01*
X928575Y46000D01*
X930325D01*
G01X931758Y47042D02*
X932050Y47333D01*
X932300Y47500D01*
X932633Y47583D01*
X932925Y47500D01*
X933133Y47333D01*
X933300Y47083D01*
X933342Y46792D01*
X933300Y46542D01*
X933133Y46292D01*
X932883Y46083D01*
X932592Y46000D01*
X932258Y46083D01*
X931967Y46333D01*
X931800Y46708D01*
X931758Y47125D01*
X931842Y47667D01*
X931967Y47958D01*
X932175Y48250D01*
X932467Y48458D01*
X932758Y48500D01*
X933050Y48417D01*
X933258Y48208D01*
G01X934942Y46292D02*
X935233Y46083D01*
X935567Y46000D01*
X935900Y46083D01*
X936192Y46333D01*
X936400Y46708D01*
X936483Y47083D01*
Y47542D01*
X936400Y47917D01*
X936192Y48250D01*
X935942Y48417D01*
X935650Y48500D01*
X935317Y48417D01*
X935067Y48250D01*
X934900Y48000D01*
X934817Y47667D01*
X934900Y47375D01*
X935108Y47083D01*
X935358Y46917D01*
X935650Y46875D01*
X935983Y46958D01*
X936233Y47167D01*
X936483Y47542D01*
G01X931983Y70500D02*
Y68708D01*
X932150Y68333D01*
X932483Y68083D01*
X932900Y68000D01*
X933317Y68083D01*
X933650Y68333D01*
X933817Y68708D01*
Y70500D01*
G01X935083Y68500D02*
X935333Y68208D01*
X935667Y68042D01*
X936042Y68000D01*
X936375Y68042D01*
X936708Y68250D01*
X936917Y68500D01*
X936958Y68750D01*
X936875Y69042D01*
X936583Y69250D01*
X936292Y69333D01*
X935917D01*
G01X936292D02*
X936542Y69458D01*
X936750Y69667D01*
X936833Y69917D01*
X936750Y70167D01*
X936542Y70375D01*
X936167Y70500D01*
X935792Y70458D01*
X935417Y70292D01*
G01X939100Y68000D02*
X939392Y68042D01*
X939725Y68167D01*
X939933Y68375D01*
X940017Y68667D01*
X939933Y68958D01*
X939683Y69208D01*
X939308Y69333D01*
X938892D01*
X938642Y69417D01*
X938433Y69625D01*
X938350Y69917D01*
X938475Y70208D01*
X938767Y70417D01*
X939100Y70500D01*
X939433Y70417D01*
X939725Y70208D01*
X939850Y69917D01*
X939767Y69625D01*
X939558Y69417D01*
X939308Y69333D01*
X938892D01*
X938517Y69208D01*
X938267Y68958D01*
X938183Y68667D01*
X938267Y68375D01*
X938475Y68167D01*
X938808Y68042D01*
X939100Y68000D01*
G01X922300Y64500D02*
X935700D01*
G01X922517Y75500D02*
Y78000D01*
X923558D01*
X923892Y77875D01*
X924100Y77708D01*
X924183Y77375D01*
X924100Y77042D01*
X923850Y76833D01*
X923558Y76708D01*
X922517D01*
G01X923558D02*
X924183Y75500D01*
G01X925533Y75875D02*
X925783Y75667D01*
X926075Y75542D01*
X926450Y75500D01*
X926825Y75583D01*
X927117Y75750D01*
X927325Y76042D01*
X927367Y76375D01*
X927283Y76708D01*
X927075Y76917D01*
X926783Y77083D01*
X926492Y77125D01*
X926200Y77083D01*
X925825Y76917D01*
X925950Y78000D01*
X927075D01*
G01X928633Y76000D02*
X928883Y75708D01*
X929217Y75542D01*
X929592Y75500D01*
X929925Y75542D01*
X930258Y75750D01*
X930467Y76000D01*
X930508Y76250D01*
X930425Y76542D01*
X930133Y76750D01*
X929842Y76833D01*
X929467D01*
G01X929842D02*
X930092Y76958D01*
X930300Y77167D01*
X930383Y77417D01*
X930300Y77667D01*
X930092Y77875D01*
X929717Y78000D01*
X929342Y77958D01*
X928967Y77792D01*
G01X931858Y77583D02*
X932108Y77833D01*
X932400Y77958D01*
X932733Y78000D01*
X933150Y77917D01*
X933442Y77708D01*
X933525Y77458D01*
X933483Y77208D01*
X933317Y77000D01*
X932483Y76583D01*
X932108Y76292D01*
X931858Y75875D01*
X931775Y75500D01*
X933525D01*
G01X954508Y394400D02*
X931108D01*
Y365600D01*
X982908D01*
Y394400D01*
G01X933750Y454700D02*
Y450700D01*
X941150D01*
G01X926825Y443033D02*
X927158Y442825D01*
X927533Y442700D01*
X927867D01*
X928200Y442825D01*
X928450Y443033D01*
X928575Y443325D01*
X928492Y443617D01*
X928283Y443867D01*
X927908Y444033D01*
X927408Y444117D01*
X927117Y444283D01*
X926992Y444575D01*
X927075Y444867D01*
X927283Y445075D01*
X927575Y445200D01*
X927867D01*
X928158Y445117D01*
X928408Y444908D01*
G01X931717Y444992D02*
X931467Y445117D01*
X931175Y445200D01*
X930842D01*
X930467Y445075D01*
X930175Y444867D01*
X929967Y444617D01*
X929800Y444200D01*
X929758Y443825D01*
X929842Y443450D01*
X929967Y443200D01*
X930217Y442950D01*
X930508Y442783D01*
X930800Y442700D01*
X931092D01*
X931383Y442783D01*
X931633Y442908D01*
X931842Y443075D01*
G01X933900Y442700D02*
Y445200D01*
X933400Y444700D01*
G01Y442700D02*
X934400D01*
G01X936208Y444783D02*
X936458Y445033D01*
X936750Y445158D01*
X937083Y445200D01*
X937500Y445117D01*
X937792Y444908D01*
X937875Y444658D01*
X937833Y444408D01*
X937667Y444200D01*
X936833Y443783D01*
X936458Y443492D01*
X936208Y443075D01*
X936125Y442700D01*
X937875D01*
G01X939392Y442992D02*
X939683Y442783D01*
X940017Y442700D01*
X940350Y442783D01*
X940642Y443033D01*
X940850Y443408D01*
X940933Y443783D01*
Y444242D01*
X940850Y444617D01*
X940642Y444950D01*
X940392Y445117D01*
X940100Y445200D01*
X939767Y445117D01*
X939517Y444950D01*
X939350Y444700D01*
X939267Y444367D01*
X939350Y444075D01*
X939558Y443783D01*
X939808Y443617D01*
X940100Y443575D01*
X940433Y443658D01*
X940683Y443867D01*
X940933Y444242D01*
G01X942492Y442992D02*
X942783Y442783D01*
X943117Y442700D01*
X943450Y442783D01*
X943742Y443033D01*
X943950Y443408D01*
X944033Y443783D01*
Y444242D01*
X943950Y444617D01*
X943742Y444950D01*
X943492Y445117D01*
X943200Y445200D01*
X942867Y445117D01*
X942617Y444950D01*
X942450Y444700D01*
X942367Y444367D01*
X942450Y444075D01*
X942658Y443783D01*
X942908Y443617D01*
X943200Y443575D01*
X943533Y443658D01*
X943783Y443867D01*
X944033Y444242D01*
G01X929375Y458033D02*
X929708Y457825D01*
X930083Y457700D01*
X930417D01*
X930750Y457825D01*
X931000Y458033D01*
X931125Y458325D01*
X931042Y458617D01*
X930833Y458867D01*
X930458Y459033D01*
X929958Y459117D01*
X929667Y459283D01*
X929542Y459575D01*
X929625Y459867D01*
X929833Y460075D01*
X930125Y460200D01*
X930417D01*
X930708Y460117D01*
X930958Y459908D01*
G01X932517Y457700D02*
Y460200D01*
X933558D01*
X933892Y460075D01*
X934100Y459908D01*
X934183Y459575D01*
X934100Y459242D01*
X933850Y459033D01*
X933558Y458908D01*
X932517D01*
G01X933558D02*
X934183Y457700D01*
G01X936450D02*
X936742Y457742D01*
X937075Y457867D01*
X937283Y458075D01*
X937367Y458367D01*
X937283Y458658D01*
X937033Y458908D01*
X936658Y459033D01*
X936242D01*
X935992Y459117D01*
X935783Y459325D01*
X935700Y459617D01*
X935825Y459908D01*
X936117Y460117D01*
X936450Y460200D01*
X936783Y460117D01*
X937075Y459908D01*
X937200Y459617D01*
X937117Y459325D01*
X936908Y459117D01*
X936658Y459033D01*
X936242D01*
X935867Y458908D01*
X935617Y458658D01*
X935533Y458367D01*
X935617Y458075D01*
X935825Y457867D01*
X936158Y457742D01*
X936450Y457700D01*
G01X940050D02*
Y460200D01*
X938508Y458408D01*
X940592D01*
G01X942650Y460200D02*
X942317Y460117D01*
X942067Y459908D01*
X941900Y459658D01*
X941775Y459325D01*
X941733Y458950D01*
X941775Y458575D01*
X941900Y458242D01*
X942067Y457992D01*
X942317Y457783D01*
X942650Y457700D01*
X942983Y457783D01*
X943233Y457992D01*
X943400Y458242D01*
X943525Y458575D01*
X943567Y458950D01*
X943525Y459325D01*
X943400Y459658D01*
X943233Y459908D01*
X942983Y460117D01*
X942650Y460200D01*
G01X951111Y50797D02*
Y53297D01*
X952152D01*
X952486Y53172D01*
X952694Y53005D01*
X952777Y52672D01*
X952694Y52339D01*
X952444Y52130D01*
X952152Y52005D01*
X951111D01*
G01X952152D02*
X952777Y50797D01*
G01X954127Y51297D02*
X954377Y51005D01*
X954711Y50839D01*
X955086Y50797D01*
X955419Y50839D01*
X955752Y51047D01*
X955961Y51297D01*
X956002Y51547D01*
X955919Y51839D01*
X955627Y52047D01*
X955336Y52130D01*
X954961D01*
G01X955336D02*
X955586Y52255D01*
X955794Y52464D01*
X955877Y52714D01*
X955794Y52964D01*
X955586Y53172D01*
X955211Y53297D01*
X954836Y53255D01*
X954461Y53089D01*
G01X958144Y53297D02*
X957811Y53214D01*
X957561Y53005D01*
X957394Y52755D01*
X957269Y52422D01*
X957227Y52047D01*
X957269Y51672D01*
X957394Y51339D01*
X957561Y51089D01*
X957811Y50880D01*
X958144Y50797D01*
X958477Y50880D01*
X958727Y51089D01*
X958894Y51339D01*
X959019Y51672D01*
X959061Y52047D01*
X959019Y52422D01*
X958894Y52755D01*
X958727Y53005D01*
X958477Y53214D01*
X958144Y53297D01*
G01X960327Y51172D02*
X960577Y50964D01*
X960869Y50839D01*
X961244Y50797D01*
X961619Y50880D01*
X961911Y51047D01*
X962119Y51339D01*
X962161Y51672D01*
X962077Y52005D01*
X961869Y52214D01*
X961577Y52380D01*
X961286Y52422D01*
X960994Y52380D01*
X960619Y52214D01*
X960744Y53297D01*
X961869D01*
G01X941394Y53797D02*
Y49797D01*
X948794D01*
G01X955500Y57517D02*
X953000D01*
Y58558D01*
X953125Y58892D01*
X953292Y59100D01*
X953625Y59183D01*
X953958Y59100D01*
X954167Y58850D01*
X954292Y58558D01*
Y57517D01*
G01Y58558D02*
X955500Y59183D01*
G01X954458Y60658D02*
X954167Y60950D01*
X954000Y61200D01*
X953917Y61533D01*
X954000Y61825D01*
X954167Y62033D01*
X954417Y62200D01*
X954708Y62242D01*
X954958Y62200D01*
X955208Y62033D01*
X955417Y61783D01*
X955500Y61492D01*
X955417Y61158D01*
X955167Y60867D01*
X954792Y60700D01*
X954375Y60658D01*
X953833Y60742D01*
X953542Y60867D01*
X953250Y61075D01*
X953042Y61367D01*
X953000Y61658D01*
X953083Y61950D01*
X953292Y62158D01*
G01X955500Y64550D02*
X955458Y64842D01*
X955333Y65175D01*
X955125Y65383D01*
X954833Y65467D01*
X954542Y65383D01*
X954292Y65133D01*
X954167Y64758D01*
Y64342D01*
X954083Y64092D01*
X953875Y63883D01*
X953583Y63800D01*
X953292Y63925D01*
X953083Y64217D01*
X953000Y64550D01*
X953083Y64883D01*
X953292Y65175D01*
X953583Y65300D01*
X953875Y65217D01*
X954083Y65008D01*
X954167Y64758D01*
Y64342D01*
X954292Y63967D01*
X954542Y63717D01*
X954833Y63633D01*
X955125Y63717D01*
X955333Y63925D01*
X955458Y64258D01*
X955500Y64550D01*
G01X955000Y66733D02*
X955292Y66983D01*
X955458Y67317D01*
X955500Y67692D01*
X955458Y68025D01*
X955250Y68358D01*
X955000Y68567D01*
X954750Y68608D01*
X954458Y68525D01*
X954250Y68233D01*
X954167Y67942D01*
Y67567D01*
G01Y67942D02*
X954042Y68192D01*
X953833Y68400D01*
X953583Y68483D01*
X953333Y68400D01*
X953125Y68192D01*
X953000Y67817D01*
X953042Y67442D01*
X953208Y67067D01*
G01X942800Y61500D02*
Y57500D01*
X950200D01*
G01X964050Y445750D02*
X946850D01*
Y455650D01*
X964050D01*
Y445750D01*
G01X951450Y436000D02*
X955450D01*
Y443400D01*
G01X943617Y461625D02*
X943825Y461958D01*
X943950Y462333D01*
Y462667D01*
X943825Y463000D01*
X943617Y463250D01*
X943325Y463375D01*
X943033Y463292D01*
X942783Y463083D01*
X942617Y462708D01*
X942533Y462208D01*
X942367Y461917D01*
X942075Y461792D01*
X941783Y461875D01*
X941575Y462083D01*
X941450Y462375D01*
Y462667D01*
X941533Y462958D01*
X941742Y463208D01*
G01X943950Y464767D02*
X941450D01*
Y465808D01*
X941575Y466142D01*
X941742Y466350D01*
X942075Y466433D01*
X942408Y466350D01*
X942617Y466100D01*
X942742Y465808D01*
Y464767D01*
G01Y465808D02*
X943950Y466433D01*
G01X943658Y467992D02*
X943867Y468283D01*
X943950Y468617D01*
X943867Y468950D01*
X943617Y469242D01*
X943242Y469450D01*
X942867Y469533D01*
X942408D01*
X942033Y469450D01*
X941700Y469242D01*
X941533Y468992D01*
X941450Y468700D01*
X941533Y468367D01*
X941700Y468117D01*
X941950Y467950D01*
X942283Y467867D01*
X942575Y467950D01*
X942867Y468158D01*
X943033Y468408D01*
X943075Y468700D01*
X942992Y469033D01*
X942783Y469283D01*
X942408Y469533D01*
G01X943450Y470883D02*
X943742Y471133D01*
X943908Y471467D01*
X943950Y471842D01*
X943908Y472175D01*
X943700Y472508D01*
X943450Y472717D01*
X943200Y472758D01*
X942908Y472675D01*
X942700Y472383D01*
X942617Y472092D01*
Y471717D01*
G01Y472092D02*
X942492Y472342D01*
X942283Y472550D01*
X942033Y472633D01*
X941783Y472550D01*
X941575Y472342D01*
X941450Y471967D01*
X941492Y471592D01*
X941658Y471217D01*
G01X943575Y473983D02*
X943783Y474233D01*
X943908Y474525D01*
X943950Y474900D01*
X943867Y475275D01*
X943700Y475567D01*
X943408Y475775D01*
X943075Y475817D01*
X942742Y475733D01*
X942533Y475525D01*
X942367Y475233D01*
X942325Y474942D01*
X942367Y474650D01*
X942533Y474275D01*
X941450Y474400D01*
Y475525D01*
G01X950450Y461500D02*
X954450D01*
Y468900D01*
G01X948617Y461625D02*
X948825Y461958D01*
X948950Y462333D01*
Y462667D01*
X948825Y463000D01*
X948617Y463250D01*
X948325Y463375D01*
X948033Y463292D01*
X947783Y463083D01*
X947617Y462708D01*
X947533Y462208D01*
X947367Y461917D01*
X947075Y461792D01*
X946783Y461875D01*
X946575Y462083D01*
X946450Y462375D01*
Y462667D01*
X946533Y462958D01*
X946742Y463208D01*
G01X948950Y464767D02*
X946450D01*
Y465808D01*
X946575Y466142D01*
X946742Y466350D01*
X947075Y466433D01*
X947408Y466350D01*
X947617Y466100D01*
X947742Y465808D01*
Y464767D01*
G01Y465808D02*
X948950Y466433D01*
G01X948658Y467992D02*
X948867Y468283D01*
X948950Y468617D01*
X948867Y468950D01*
X948617Y469242D01*
X948242Y469450D01*
X947867Y469533D01*
X947408D01*
X947033Y469450D01*
X946700Y469242D01*
X946533Y468992D01*
X946450Y468700D01*
X946533Y468367D01*
X946700Y468117D01*
X946950Y467950D01*
X947283Y467867D01*
X947575Y467950D01*
X947867Y468158D01*
X948033Y468408D01*
X948075Y468700D01*
X947992Y469033D01*
X947783Y469283D01*
X947408Y469533D01*
G01X948450Y470883D02*
X948742Y471133D01*
X948908Y471467D01*
X948950Y471842D01*
X948908Y472175D01*
X948700Y472508D01*
X948450Y472717D01*
X948200Y472758D01*
X947908Y472675D01*
X947700Y472383D01*
X947617Y472092D01*
Y471717D01*
G01Y472092D02*
X947492Y472342D01*
X947283Y472550D01*
X947033Y472633D01*
X946783Y472550D01*
X946575Y472342D01*
X946450Y471967D01*
X946492Y471592D01*
X946658Y471217D01*
G01X947908Y474108D02*
X947617Y474400D01*
X947450Y474650D01*
X947367Y474983D01*
X947450Y475275D01*
X947617Y475483D01*
X947867Y475650D01*
X948158Y475692D01*
X948408Y475650D01*
X948658Y475483D01*
X948867Y475233D01*
X948950Y474942D01*
X948867Y474608D01*
X948617Y474317D01*
X948242Y474150D01*
X947825Y474108D01*
X947283Y474192D01*
X946992Y474317D01*
X946700Y474525D01*
X946492Y474817D01*
X946450Y475108D01*
X946533Y475400D01*
X946742Y475608D01*
G01X965199Y208411D02*
X965532Y208203D01*
X965907Y208078D01*
X966241D01*
X966574Y208203D01*
X966824Y208411D01*
X966949Y208703D01*
X966866Y208995D01*
X966657Y209245D01*
X966282Y209411D01*
X965782Y209495D01*
X965491Y209661D01*
X965366Y209953D01*
X965449Y210245D01*
X965657Y210453D01*
X965949Y210578D01*
X966241D01*
X966532Y210495D01*
X966782Y210286D01*
G01X968341Y208078D02*
Y210578D01*
X969382D01*
X969716Y210453D01*
X969924Y210286D01*
X970007Y209953D01*
X969924Y209620D01*
X969674Y209411D01*
X969382Y209286D01*
X968341D01*
G01X969382D02*
X970007Y208078D01*
G01X972191D02*
X972274Y208620D01*
X972399Y209078D01*
X972566Y209495D01*
X972774Y209953D01*
X973107Y210578D01*
X971441D01*
G01X975374Y208078D02*
Y210578D01*
X974874Y210078D01*
G01Y208078D02*
X975874D01*
G01X978474D02*
X978766Y208120D01*
X979099Y208245D01*
X979307Y208453D01*
X979391Y208745D01*
X979307Y209036D01*
X979057Y209286D01*
X978682Y209411D01*
X978266D01*
X978016Y209495D01*
X977807Y209703D01*
X977724Y209995D01*
X977849Y210286D01*
X978141Y210495D01*
X978474Y210578D01*
X978807Y210495D01*
X979099Y210286D01*
X979224Y209995D01*
X979141Y209703D01*
X978932Y209495D01*
X978682Y209411D01*
X978266D01*
X977891Y209286D01*
X977641Y209036D01*
X977557Y208745D01*
X977641Y208453D01*
X977849Y208245D01*
X978182Y208120D01*
X978474Y208078D01*
G01X965199Y213411D02*
X965532Y213203D01*
X965907Y213078D01*
X966241D01*
X966574Y213203D01*
X966824Y213411D01*
X966949Y213703D01*
X966866Y213995D01*
X966657Y214245D01*
X966282Y214411D01*
X965782Y214495D01*
X965491Y214661D01*
X965366Y214953D01*
X965449Y215245D01*
X965657Y215453D01*
X965949Y215578D01*
X966241D01*
X966532Y215495D01*
X966782Y215286D01*
G01X968341Y213078D02*
Y215578D01*
X969382D01*
X969716Y215453D01*
X969924Y215286D01*
X970007Y214953D01*
X969924Y214620D01*
X969674Y214411D01*
X969382Y214286D01*
X968341D01*
G01X969382D02*
X970007Y213078D01*
G01X972191D02*
X972274Y213620D01*
X972399Y214078D01*
X972566Y214495D01*
X972774Y214953D01*
X973107Y215578D01*
X971441D01*
G01X974582Y215161D02*
X974832Y215411D01*
X975124Y215536D01*
X975457Y215578D01*
X975874Y215495D01*
X976166Y215286D01*
X976249Y215036D01*
X976207Y214786D01*
X976041Y214578D01*
X975207Y214161D01*
X974832Y213870D01*
X974582Y213453D01*
X974499Y213078D01*
X976249D01*
G01X977682Y215161D02*
X977932Y215411D01*
X978224Y215536D01*
X978557Y215578D01*
X978974Y215495D01*
X979266Y215286D01*
X979349Y215036D01*
X979307Y214786D01*
X979141Y214578D01*
X978307Y214161D01*
X977932Y213870D01*
X977682Y213453D01*
X977599Y213078D01*
X979349D01*
G01X965199Y218411D02*
X965532Y218203D01*
X965907Y218078D01*
X966241D01*
X966574Y218203D01*
X966824Y218411D01*
X966949Y218703D01*
X966866Y218995D01*
X966657Y219245D01*
X966282Y219411D01*
X965782Y219495D01*
X965491Y219661D01*
X965366Y219953D01*
X965449Y220245D01*
X965657Y220453D01*
X965949Y220578D01*
X966241D01*
X966532Y220495D01*
X966782Y220286D01*
G01X968341Y218078D02*
Y220578D01*
X969382D01*
X969716Y220453D01*
X969924Y220286D01*
X970007Y219953D01*
X969924Y219620D01*
X969674Y219411D01*
X969382Y219286D01*
X968341D01*
G01X969382D02*
X970007Y218078D01*
G01X972191D02*
X972274Y218620D01*
X972399Y219078D01*
X972566Y219495D01*
X972774Y219953D01*
X973107Y220578D01*
X971441D01*
G01X974582Y220161D02*
X974832Y220411D01*
X975124Y220536D01*
X975457Y220578D01*
X975874Y220495D01*
X976166Y220286D01*
X976249Y220036D01*
X976207Y219786D01*
X976041Y219578D01*
X975207Y219161D01*
X974832Y218870D01*
X974582Y218453D01*
X974499Y218078D01*
X976249D01*
G01X977557Y218578D02*
X977807Y218286D01*
X978141Y218120D01*
X978516Y218078D01*
X978849Y218120D01*
X979182Y218328D01*
X979391Y218578D01*
X979432Y218828D01*
X979349Y219120D01*
X979057Y219328D01*
X978766Y219411D01*
X978391D01*
G01X978766D02*
X979016Y219536D01*
X979224Y219745D01*
X979307Y219995D01*
X979224Y220245D01*
X979016Y220453D01*
X978641Y220578D01*
X978266Y220536D01*
X977891Y220370D01*
G01X956325Y401792D02*
X956075Y401917D01*
X955783Y402000D01*
X955450D01*
X955075Y401875D01*
X954783Y401667D01*
X954575Y401417D01*
X954408Y401000D01*
X954366Y400625D01*
X954450Y400250D01*
X954575Y400000D01*
X954825Y399750D01*
X955116Y399583D01*
X955408Y399500D01*
X955700D01*
X955991Y399583D01*
X956241Y399708D01*
X956450Y399875D01*
G01X957550Y399500D02*
Y402000D01*
X959466Y399500D01*
Y402000D01*
G01X961525Y399500D02*
X961608Y400042D01*
X961733Y400500D01*
X961900Y400917D01*
X962108Y401375D01*
X962441Y402000D01*
X960775D01*
G01X959858Y394400D02*
X982908D01*
G01X954050Y445750D02*
Y445900D01*
X955300Y447150D01*
X956500Y445950D01*
Y445700D01*
G01X968617Y439125D02*
X968825Y439458D01*
X968950Y439833D01*
Y440167D01*
X968825Y440500D01*
X968617Y440750D01*
X968325Y440875D01*
X968033Y440792D01*
X967783Y440583D01*
X967617Y440208D01*
X967533Y439708D01*
X967367Y439417D01*
X967075Y439292D01*
X966783Y439375D01*
X966575Y439583D01*
X966450Y439875D01*
Y440167D01*
X966533Y440458D01*
X966742Y440708D01*
G01X968950Y442267D02*
X966450D01*
Y443308D01*
X966575Y443642D01*
X966742Y443850D01*
X967075Y443933D01*
X967408Y443850D01*
X967617Y443600D01*
X967742Y443308D01*
Y442267D01*
G01Y443308D02*
X968950Y443933D01*
G01X968658Y445492D02*
X968867Y445783D01*
X968950Y446117D01*
X968867Y446450D01*
X968617Y446742D01*
X968242Y446950D01*
X967867Y447033D01*
X967408D01*
X967033Y446950D01*
X966700Y446742D01*
X966533Y446492D01*
X966450Y446200D01*
X966533Y445867D01*
X966700Y445617D01*
X966950Y445450D01*
X967283Y445367D01*
X967575Y445450D01*
X967867Y445658D01*
X968033Y445908D01*
X968075Y446200D01*
X967992Y446533D01*
X967783Y446783D01*
X967408Y447033D01*
G01X968450Y448383D02*
X968742Y448633D01*
X968908Y448967D01*
X968950Y449342D01*
X968908Y449675D01*
X968700Y450008D01*
X968450Y450217D01*
X968200Y450258D01*
X967908Y450175D01*
X967700Y449883D01*
X967617Y449592D01*
Y449217D01*
G01Y449592D02*
X967492Y449842D01*
X967283Y450050D01*
X967033Y450133D01*
X966783Y450050D01*
X966575Y449842D01*
X966450Y449467D01*
X966492Y449092D01*
X966658Y448717D01*
G01X968450Y451483D02*
X968742Y451733D01*
X968908Y452067D01*
X968950Y452442D01*
X968908Y452775D01*
X968700Y453108D01*
X968450Y453317D01*
X968200Y453358D01*
X967908Y453275D01*
X967700Y452983D01*
X967617Y452692D01*
Y452317D01*
G01Y452692D02*
X967492Y452942D01*
X967283Y453150D01*
X967033Y453233D01*
X966783Y453150D01*
X966575Y452942D01*
X966450Y452567D01*
X966492Y452192D01*
X966658Y451817D01*
G01X955950Y436000D02*
X959950D01*
Y443400D01*
G01X964383Y460200D02*
Y458408D01*
X964550Y458033D01*
X964883Y457783D01*
X965300Y457700D01*
X965717Y457783D01*
X966050Y458033D01*
X966217Y458408D01*
Y460200D01*
G01X968400Y457700D02*
Y460200D01*
X967900Y459700D01*
G01Y457700D02*
X968900D01*
G01X971500D02*
X971792Y457742D01*
X972125Y457867D01*
X972333Y458075D01*
X972417Y458367D01*
X972333Y458658D01*
X972083Y458908D01*
X971708Y459033D01*
X971292D01*
X971042Y459117D01*
X970833Y459325D01*
X970750Y459617D01*
X970875Y459908D01*
X971167Y460117D01*
X971500Y460200D01*
X971833Y460117D01*
X972125Y459908D01*
X972250Y459617D01*
X972167Y459325D01*
X971958Y459117D01*
X971708Y459033D01*
X971292D01*
X970917Y458908D01*
X970667Y458658D01*
X970583Y458367D01*
X970667Y458075D01*
X970875Y457867D01*
X971208Y457742D01*
X971500Y457700D01*
G01X973683Y458075D02*
X973933Y457867D01*
X974225Y457742D01*
X974600Y457700D01*
X974975Y457783D01*
X975267Y457950D01*
X975475Y458242D01*
X975517Y458575D01*
X975433Y458908D01*
X975225Y459117D01*
X974933Y459283D01*
X974642Y459325D01*
X974350Y459283D01*
X973975Y459117D01*
X974100Y460200D01*
X975225D01*
G01X955068Y461550D02*
X959068D01*
Y468950D01*
G01X972000Y531467D02*
X969500D01*
Y532508D01*
X969625Y532842D01*
X969792Y533050D01*
X970125Y533133D01*
X970458Y533050D01*
X970667Y532800D01*
X970792Y532508D01*
Y531467D01*
G01Y532508D02*
X972000Y533133D01*
G01Y535317D02*
X971458Y535400D01*
X971000Y535525D01*
X970583Y535692D01*
X970125Y535900D01*
X969500Y536233D01*
Y534567D01*
G01X971708Y537792D02*
X971917Y538083D01*
X972000Y538417D01*
X971917Y538750D01*
X971667Y539042D01*
X971292Y539250D01*
X970917Y539333D01*
X970458D01*
X970083Y539250D01*
X969750Y539042D01*
X969583Y538792D01*
X969500Y538500D01*
X969583Y538167D01*
X969750Y537917D01*
X970000Y537750D01*
X970333Y537667D01*
X970625Y537750D01*
X970917Y537958D01*
X971083Y538208D01*
X971125Y538500D01*
X971042Y538833D01*
X970833Y539083D01*
X970458Y539333D01*
G01X969500Y541600D02*
X969583Y541267D01*
X969792Y541017D01*
X970042Y540850D01*
X970375Y540725D01*
X970750Y540683D01*
X971125Y540725D01*
X971458Y540850D01*
X971708Y541017D01*
X971917Y541267D01*
X972000Y541600D01*
X971917Y541933D01*
X971708Y542183D01*
X971458Y542350D01*
X971125Y542475D01*
X970750Y542517D01*
X970375Y542475D01*
X970042Y542350D01*
X969792Y542183D01*
X969583Y541933D01*
X969500Y541600D01*
G01X970958Y543908D02*
X970667Y544200D01*
X970500Y544450D01*
X970417Y544783D01*
X970500Y545075D01*
X970667Y545283D01*
X970917Y545450D01*
X971208Y545492D01*
X971458Y545450D01*
X971708Y545283D01*
X971917Y545033D01*
X972000Y544742D01*
X971917Y544408D01*
X971667Y544117D01*
X971292Y543950D01*
X970875Y543908D01*
X970333Y543992D01*
X970042Y544117D01*
X969750Y544325D01*
X969542Y544617D01*
X969500Y544908D01*
X969583Y545200D01*
X969792Y545408D01*
G01X967167Y529875D02*
X967375Y530208D01*
X967500Y530583D01*
Y530917D01*
X967375Y531250D01*
X967167Y531500D01*
X966875Y531625D01*
X966583Y531542D01*
X966333Y531333D01*
X966167Y530958D01*
X966083Y530458D01*
X965917Y530167D01*
X965625Y530042D01*
X965333Y530125D01*
X965125Y530333D01*
X965000Y530625D01*
Y530917D01*
X965083Y531208D01*
X965292Y531458D01*
G01X965208Y534767D02*
X965083Y534517D01*
X965000Y534225D01*
Y533892D01*
X965125Y533517D01*
X965333Y533225D01*
X965583Y533017D01*
X966000Y532850D01*
X966375Y532808D01*
X966750Y532892D01*
X967000Y533017D01*
X967250Y533267D01*
X967417Y533558D01*
X967500Y533850D01*
Y534142D01*
X967417Y534433D01*
X967292Y534683D01*
X967125Y534892D01*
G01X967500Y536950D02*
X965000D01*
X965500Y536450D01*
G01X967500D02*
Y537450D01*
G01X967000Y539133D02*
X967292Y539383D01*
X967458Y539717D01*
X967500Y540092D01*
X967458Y540425D01*
X967250Y540758D01*
X967000Y540967D01*
X966750Y541008D01*
X966458Y540925D01*
X966250Y540633D01*
X966167Y540342D01*
Y539967D01*
G01Y540342D02*
X966042Y540592D01*
X965833Y540800D01*
X965583Y540883D01*
X965333Y540800D01*
X965125Y540592D01*
X965000Y540217D01*
X965042Y539842D01*
X965208Y539467D01*
G01X967500Y543150D02*
X965000D01*
X965500Y542650D01*
G01X967500D02*
Y543650D01*
G01Y546250D02*
X965000D01*
X965500Y545750D01*
G01X967500D02*
Y546750D01*
G01X984117Y58000D02*
Y55500D01*
X985783D01*
G01X987967D02*
X988050Y56042D01*
X988175Y56500D01*
X988342Y56917D01*
X988550Y57375D01*
X988883Y58000D01*
X987217D01*
G01X980827Y182882D02*
X981035Y183215D01*
X981160Y183590D01*
Y183924D01*
X981035Y184257D01*
X980827Y184507D01*
X980535Y184632D01*
X980243Y184549D01*
X979993Y184340D01*
X979827Y183965D01*
X979743Y183465D01*
X979577Y183174D01*
X979285Y183049D01*
X978993Y183132D01*
X978785Y183340D01*
X978660Y183632D01*
Y183924D01*
X978743Y184215D01*
X978952Y184465D01*
G01X978868Y187774D02*
X978743Y187524D01*
X978660Y187232D01*
Y186899D01*
X978785Y186524D01*
X978993Y186232D01*
X979243Y186024D01*
X979660Y185857D01*
X980035Y185815D01*
X980410Y185899D01*
X980660Y186024D01*
X980910Y186274D01*
X981077Y186565D01*
X981160Y186857D01*
Y187149D01*
X981077Y187440D01*
X980952Y187690D01*
X980785Y187899D01*
G01X981160Y189957D02*
X978660D01*
X979160Y189457D01*
G01X981160D02*
Y190457D01*
G01X978660Y193057D02*
X978743Y192724D01*
X978952Y192474D01*
X979202Y192307D01*
X979535Y192182D01*
X979910Y192140D01*
X980285Y192182D01*
X980618Y192307D01*
X980868Y192474D01*
X981077Y192724D01*
X981160Y193057D01*
X981077Y193390D01*
X980868Y193640D01*
X980618Y193807D01*
X980285Y193932D01*
X979910Y193974D01*
X979535Y193932D01*
X979202Y193807D01*
X978952Y193640D01*
X978743Y193390D01*
X978660Y193057D01*
G01X980118Y195365D02*
X979827Y195657D01*
X979660Y195907D01*
X979577Y196240D01*
X979660Y196532D01*
X979827Y196740D01*
X980077Y196907D01*
X980368Y196949D01*
X980618Y196907D01*
X980868Y196740D01*
X981077Y196490D01*
X981160Y196199D01*
X981077Y195865D01*
X980827Y195574D01*
X980452Y195407D01*
X980035Y195365D01*
X979493Y195449D01*
X979202Y195574D01*
X978910Y195782D01*
X978702Y196074D01*
X978660Y196365D01*
X978743Y196657D01*
X978952Y196865D01*
G01X980785Y198340D02*
X980993Y198590D01*
X981118Y198882D01*
X981160Y199257D01*
X981077Y199632D01*
X980910Y199924D01*
X980618Y200132D01*
X980285Y200174D01*
X979952Y200090D01*
X979743Y199882D01*
X979577Y199590D01*
X979535Y199299D01*
X979577Y199007D01*
X979743Y198632D01*
X978660Y198757D01*
Y199882D01*
G01X976427Y182882D02*
X976635Y183215D01*
X976760Y183590D01*
Y183924D01*
X976635Y184257D01*
X976427Y184507D01*
X976135Y184632D01*
X975843Y184549D01*
X975593Y184340D01*
X975427Y183965D01*
X975343Y183465D01*
X975177Y183174D01*
X974885Y183049D01*
X974593Y183132D01*
X974385Y183340D01*
X974260Y183632D01*
Y183924D01*
X974343Y184215D01*
X974552Y184465D01*
G01X974468Y187774D02*
X974343Y187524D01*
X974260Y187232D01*
Y186899D01*
X974385Y186524D01*
X974593Y186232D01*
X974843Y186024D01*
X975260Y185857D01*
X975635Y185815D01*
X976010Y185899D01*
X976260Y186024D01*
X976510Y186274D01*
X976677Y186565D01*
X976760Y186857D01*
Y187149D01*
X976677Y187440D01*
X976552Y187690D01*
X976385Y187899D01*
G01X976760Y189957D02*
X974260D01*
X974760Y189457D01*
G01X976760D02*
Y190457D01*
G01X974260Y193057D02*
X974343Y192724D01*
X974552Y192474D01*
X974802Y192307D01*
X975135Y192182D01*
X975510Y192140D01*
X975885Y192182D01*
X976218Y192307D01*
X976468Y192474D01*
X976677Y192724D01*
X976760Y193057D01*
X976677Y193390D01*
X976468Y193640D01*
X976218Y193807D01*
X975885Y193932D01*
X975510Y193974D01*
X975135Y193932D01*
X974802Y193807D01*
X974552Y193640D01*
X974343Y193390D01*
X974260Y193057D01*
G01X975718Y195365D02*
X975427Y195657D01*
X975260Y195907D01*
X975177Y196240D01*
X975260Y196532D01*
X975427Y196740D01*
X975677Y196907D01*
X975968Y196949D01*
X976218Y196907D01*
X976468Y196740D01*
X976677Y196490D01*
X976760Y196199D01*
X976677Y195865D01*
X976427Y195574D01*
X976052Y195407D01*
X975635Y195365D01*
X975093Y195449D01*
X974802Y195574D01*
X974510Y195782D01*
X974302Y196074D01*
X974260Y196365D01*
X974343Y196657D01*
X974552Y196865D01*
G01X976760Y199757D02*
X974260D01*
X976052Y198215D01*
Y200299D01*
G01X988974Y202578D02*
Y206578D01*
X981574D01*
G01X988974Y207578D02*
Y211578D01*
X981574D01*
G01X988974Y212578D02*
Y216578D01*
X981574D01*
G01X986300Y398000D02*
Y395500D01*
G01X985342Y398000D02*
X987258D01*
G01X988567Y395500D02*
Y398000D01*
X989567D01*
X989900Y397875D01*
X990150Y397583D01*
X990233Y397250D01*
X990150Y396917D01*
X989942Y396667D01*
X989567Y396542D01*
X988567D01*
G01X992500Y395500D02*
Y398000D01*
X992000Y397500D01*
G01Y395500D02*
X993000D01*
G01X994808Y396542D02*
X995100Y396833D01*
X995350Y397000D01*
X995683Y397083D01*
X995975Y397000D01*
X996183Y396833D01*
X996350Y396583D01*
X996392Y396292D01*
X996350Y396042D01*
X996183Y395792D01*
X995933Y395583D01*
X995642Y395500D01*
X995308Y395583D01*
X995017Y395833D01*
X994850Y396208D01*
X994808Y396625D01*
X994892Y397167D01*
X995017Y397458D01*
X995225Y397750D01*
X995517Y397958D01*
X995808Y398000D01*
X996100Y397917D01*
X996308Y397708D01*
G01X997783Y395875D02*
X998033Y395667D01*
X998325Y395542D01*
X998700Y395500D01*
X999075Y395583D01*
X999367Y395750D01*
X999575Y396042D01*
X999617Y396375D01*
X999533Y396708D01*
X999325Y396917D01*
X999033Y397083D01*
X998742Y397125D01*
X998450Y397083D01*
X998075Y396917D01*
X998200Y398000D01*
X999325D01*
G01X973117Y439125D02*
X973325Y439458D01*
X973450Y439833D01*
Y440167D01*
X973325Y440500D01*
X973117Y440750D01*
X972825Y440875D01*
X972533Y440792D01*
X972283Y440583D01*
X972117Y440208D01*
X972033Y439708D01*
X971867Y439417D01*
X971575Y439292D01*
X971283Y439375D01*
X971075Y439583D01*
X970950Y439875D01*
Y440167D01*
X971033Y440458D01*
X971242Y440708D01*
G01X973450Y442267D02*
X970950D01*
Y443308D01*
X971075Y443642D01*
X971242Y443850D01*
X971575Y443933D01*
X971908Y443850D01*
X972117Y443600D01*
X972242Y443308D01*
Y442267D01*
G01Y443308D02*
X973450Y443933D01*
G01X973158Y445492D02*
X973367Y445783D01*
X973450Y446117D01*
X973367Y446450D01*
X973117Y446742D01*
X972742Y446950D01*
X972367Y447033D01*
X971908D01*
X971533Y446950D01*
X971200Y446742D01*
X971033Y446492D01*
X970950Y446200D01*
X971033Y445867D01*
X971200Y445617D01*
X971450Y445450D01*
X971783Y445367D01*
X972075Y445450D01*
X972367Y445658D01*
X972533Y445908D01*
X972575Y446200D01*
X972492Y446533D01*
X972283Y446783D01*
X971908Y447033D01*
G01X972950Y448383D02*
X973242Y448633D01*
X973408Y448967D01*
X973450Y449342D01*
X973408Y449675D01*
X973200Y450008D01*
X972950Y450217D01*
X972700Y450258D01*
X972408Y450175D01*
X972200Y449883D01*
X972117Y449592D01*
Y449217D01*
G01Y449592D02*
X971992Y449842D01*
X971783Y450050D01*
X971533Y450133D01*
X971283Y450050D01*
X971075Y449842D01*
X970950Y449467D01*
X970992Y449092D01*
X971158Y448717D01*
G01X973450Y452900D02*
X970950D01*
X972742Y451358D01*
Y453442D01*
G01X988000Y475467D02*
X985500D01*
Y476508D01*
X985625Y476842D01*
X985792Y477050D01*
X986125Y477133D01*
X986458Y477050D01*
X986667Y476800D01*
X986792Y476508D01*
Y475467D01*
G01Y476508D02*
X988000Y477133D01*
G01Y479317D02*
X987458Y479400D01*
X987000Y479525D01*
X986583Y479692D01*
X986125Y479900D01*
X985500Y480233D01*
Y478567D01*
G01X987708Y481792D02*
X987917Y482083D01*
X988000Y482417D01*
X987917Y482750D01*
X987667Y483042D01*
X987292Y483250D01*
X986917Y483333D01*
X986458D01*
X986083Y483250D01*
X985750Y483042D01*
X985583Y482792D01*
X985500Y482500D01*
X985583Y482167D01*
X985750Y481917D01*
X986000Y481750D01*
X986333Y481667D01*
X986625Y481750D01*
X986917Y481958D01*
X987083Y482208D01*
X987125Y482500D01*
X987042Y482833D01*
X986833Y483083D01*
X986458Y483333D01*
G01X985500Y485600D02*
X985583Y485267D01*
X985792Y485017D01*
X986042Y484850D01*
X986375Y484725D01*
X986750Y484683D01*
X987125Y484725D01*
X987458Y484850D01*
X987708Y485017D01*
X987917Y485267D01*
X988000Y485600D01*
X987917Y485933D01*
X987708Y486183D01*
X987458Y486350D01*
X987125Y486475D01*
X986750Y486517D01*
X986375Y486475D01*
X986042Y486350D01*
X985792Y486183D01*
X985583Y485933D01*
X985500Y485600D01*
G01X987625Y487783D02*
X987833Y488033D01*
X987958Y488325D01*
X988000Y488700D01*
X987917Y489075D01*
X987750Y489367D01*
X987458Y489575D01*
X987125Y489617D01*
X986792Y489533D01*
X986583Y489325D01*
X986417Y489033D01*
X986375Y488742D01*
X986417Y488450D01*
X986583Y488075D01*
X985500Y488200D01*
Y489325D01*
G01X974467Y495500D02*
Y498000D01*
X975508D01*
X975842Y497875D01*
X976050Y497708D01*
X976133Y497375D01*
X976050Y497042D01*
X975800Y496833D01*
X975508Y496708D01*
X974467D01*
G01X975508D02*
X976133Y495500D01*
G01X978317D02*
X978400Y496042D01*
X978525Y496500D01*
X978692Y496917D01*
X978900Y497375D01*
X979233Y498000D01*
X977567D01*
G01X980792Y495792D02*
X981083Y495583D01*
X981417Y495500D01*
X981750Y495583D01*
X982042Y495833D01*
X982250Y496208D01*
X982333Y496583D01*
Y497042D01*
X982250Y497417D01*
X982042Y497750D01*
X981792Y497917D01*
X981500Y498000D01*
X981167Y497917D01*
X980917Y497750D01*
X980750Y497500D01*
X980667Y497167D01*
X980750Y496875D01*
X980958Y496583D01*
X981208Y496417D01*
X981500Y496375D01*
X981833Y496458D01*
X982083Y496667D01*
X982333Y497042D01*
G01X984600Y498000D02*
X984267Y497917D01*
X984017Y497708D01*
X983850Y497458D01*
X983725Y497125D01*
X983683Y496750D01*
X983725Y496375D01*
X983850Y496042D01*
X984017Y495792D01*
X984267Y495583D01*
X984600Y495500D01*
X984933Y495583D01*
X985183Y495792D01*
X985350Y496042D01*
X985475Y496375D01*
X985517Y496750D01*
X985475Y497125D01*
X985350Y497458D01*
X985183Y497708D01*
X984933Y497917D01*
X984600Y498000D01*
G01X988200Y495500D02*
Y498000D01*
X986658Y496208D01*
X988742D01*
G01X970500Y514433D02*
X972292D01*
X972667Y514600D01*
X972917Y514933D01*
X973000Y515350D01*
X972917Y515767D01*
X972667Y516100D01*
X972292Y516267D01*
X970500D01*
G01X973000Y518450D02*
X970500D01*
X971000Y517950D01*
G01X973000D02*
Y518950D01*
G01X972708Y520842D02*
X972917Y521133D01*
X973000Y521467D01*
X972917Y521800D01*
X972667Y522092D01*
X972292Y522300D01*
X971917Y522383D01*
X971458D01*
X971083Y522300D01*
X970750Y522092D01*
X970583Y521842D01*
X970500Y521550D01*
X970583Y521217D01*
X970750Y520967D01*
X971000Y520800D01*
X971333Y520717D01*
X971625Y520800D01*
X971917Y521008D01*
X972083Y521258D01*
X972125Y521550D01*
X972042Y521883D01*
X971833Y522133D01*
X971458Y522383D01*
G01X972500Y523733D02*
X972792Y523983D01*
X972958Y524317D01*
X973000Y524692D01*
X972958Y525025D01*
X972750Y525358D01*
X972500Y525567D01*
X972250Y525608D01*
X971958Y525525D01*
X971750Y525233D01*
X971667Y524942D01*
Y524567D01*
G01Y524942D02*
X971542Y525192D01*
X971333Y525400D01*
X971083Y525483D01*
X970833Y525400D01*
X970625Y525192D01*
X970500Y524817D01*
X970542Y524442D01*
X970708Y524067D01*
G01X984500Y514433D02*
X986292D01*
X986667Y514600D01*
X986917Y514933D01*
X987000Y515350D01*
X986917Y515767D01*
X986667Y516100D01*
X986292Y516267D01*
X984500D01*
G01X987000Y518450D02*
X984500D01*
X985000Y517950D01*
G01X987000D02*
Y518950D01*
G01X986708Y520842D02*
X986917Y521133D01*
X987000Y521467D01*
X986917Y521800D01*
X986667Y522092D01*
X986292Y522300D01*
X985917Y522383D01*
X985458D01*
X985083Y522300D01*
X984750Y522092D01*
X984583Y521842D01*
X984500Y521550D01*
X984583Y521217D01*
X984750Y520967D01*
X985000Y520800D01*
X985333Y520717D01*
X985625Y520800D01*
X985917Y521008D01*
X986083Y521258D01*
X986125Y521550D01*
X986042Y521883D01*
X985833Y522133D01*
X985458Y522383D01*
G01X984917Y523858D02*
X984667Y524108D01*
X984542Y524400D01*
X984500Y524733D01*
X984583Y525150D01*
X984792Y525442D01*
X985042Y525525D01*
X985292Y525483D01*
X985500Y525317D01*
X985917Y524483D01*
X986208Y524108D01*
X986625Y523858D01*
X987000Y523775D01*
Y525525D01*
G01X986000Y531467D02*
X983500D01*
Y532508D01*
X983625Y532842D01*
X983792Y533050D01*
X984125Y533133D01*
X984458Y533050D01*
X984667Y532800D01*
X984792Y532508D01*
Y531467D01*
G01Y532508D02*
X986000Y533133D01*
G01Y535317D02*
X985458Y535400D01*
X985000Y535525D01*
X984583Y535692D01*
X984125Y535900D01*
X983500Y536233D01*
Y534567D01*
G01X985708Y537792D02*
X985917Y538083D01*
X986000Y538417D01*
X985917Y538750D01*
X985667Y539042D01*
X985292Y539250D01*
X984917Y539333D01*
X984458D01*
X984083Y539250D01*
X983750Y539042D01*
X983583Y538792D01*
X983500Y538500D01*
X983583Y538167D01*
X983750Y537917D01*
X984000Y537750D01*
X984333Y537667D01*
X984625Y537750D01*
X984917Y537958D01*
X985083Y538208D01*
X985125Y538500D01*
X985042Y538833D01*
X984833Y539083D01*
X984458Y539333D01*
G01X983500Y541600D02*
X983583Y541267D01*
X983792Y541017D01*
X984042Y540850D01*
X984375Y540725D01*
X984750Y540683D01*
X985125Y540725D01*
X985458Y540850D01*
X985708Y541017D01*
X985917Y541267D01*
X986000Y541600D01*
X985917Y541933D01*
X985708Y542183D01*
X985458Y542350D01*
X985125Y542475D01*
X984750Y542517D01*
X984375Y542475D01*
X984042Y542350D01*
X983792Y542183D01*
X983583Y541933D01*
X983500Y541600D01*
G01X983917Y543908D02*
X983667Y544158D01*
X983542Y544450D01*
X983500Y544783D01*
X983583Y545200D01*
X983792Y545492D01*
X984042Y545575D01*
X984292Y545533D01*
X984500Y545367D01*
X984917Y544533D01*
X985208Y544158D01*
X985625Y543908D01*
X986000Y543825D01*
Y545575D01*
G01X976000Y531467D02*
X973500D01*
Y532508D01*
X973625Y532842D01*
X973792Y533050D01*
X974125Y533133D01*
X974458Y533050D01*
X974667Y532800D01*
X974792Y532508D01*
Y531467D01*
G01Y532508D02*
X976000Y533133D01*
G01Y535317D02*
X975458Y535400D01*
X975000Y535525D01*
X974583Y535692D01*
X974125Y535900D01*
X973500Y536233D01*
Y534567D01*
G01X975708Y537792D02*
X975917Y538083D01*
X976000Y538417D01*
X975917Y538750D01*
X975667Y539042D01*
X975292Y539250D01*
X974917Y539333D01*
X974458D01*
X974083Y539250D01*
X973750Y539042D01*
X973583Y538792D01*
X973500Y538500D01*
X973583Y538167D01*
X973750Y537917D01*
X974000Y537750D01*
X974333Y537667D01*
X974625Y537750D01*
X974917Y537958D01*
X975083Y538208D01*
X975125Y538500D01*
X975042Y538833D01*
X974833Y539083D01*
X974458Y539333D01*
G01X973500Y541600D02*
X973583Y541267D01*
X973792Y541017D01*
X974042Y540850D01*
X974375Y540725D01*
X974750Y540683D01*
X975125Y540725D01*
X975458Y540850D01*
X975708Y541017D01*
X975917Y541267D01*
X976000Y541600D01*
X975917Y541933D01*
X975708Y542183D01*
X975458Y542350D01*
X975125Y542475D01*
X974750Y542517D01*
X974375Y542475D01*
X974042Y542350D01*
X973792Y542183D01*
X973583Y541933D01*
X973500Y541600D01*
G01X976000Y544617D02*
X975458Y544700D01*
X975000Y544825D01*
X974583Y544992D01*
X974125Y545200D01*
X973500Y545533D01*
Y543867D01*
G01X981167Y529875D02*
X981375Y530208D01*
X981500Y530583D01*
Y530917D01*
X981375Y531250D01*
X981167Y531500D01*
X980875Y531625D01*
X980583Y531542D01*
X980333Y531333D01*
X980167Y530958D01*
X980083Y530458D01*
X979917Y530167D01*
X979625Y530042D01*
X979333Y530125D01*
X979125Y530333D01*
X979000Y530625D01*
Y530917D01*
X979083Y531208D01*
X979292Y531458D01*
G01X979208Y534767D02*
X979083Y534517D01*
X979000Y534225D01*
Y533892D01*
X979125Y533517D01*
X979333Y533225D01*
X979583Y533017D01*
X980000Y532850D01*
X980375Y532808D01*
X980750Y532892D01*
X981000Y533017D01*
X981250Y533267D01*
X981417Y533558D01*
X981500Y533850D01*
Y534142D01*
X981417Y534433D01*
X981292Y534683D01*
X981125Y534892D01*
G01X981500Y536950D02*
X979000D01*
X979500Y536450D01*
G01X981500D02*
Y537450D01*
G01X981000Y539133D02*
X981292Y539383D01*
X981458Y539717D01*
X981500Y540092D01*
X981458Y540425D01*
X981250Y540758D01*
X981000Y540967D01*
X980750Y541008D01*
X980458Y540925D01*
X980250Y540633D01*
X980167Y540342D01*
Y539967D01*
G01Y540342D02*
X980042Y540592D01*
X979833Y540800D01*
X979583Y540883D01*
X979333Y540800D01*
X979125Y540592D01*
X979000Y540217D01*
X979042Y539842D01*
X979208Y539467D01*
G01X979000Y543150D02*
X979083Y542817D01*
X979292Y542567D01*
X979542Y542400D01*
X979875Y542275D01*
X980250Y542233D01*
X980625Y542275D01*
X980958Y542400D01*
X981208Y542567D01*
X981417Y542817D01*
X981500Y543150D01*
X981417Y543483D01*
X981208Y543733D01*
X980958Y543900D01*
X980625Y544025D01*
X980250Y544067D01*
X979875Y544025D01*
X979542Y543900D01*
X979292Y543733D01*
X979083Y543483D01*
X979000Y543150D01*
G01X981000Y545333D02*
X981292Y545583D01*
X981458Y545917D01*
X981500Y546292D01*
X981458Y546625D01*
X981250Y546958D01*
X981000Y547167D01*
X980750Y547208D01*
X980458Y547125D01*
X980250Y546833D01*
X980167Y546542D01*
Y546167D01*
G01Y546542D02*
X980042Y546792D01*
X979833Y547000D01*
X979583Y547083D01*
X979333Y547000D01*
X979125Y546792D01*
X979000Y546417D01*
X979042Y546042D01*
X979208Y545667D01*
G01X984500Y732500D02*
X983833Y732583D01*
X983250Y732917D01*
X982750Y733417D01*
X982417Y734000D01*
X982250Y734667D01*
Y735333D01*
X982417Y736000D01*
X982750Y736583D01*
X983250Y737083D01*
X983833Y737417D01*
X984500Y737500D01*
X985167Y737417D01*
X985750Y737083D01*
X986250Y736583D01*
X986583Y736000D01*
X986750Y735333D01*
Y734667D01*
X986583Y734000D01*
X986250Y733417D01*
X985750Y732917D01*
X985167Y732583D01*
X984500Y732500D01*
G01X988350Y733167D02*
X989017Y732750D01*
X989767Y732500D01*
X990433D01*
X991100Y732750D01*
X991600Y733167D01*
X991850Y733750D01*
X991683Y734333D01*
X991267Y734833D01*
X990517Y735167D01*
X989517Y735333D01*
X988933Y735667D01*
X988683Y736250D01*
X988850Y736833D01*
X989267Y737250D01*
X989850Y737500D01*
X990433D01*
X991017Y737333D01*
X991517Y736917D01*
G01X997533Y737083D02*
X997033Y737333D01*
X996450Y737500D01*
X995783D01*
X995033Y737250D01*
X994450Y736833D01*
X994033Y736333D01*
X993700Y735500D01*
X993617Y734750D01*
X993783Y734000D01*
X994033Y733500D01*
X994533Y733000D01*
X995117Y732667D01*
X995700Y732500D01*
X996283D01*
X996867Y732667D01*
X997367Y732917D01*
X997783Y733250D01*
G01X1001300Y732500D02*
Y737500D01*
X1000300Y736500D01*
G01Y732500D02*
X1002300D01*
G01X1006900Y732333D02*
X1006733Y732417D01*
Y732583D01*
X1006900Y732667D01*
X1007067Y732583D01*
Y732417D01*
X1006900Y732333D01*
G01Y734583D02*
X1006733Y734667D01*
Y734833D01*
X1006900Y734917D01*
X1007067Y734833D01*
Y734667D01*
X1006900Y734583D01*
G01X1013500Y732500D02*
Y737500D01*
X1010417Y733917D01*
X1014583D01*
G01X1018100Y732500D02*
X1018683Y732583D01*
X1019350Y732833D01*
X1019767Y733250D01*
X1019933Y733833D01*
X1019767Y734417D01*
X1019267Y734917D01*
X1018517Y735167D01*
X1017683D01*
X1017183Y735333D01*
X1016767Y735750D01*
X1016600Y736333D01*
X1016850Y736917D01*
X1017433Y737333D01*
X1018100Y737500D01*
X1018767Y737333D01*
X1019350Y736917D01*
X1019600Y736333D01*
X1019433Y735750D01*
X1019017Y735333D01*
X1018517Y735167D01*
X1017683D01*
X1016933Y734917D01*
X1016433Y734417D01*
X1016267Y733833D01*
X1016433Y733250D01*
X1016850Y732833D01*
X1017517Y732583D01*
X1018100Y732500D01*
G01X1021533D02*
Y737500D01*
X1023700Y733333D01*
X1025867Y737500D01*
Y732500D01*
G01X1027550D02*
Y737500D01*
G01X1031050D02*
Y732500D01*
G01Y735000D02*
X1027550D01*
G01X1033317Y737500D02*
X1036483D01*
X1033317Y732500D01*
X1036483D01*
G01X994500Y55158D02*
X992000D01*
Y56742D01*
G01X993208Y56158D02*
Y55158D01*
G01X994500Y59050D02*
X992000D01*
X992500Y58550D01*
G01X994500D02*
Y59550D01*
G01X997500Y52850D02*
X1000000D01*
G01X997500Y51892D02*
Y53808D01*
G01X997708Y56867D02*
X997583Y56617D01*
X997500Y56325D01*
Y55992D01*
X997625Y55617D01*
X997833Y55325D01*
X998083Y55117D01*
X998500Y54950D01*
X998875Y54908D01*
X999250Y54992D01*
X999500Y55117D01*
X999750Y55367D01*
X999917Y55658D01*
X1000000Y55950D01*
Y56242D01*
X999917Y56533D01*
X999792Y56783D01*
X999625Y56992D01*
G01X1000000Y59050D02*
X997500D01*
X998000Y58550D01*
G01X1000000D02*
Y59550D01*
G01X997500Y62150D02*
X997583Y61817D01*
X997792Y61567D01*
X998042Y61400D01*
X998375Y61275D01*
X998750Y61233D01*
X999125Y61275D01*
X999458Y61400D01*
X999708Y61567D01*
X999917Y61817D01*
X1000000Y62150D01*
X999917Y62483D01*
X999708Y62733D01*
X999458Y62900D01*
X999125Y63025D01*
X998750Y63067D01*
X998375Y63025D01*
X998042Y62900D01*
X997792Y62733D01*
X997583Y62483D01*
X997500Y62150D01*
G01X1002000Y52850D02*
X1004500D01*
G01X1002000Y51892D02*
Y53808D01*
G01X1002208Y56867D02*
X1002083Y56617D01*
X1002000Y56325D01*
Y55992D01*
X1002125Y55617D01*
X1002333Y55325D01*
X1002583Y55117D01*
X1003000Y54950D01*
X1003375Y54908D01*
X1003750Y54992D01*
X1004000Y55117D01*
X1004250Y55367D01*
X1004417Y55658D01*
X1004500Y55950D01*
Y56242D01*
X1004417Y56533D01*
X1004292Y56783D01*
X1004125Y56992D01*
G01X1004500Y59050D02*
X1002000D01*
X1002500Y58550D01*
G01X1004500D02*
Y59550D01*
G01X1002417Y61358D02*
X1002167Y61608D01*
X1002042Y61900D01*
X1002000Y62233D01*
X1002083Y62650D01*
X1002292Y62942D01*
X1002542Y63025D01*
X1002792Y62983D01*
X1003000Y62817D01*
X1003417Y61983D01*
X1003708Y61608D01*
X1004125Y61358D01*
X1004500Y61275D01*
Y63025D01*
G01X1010700Y73100D02*
X997300D01*
G01Y65900D02*
X1010700D01*
G01X997300Y73100D02*
Y65900D01*
G01X999017Y121000D02*
Y123500D01*
X1000017D01*
X1000350Y123375D01*
X1000600Y123083D01*
X1000683Y122750D01*
X1000600Y122417D01*
X1000392Y122167D01*
X1000017Y122042D01*
X999017D01*
G01X1002117Y121000D02*
Y123500D01*
X1003158D01*
X1003492Y123375D01*
X1003700Y123208D01*
X1003783Y122875D01*
X1003700Y122542D01*
X1003450Y122333D01*
X1003158Y122208D01*
X1002117D01*
G01X1003158D02*
X1003783Y121000D01*
G01X1005133Y121500D02*
X1005383Y121208D01*
X1005717Y121042D01*
X1006092Y121000D01*
X1006425Y121042D01*
X1006758Y121250D01*
X1006967Y121500D01*
X1007008Y121750D01*
X1006925Y122042D01*
X1006633Y122250D01*
X1006342Y122333D01*
X1005967D01*
G01X1006342D02*
X1006592Y122458D01*
X1006800Y122667D01*
X1006883Y122917D01*
X1006800Y123167D01*
X1006592Y123375D01*
X1006217Y123500D01*
X1005842Y123458D01*
X1005467Y123292D01*
G01X1009150Y121000D02*
X1009442Y121042D01*
X1009775Y121167D01*
X1009983Y121375D01*
X1010067Y121667D01*
X1009983Y121958D01*
X1009733Y122208D01*
X1009358Y122333D01*
X1008942D01*
X1008692Y122417D01*
X1008483Y122625D01*
X1008400Y122917D01*
X1008525Y123208D01*
X1008817Y123417D01*
X1009150Y123500D01*
X1009483Y123417D01*
X1009775Y123208D01*
X1009900Y122917D01*
X1009817Y122625D01*
X1009608Y122417D01*
X1009358Y122333D01*
X1008942D01*
X1008567Y122208D01*
X1008317Y121958D01*
X1008233Y121667D01*
X1008317Y121375D01*
X1008525Y121167D01*
X1008858Y121042D01*
X1009150Y121000D01*
G01X1004000Y126517D02*
X1001500D01*
Y127517D01*
X1001625Y127850D01*
X1001917Y128100D01*
X1002250Y128183D01*
X1002583Y128100D01*
X1002833Y127892D01*
X1002958Y127517D01*
Y126517D01*
G01X1004000Y129617D02*
X1001500D01*
Y130658D01*
X1001625Y130992D01*
X1001792Y131200D01*
X1002125Y131283D01*
X1002458Y131200D01*
X1002667Y130950D01*
X1002792Y130658D01*
Y129617D01*
G01Y130658D02*
X1004000Y131283D01*
G01X1003625Y132633D02*
X1003833Y132883D01*
X1003958Y133175D01*
X1004000Y133550D01*
X1003917Y133925D01*
X1003750Y134217D01*
X1003458Y134425D01*
X1003125Y134467D01*
X1002792Y134383D01*
X1002583Y134175D01*
X1002417Y133883D01*
X1002375Y133592D01*
X1002417Y133300D01*
X1002583Y132925D01*
X1001500Y133050D01*
Y134175D01*
G01X1004000Y136567D02*
X1003458Y136650D01*
X1003000Y136775D01*
X1002583Y136942D01*
X1002125Y137150D01*
X1001500Y137483D01*
Y135817D01*
G01X1012874Y196278D02*
Y215478D01*
X1001674D01*
Y196278D01*
X1012874D01*
Y196678D01*
G01X1003767Y278292D02*
X1003517Y278417D01*
X1003225Y278500D01*
X1002892D01*
X1002517Y278375D01*
X1002225Y278167D01*
X1002017Y277917D01*
X1001850Y277500D01*
X1001808Y277125D01*
X1001892Y276750D01*
X1002017Y276500D01*
X1002267Y276250D01*
X1002558Y276083D01*
X1002850Y276000D01*
X1003142D01*
X1003433Y276083D01*
X1003683Y276208D01*
X1003892Y276375D01*
G01X1005033Y276500D02*
X1005283Y276208D01*
X1005617Y276042D01*
X1005992Y276000D01*
X1006325Y276042D01*
X1006658Y276250D01*
X1006867Y276500D01*
X1006908Y276750D01*
X1006825Y277042D01*
X1006533Y277250D01*
X1006242Y277333D01*
X1005867D01*
G01X1006242D02*
X1006492Y277458D01*
X1006700Y277667D01*
X1006783Y277917D01*
X1006700Y278167D01*
X1006492Y278375D01*
X1006117Y278500D01*
X1005742Y278458D01*
X1005367Y278292D01*
G01X1009050Y278500D02*
X1008717Y278417D01*
X1008467Y278208D01*
X1008300Y277958D01*
X1008175Y277625D01*
X1008133Y277250D01*
X1008175Y276875D01*
X1008300Y276542D01*
X1008467Y276292D01*
X1008717Y276083D01*
X1009050Y276000D01*
X1009383Y276083D01*
X1009633Y276292D01*
X1009800Y276542D01*
X1009925Y276875D01*
X1009967Y277250D01*
X1009925Y277625D01*
X1009800Y277958D01*
X1009633Y278208D01*
X1009383Y278417D01*
X1009050Y278500D01*
G01X1011442Y276292D02*
X1011733Y276083D01*
X1012067Y276000D01*
X1012400Y276083D01*
X1012692Y276333D01*
X1012900Y276708D01*
X1012983Y277083D01*
Y277542D01*
X1012900Y277917D01*
X1012692Y278250D01*
X1012442Y278417D01*
X1012150Y278500D01*
X1011817Y278417D01*
X1011567Y278250D01*
X1011400Y278000D01*
X1011317Y277667D01*
X1011400Y277375D01*
X1011608Y277083D01*
X1011858Y276917D01*
X1012150Y276875D01*
X1012483Y276958D01*
X1012733Y277167D01*
X1012983Y277542D01*
G01X1003767Y282292D02*
X1003517Y282417D01*
X1003225Y282500D01*
X1002892D01*
X1002517Y282375D01*
X1002225Y282167D01*
X1002017Y281917D01*
X1001850Y281500D01*
X1001808Y281125D01*
X1001892Y280750D01*
X1002017Y280500D01*
X1002267Y280250D01*
X1002558Y280083D01*
X1002850Y280000D01*
X1003142D01*
X1003433Y280083D01*
X1003683Y280208D01*
X1003892Y280375D01*
G01X1005033Y280500D02*
X1005283Y280208D01*
X1005617Y280042D01*
X1005992Y280000D01*
X1006325Y280042D01*
X1006658Y280250D01*
X1006867Y280500D01*
X1006908Y280750D01*
X1006825Y281042D01*
X1006533Y281250D01*
X1006242Y281333D01*
X1005867D01*
G01X1006242D02*
X1006492Y281458D01*
X1006700Y281667D01*
X1006783Y281917D01*
X1006700Y282167D01*
X1006492Y282375D01*
X1006117Y282500D01*
X1005742Y282458D01*
X1005367Y282292D01*
G01X1009050Y280000D02*
Y282500D01*
X1008550Y282000D01*
G01Y280000D02*
X1009550D01*
G01X1012150Y282500D02*
X1011817Y282417D01*
X1011567Y282208D01*
X1011400Y281958D01*
X1011275Y281625D01*
X1011233Y281250D01*
X1011275Y280875D01*
X1011400Y280542D01*
X1011567Y280292D01*
X1011817Y280083D01*
X1012150Y280000D01*
X1012483Y280083D01*
X1012733Y280292D01*
X1012900Y280542D01*
X1013025Y280875D01*
X1013067Y281250D01*
X1013025Y281625D01*
X1012900Y281958D01*
X1012733Y282208D01*
X1012483Y282417D01*
X1012150Y282500D01*
G01X1013700Y462000D02*
X1000300D01*
G01D02*
Y472000D01*
G01D02*
X1013700D01*
G01X1000000Y486200D02*
X996000D01*
Y478800D01*
G01X993000Y475467D02*
X990500D01*
Y476508D01*
X990625Y476842D01*
X990792Y477050D01*
X991125Y477133D01*
X991458Y477050D01*
X991667Y476800D01*
X991792Y476508D01*
Y475467D01*
G01Y476508D02*
X993000Y477133D01*
G01Y479317D02*
X992458Y479400D01*
X992000Y479525D01*
X991583Y479692D01*
X991125Y479900D01*
X990500Y480233D01*
Y478567D01*
G01X992708Y481792D02*
X992917Y482083D01*
X993000Y482417D01*
X992917Y482750D01*
X992667Y483042D01*
X992292Y483250D01*
X991917Y483333D01*
X991458D01*
X991083Y483250D01*
X990750Y483042D01*
X990583Y482792D01*
X990500Y482500D01*
X990583Y482167D01*
X990750Y481917D01*
X991000Y481750D01*
X991333Y481667D01*
X991625Y481750D01*
X991917Y481958D01*
X992083Y482208D01*
X992125Y482500D01*
X992042Y482833D01*
X991833Y483083D01*
X991458Y483333D01*
G01X990500Y485600D02*
X990583Y485267D01*
X990792Y485017D01*
X991042Y484850D01*
X991375Y484725D01*
X991750Y484683D01*
X992125Y484725D01*
X992458Y484850D01*
X992708Y485017D01*
X992917Y485267D01*
X993000Y485600D01*
X992917Y485933D01*
X992708Y486183D01*
X992458Y486350D01*
X992125Y486475D01*
X991750Y486517D01*
X991375Y486475D01*
X991042Y486350D01*
X990792Y486183D01*
X990583Y485933D01*
X990500Y485600D01*
G01X993000Y488700D02*
X992958Y488992D01*
X992833Y489325D01*
X992625Y489533D01*
X992333Y489617D01*
X992042Y489533D01*
X991792Y489283D01*
X991667Y488908D01*
Y488492D01*
X991583Y488242D01*
X991375Y488033D01*
X991083Y487950D01*
X990792Y488075D01*
X990583Y488367D01*
X990500Y488700D01*
X990583Y489033D01*
X990792Y489325D01*
X991083Y489450D01*
X991375Y489367D01*
X991583Y489158D01*
X991667Y488908D01*
Y488492D01*
X991792Y488117D01*
X992042Y487867D01*
X992333Y487783D01*
X992625Y487867D01*
X992833Y488075D01*
X992958Y488408D01*
X993000Y488700D01*
G01X1005000Y486200D02*
X1001000D01*
Y478800D01*
G01X999700Y494500D02*
Y498500D01*
X992300D01*
G01X993000Y520000D02*
X991800Y518800D01*
G01X993000Y520000D02*
X991800Y521200D01*
G01Y522300D02*
Y517700D01*
G01X1002700D02*
X991800D01*
G01X1002700Y522300D02*
Y517700D01*
G01X991800Y522300D02*
X1002700D01*
G01X990000Y531467D02*
X987500D01*
Y532508D01*
X987625Y532842D01*
X987792Y533050D01*
X988125Y533133D01*
X988458Y533050D01*
X988667Y532800D01*
X988792Y532508D01*
Y531467D01*
G01Y532508D02*
X990000Y533133D01*
G01Y535317D02*
X989458Y535400D01*
X989000Y535525D01*
X988583Y535692D01*
X988125Y535900D01*
X987500Y536233D01*
Y534567D01*
G01X989708Y537792D02*
X989917Y538083D01*
X990000Y538417D01*
X989917Y538750D01*
X989667Y539042D01*
X989292Y539250D01*
X988917Y539333D01*
X988458D01*
X988083Y539250D01*
X987750Y539042D01*
X987583Y538792D01*
X987500Y538500D01*
X987583Y538167D01*
X987750Y537917D01*
X988000Y537750D01*
X988333Y537667D01*
X988625Y537750D01*
X988917Y537958D01*
X989083Y538208D01*
X989125Y538500D01*
X989042Y538833D01*
X988833Y539083D01*
X988458Y539333D01*
G01X987500Y541600D02*
X987583Y541267D01*
X987792Y541017D01*
X988042Y540850D01*
X988375Y540725D01*
X988750Y540683D01*
X989125Y540725D01*
X989458Y540850D01*
X989708Y541017D01*
X989917Y541267D01*
X990000Y541600D01*
X989917Y541933D01*
X989708Y542183D01*
X989458Y542350D01*
X989125Y542475D01*
X988750Y542517D01*
X988375Y542475D01*
X988042Y542350D01*
X987792Y542183D01*
X987583Y541933D01*
X987500Y541600D01*
G01X989500Y543783D02*
X989792Y544033D01*
X989958Y544367D01*
X990000Y544742D01*
X989958Y545075D01*
X989750Y545408D01*
X989500Y545617D01*
X989250Y545658D01*
X988958Y545575D01*
X988750Y545283D01*
X988667Y544992D01*
Y544617D01*
G01Y544992D02*
X988542Y545242D01*
X988333Y545450D01*
X988083Y545533D01*
X987833Y545450D01*
X987625Y545242D01*
X987500Y544867D01*
X987542Y544492D01*
X987708Y544117D01*
G01X1001000Y542200D02*
X997000D01*
Y534800D01*
G01X1005000Y542200D02*
X1001000D01*
Y534800D01*
G01X999967Y883500D02*
Y886000D01*
X1000967D01*
X1001300Y885875D01*
X1001550Y885583D01*
X1001633Y885250D01*
X1001550Y884917D01*
X1001342Y884667D01*
X1000967Y884542D01*
X999967D01*
G01X1004817Y885792D02*
X1004567Y885917D01*
X1004275Y886000D01*
X1003942D01*
X1003567Y885875D01*
X1003275Y885667D01*
X1003067Y885417D01*
X1002900Y885000D01*
X1002858Y884625D01*
X1002942Y884250D01*
X1003067Y884000D01*
X1003317Y883750D01*
X1003608Y883583D01*
X1003900Y883500D01*
X1004192D01*
X1004483Y883583D01*
X1004733Y883708D01*
X1004942Y883875D01*
G01X1007000Y883500D02*
Y886000D01*
X1006500Y885500D01*
G01Y883500D02*
X1007500D01*
G01X1010100Y886000D02*
X1009767Y885917D01*
X1009517Y885708D01*
X1009350Y885458D01*
X1009225Y885125D01*
X1009183Y884750D01*
X1009225Y884375D01*
X1009350Y884042D01*
X1009517Y883792D01*
X1009767Y883583D01*
X1010100Y883500D01*
X1010433Y883583D01*
X1010683Y883792D01*
X1010850Y884042D01*
X1010975Y884375D01*
X1011017Y884750D01*
X1010975Y885125D01*
X1010850Y885458D01*
X1010683Y885708D01*
X1010433Y885917D01*
X1010100Y886000D01*
G01X1013200D02*
X1012867Y885917D01*
X1012617Y885708D01*
X1012450Y885458D01*
X1012325Y885125D01*
X1012283Y884750D01*
X1012325Y884375D01*
X1012450Y884042D01*
X1012617Y883792D01*
X1012867Y883583D01*
X1013200Y883500D01*
X1013533Y883583D01*
X1013783Y883792D01*
X1013950Y884042D01*
X1014075Y884375D01*
X1014117Y884750D01*
X1014075Y885125D01*
X1013950Y885458D01*
X1013783Y885708D01*
X1013533Y885917D01*
X1013200Y886000D01*
G01X996017Y906000D02*
Y908500D01*
X997017D01*
X997350Y908375D01*
X997600Y908083D01*
X997683Y907750D01*
X997600Y907417D01*
X997392Y907167D01*
X997017Y907042D01*
X996017D01*
G01X999117Y906000D02*
Y908500D01*
X1000158D01*
X1000492Y908375D01*
X1000700Y908208D01*
X1000783Y907875D01*
X1000700Y907542D01*
X1000450Y907333D01*
X1000158Y907208D01*
X999117D01*
G01X1000158D02*
X1000783Y906000D01*
G01X1003050D02*
X1003342Y906042D01*
X1003675Y906167D01*
X1003883Y906375D01*
X1003967Y906667D01*
X1003883Y906958D01*
X1003633Y907208D01*
X1003258Y907333D01*
X1002842D01*
X1002592Y907417D01*
X1002383Y907625D01*
X1002300Y907917D01*
X1002425Y908208D01*
X1002717Y908417D01*
X1003050Y908500D01*
X1003383Y908417D01*
X1003675Y908208D01*
X1003800Y907917D01*
X1003717Y907625D01*
X1003508Y907417D01*
X1003258Y907333D01*
X1002842D01*
X1002467Y907208D01*
X1002217Y906958D01*
X1002133Y906667D01*
X1002217Y906375D01*
X1002425Y906167D01*
X1002758Y906042D01*
X1003050Y906000D01*
G01X1006150D02*
X1006442Y906042D01*
X1006775Y906167D01*
X1006983Y906375D01*
X1007067Y906667D01*
X1006983Y906958D01*
X1006733Y907208D01*
X1006358Y907333D01*
X1005942D01*
X1005692Y907417D01*
X1005483Y907625D01*
X1005400Y907917D01*
X1005525Y908208D01*
X1005817Y908417D01*
X1006150Y908500D01*
X1006483Y908417D01*
X1006775Y908208D01*
X1006900Y907917D01*
X1006817Y907625D01*
X1006608Y907417D01*
X1006358Y907333D01*
X1005942D01*
X1005567Y907208D01*
X1005317Y906958D01*
X1005233Y906667D01*
X1005317Y906375D01*
X1005525Y906167D01*
X1005858Y906042D01*
X1006150Y906000D01*
G01X996233Y901468D02*
Y903968D01*
X997274D01*
X997608Y903843D01*
X997816Y903676D01*
X997899Y903343D01*
X997816Y903010D01*
X997566Y902801D01*
X997274Y902676D01*
X996233D01*
G01X997274D02*
X997899Y901468D01*
G01X1000666D02*
Y903968D01*
X999124Y902176D01*
X1001208D01*
G01X1002349Y901843D02*
X1002599Y901635D01*
X1002891Y901510D01*
X1003266Y901468D01*
X1003641Y901551D01*
X1003933Y901718D01*
X1004141Y902010D01*
X1004183Y902343D01*
X1004099Y902676D01*
X1003891Y902885D01*
X1003599Y903051D01*
X1003308Y903093D01*
X1003016Y903051D01*
X1002641Y902885D01*
X1002766Y903968D01*
X1003891D01*
G01X1006283Y901468D02*
X1006366Y902010D01*
X1006491Y902468D01*
X1006658Y902885D01*
X1006866Y903343D01*
X1007199Y903968D01*
X1005533D01*
G01X994683Y897468D02*
Y899968D01*
X995683D01*
X996016Y899843D01*
X996266Y899551D01*
X996349Y899218D01*
X996266Y898885D01*
X996058Y898635D01*
X995683Y898510D01*
X994683D01*
G01X999533Y899760D02*
X999283Y899885D01*
X998991Y899968D01*
X998658D01*
X998283Y899843D01*
X997991Y899635D01*
X997783Y899385D01*
X997616Y898968D01*
X997574Y898593D01*
X997658Y898218D01*
X997783Y897968D01*
X998033Y897718D01*
X998324Y897551D01*
X998616Y897468D01*
X998908D01*
X999199Y897551D01*
X999449Y897676D01*
X999658Y897843D01*
G01X1001716Y897468D02*
Y899968D01*
X1001216Y899468D01*
G01Y897468D02*
X1002216D01*
G01X1004816Y899968D02*
X1004483Y899885D01*
X1004233Y899676D01*
X1004066Y899426D01*
X1003941Y899093D01*
X1003899Y898718D01*
X1003941Y898343D01*
X1004066Y898010D01*
X1004233Y897760D01*
X1004483Y897551D01*
X1004816Y897468D01*
X1005149Y897551D01*
X1005399Y897760D01*
X1005566Y898010D01*
X1005691Y898343D01*
X1005733Y898718D01*
X1005691Y899093D01*
X1005566Y899426D01*
X1005399Y899676D01*
X1005149Y899885D01*
X1004816Y899968D01*
G01X1007916Y897468D02*
Y899968D01*
X1007416Y899468D01*
G01Y897468D02*
X1008416D01*
G01X1021750Y73350D02*
X1012250D01*
Y55650D01*
X1021750D01*
Y73350D01*
G01X1006500Y52850D02*
X1009000D01*
G01X1006500Y51892D02*
Y53808D01*
G01X1006708Y56867D02*
X1006583Y56617D01*
X1006500Y56325D01*
Y55992D01*
X1006625Y55617D01*
X1006833Y55325D01*
X1007083Y55117D01*
X1007500Y54950D01*
X1007875Y54908D01*
X1008250Y54992D01*
X1008500Y55117D01*
X1008750Y55367D01*
X1008917Y55658D01*
X1009000Y55950D01*
Y56242D01*
X1008917Y56533D01*
X1008792Y56783D01*
X1008625Y56992D01*
G01X1009000Y59050D02*
X1006500D01*
X1007000Y58550D01*
G01X1009000D02*
Y59550D01*
G01Y62150D02*
X1006500D01*
X1007000Y61650D01*
G01X1009000D02*
Y62650D01*
G01X1010700Y65900D02*
Y73100D01*
G01X1009000Y107517D02*
X1006500D01*
Y108517D01*
X1006625Y108850D01*
X1006917Y109100D01*
X1007250Y109183D01*
X1007583Y109100D01*
X1007833Y108892D01*
X1007958Y108517D01*
Y107517D01*
G01X1009000Y110617D02*
X1006500D01*
Y111658D01*
X1006625Y111992D01*
X1006792Y112200D01*
X1007125Y112283D01*
X1007458Y112200D01*
X1007667Y111950D01*
X1007792Y111658D01*
Y110617D01*
G01Y111658D02*
X1009000Y112283D01*
G01Y115050D02*
X1006500D01*
X1008292Y113508D01*
Y115592D01*
G01X1006500Y117650D02*
X1006583Y117317D01*
X1006792Y117067D01*
X1007042Y116900D01*
X1007375Y116775D01*
X1007750Y116733D01*
X1008125Y116775D01*
X1008458Y116900D01*
X1008708Y117067D01*
X1008917Y117317D01*
X1009000Y117650D01*
X1008917Y117983D01*
X1008708Y118233D01*
X1008458Y118400D01*
X1008125Y118525D01*
X1007750Y118567D01*
X1007375Y118525D01*
X1007042Y118400D01*
X1006792Y118233D01*
X1006583Y117983D01*
X1006500Y117650D01*
G01X1012017Y110000D02*
Y112500D01*
X1013017D01*
X1013350Y112375D01*
X1013600Y112083D01*
X1013683Y111750D01*
X1013600Y111417D01*
X1013392Y111167D01*
X1013017Y111042D01*
X1012017D01*
G01X1015117Y110000D02*
Y112500D01*
X1016158D01*
X1016492Y112375D01*
X1016700Y112208D01*
X1016783Y111875D01*
X1016700Y111542D01*
X1016450Y111333D01*
X1016158Y111208D01*
X1015117D01*
G01X1016158D02*
X1016783Y110000D01*
G01X1018133Y110375D02*
X1018383Y110167D01*
X1018675Y110042D01*
X1019050Y110000D01*
X1019425Y110083D01*
X1019717Y110250D01*
X1019925Y110542D01*
X1019967Y110875D01*
X1019883Y111208D01*
X1019675Y111417D01*
X1019383Y111583D01*
X1019092Y111625D01*
X1018800Y111583D01*
X1018425Y111417D01*
X1018550Y112500D01*
X1019675D01*
G01X1022650Y110000D02*
Y112500D01*
X1021108Y110708D01*
X1023192D01*
G01X1012017Y119000D02*
Y121500D01*
X1013017D01*
X1013350Y121375D01*
X1013600Y121083D01*
X1013683Y120750D01*
X1013600Y120417D01*
X1013392Y120167D01*
X1013017Y120042D01*
X1012017D01*
G01X1015117Y119000D02*
Y121500D01*
X1016158D01*
X1016492Y121375D01*
X1016700Y121208D01*
X1016783Y120875D01*
X1016700Y120542D01*
X1016450Y120333D01*
X1016158Y120208D01*
X1015117D01*
G01X1016158D02*
X1016783Y119000D01*
G01X1018133Y119375D02*
X1018383Y119167D01*
X1018675Y119042D01*
X1019050Y119000D01*
X1019425Y119083D01*
X1019717Y119250D01*
X1019925Y119542D01*
X1019967Y119875D01*
X1019883Y120208D01*
X1019675Y120417D01*
X1019383Y120583D01*
X1019092Y120625D01*
X1018800Y120583D01*
X1018425Y120417D01*
X1018550Y121500D01*
X1019675D01*
G01X1021358Y120042D02*
X1021650Y120333D01*
X1021900Y120500D01*
X1022233Y120583D01*
X1022525Y120500D01*
X1022733Y120333D01*
X1022900Y120083D01*
X1022942Y119792D01*
X1022900Y119542D01*
X1022733Y119292D01*
X1022483Y119083D01*
X1022192Y119000D01*
X1021858Y119083D01*
X1021567Y119333D01*
X1021400Y119708D01*
X1021358Y120125D01*
X1021442Y120667D01*
X1021567Y120958D01*
X1021775Y121250D01*
X1022067Y121458D01*
X1022358Y121500D01*
X1022650Y121417D01*
X1022858Y121208D01*
G01X1012017Y114500D02*
Y117000D01*
X1013017D01*
X1013350Y116875D01*
X1013600Y116583D01*
X1013683Y116250D01*
X1013600Y115917D01*
X1013392Y115667D01*
X1013017Y115542D01*
X1012017D01*
G01X1016867Y116792D02*
X1016617Y116917D01*
X1016325Y117000D01*
X1015992D01*
X1015617Y116875D01*
X1015325Y116667D01*
X1015117Y116417D01*
X1014950Y116000D01*
X1014908Y115625D01*
X1014992Y115250D01*
X1015117Y115000D01*
X1015367Y114750D01*
X1015658Y114583D01*
X1015950Y114500D01*
X1016242D01*
X1016533Y114583D01*
X1016783Y114708D01*
X1016992Y114875D01*
G01X1018133D02*
X1018383Y114667D01*
X1018675Y114542D01*
X1019050Y114500D01*
X1019425Y114583D01*
X1019717Y114750D01*
X1019925Y115042D01*
X1019967Y115375D01*
X1019883Y115708D01*
X1019675Y115917D01*
X1019383Y116083D01*
X1019092Y116125D01*
X1018800Y116083D01*
X1018425Y115917D01*
X1018550Y117000D01*
X1019675D01*
G01X1021233Y115000D02*
X1021483Y114708D01*
X1021817Y114542D01*
X1022192Y114500D01*
X1022525Y114542D01*
X1022858Y114750D01*
X1023067Y115000D01*
X1023108Y115250D01*
X1023025Y115542D01*
X1022733Y115750D01*
X1022442Y115833D01*
X1022067D01*
G01X1022442D02*
X1022692Y115958D01*
X1022900Y116167D01*
X1022983Y116417D01*
X1022900Y116667D01*
X1022692Y116875D01*
X1022317Y117000D01*
X1021942Y116958D01*
X1021567Y116792D01*
G01X1014500Y139017D02*
X1012000D01*
Y140017D01*
X1012125Y140350D01*
X1012417Y140600D01*
X1012750Y140683D01*
X1013083Y140600D01*
X1013333Y140392D01*
X1013458Y140017D01*
Y139017D01*
G01X1014500Y142117D02*
X1012000D01*
Y143158D01*
X1012125Y143492D01*
X1012292Y143700D01*
X1012625Y143783D01*
X1012958Y143700D01*
X1013167Y143450D01*
X1013292Y143158D01*
Y142117D01*
G01Y143158D02*
X1014500Y143783D01*
G01Y146550D02*
X1012000D01*
X1013792Y145008D01*
Y147092D01*
G01X1014500Y149067D02*
X1013958Y149150D01*
X1013500Y149275D01*
X1013083Y149442D01*
X1012625Y149650D01*
X1012000Y149983D01*
Y148317D01*
G01X1006517Y130000D02*
Y132500D01*
X1007517D01*
X1007850Y132375D01*
X1008100Y132083D01*
X1008183Y131750D01*
X1008100Y131417D01*
X1007892Y131167D01*
X1007517Y131042D01*
X1006517D01*
G01X1009617Y130000D02*
Y132500D01*
X1010658D01*
X1010992Y132375D01*
X1011200Y132208D01*
X1011283Y131875D01*
X1011200Y131542D01*
X1010950Y131333D01*
X1010658Y131208D01*
X1009617D01*
G01X1010658D02*
X1011283Y130000D01*
G01X1014050D02*
Y132500D01*
X1012508Y130708D01*
X1014592D01*
G01X1017150Y130000D02*
Y132500D01*
X1015608Y130708D01*
X1017692D01*
G01X1006517Y134000D02*
Y136500D01*
X1007517D01*
X1007850Y136375D01*
X1008100Y136083D01*
X1008183Y135750D01*
X1008100Y135417D01*
X1007892Y135167D01*
X1007517Y135042D01*
X1006517D01*
G01X1011367Y136292D02*
X1011117Y136417D01*
X1010825Y136500D01*
X1010492D01*
X1010117Y136375D01*
X1009825Y136167D01*
X1009617Y135917D01*
X1009450Y135500D01*
X1009408Y135125D01*
X1009492Y134750D01*
X1009617Y134500D01*
X1009867Y134250D01*
X1010158Y134083D01*
X1010450Y134000D01*
X1010742D01*
X1011033Y134083D01*
X1011283Y134208D01*
X1011492Y134375D01*
G01X1012633D02*
X1012883Y134167D01*
X1013175Y134042D01*
X1013550Y134000D01*
X1013925Y134083D01*
X1014217Y134250D01*
X1014425Y134542D01*
X1014467Y134875D01*
X1014383Y135208D01*
X1014175Y135417D01*
X1013883Y135583D01*
X1013592Y135625D01*
X1013300Y135583D01*
X1012925Y135417D01*
X1013050Y136500D01*
X1014175D01*
G01X1016650Y134000D02*
Y136500D01*
X1016150Y136000D01*
G01Y134000D02*
X1017150D01*
G01X1019000Y141517D02*
X1016500D01*
Y142517D01*
X1016625Y142850D01*
X1016917Y143100D01*
X1017250Y143183D01*
X1017583Y143100D01*
X1017833Y142892D01*
X1017958Y142517D01*
Y141517D01*
G01X1019000Y144617D02*
X1016500D01*
Y145658D01*
X1016625Y145992D01*
X1016792Y146200D01*
X1017125Y146283D01*
X1017458Y146200D01*
X1017667Y145950D01*
X1017792Y145658D01*
Y144617D01*
G01Y145658D02*
X1019000Y146283D01*
G01X1018625Y147633D02*
X1018833Y147883D01*
X1018958Y148175D01*
X1019000Y148550D01*
X1018917Y148925D01*
X1018750Y149217D01*
X1018458Y149425D01*
X1018125Y149467D01*
X1017792Y149383D01*
X1017583Y149175D01*
X1017417Y148883D01*
X1017375Y148592D01*
X1017417Y148300D01*
X1017583Y147925D01*
X1016500Y148050D01*
Y149175D01*
G01X1018500Y150733D02*
X1018792Y150983D01*
X1018958Y151317D01*
X1019000Y151692D01*
X1018958Y152025D01*
X1018750Y152358D01*
X1018500Y152567D01*
X1018250Y152608D01*
X1017958Y152525D01*
X1017750Y152233D01*
X1017667Y151942D01*
Y151567D01*
G01Y151942D02*
X1017542Y152192D01*
X1017333Y152400D01*
X1017083Y152483D01*
X1016833Y152400D01*
X1016625Y152192D01*
X1016500Y151817D01*
X1016542Y151442D01*
X1016708Y151067D01*
G01X1018000Y156067D02*
X1015500D01*
Y157067D01*
X1015625Y157400D01*
X1015917Y157650D01*
X1016250Y157733D01*
X1016583Y157650D01*
X1016833Y157442D01*
X1016958Y157067D01*
Y156067D01*
G01X1015500Y159083D02*
X1017292D01*
X1017667Y159250D01*
X1017917Y159583D01*
X1018000Y160000D01*
X1017917Y160417D01*
X1017667Y160750D01*
X1017292Y160917D01*
X1015500D01*
G01X1017500Y162183D02*
X1017792Y162433D01*
X1017958Y162767D01*
X1018000Y163142D01*
X1017958Y163475D01*
X1017750Y163808D01*
X1017500Y164017D01*
X1017250Y164058D01*
X1016958Y163975D01*
X1016750Y163683D01*
X1016667Y163392D01*
Y163017D01*
G01Y163392D02*
X1016542Y163642D01*
X1016333Y163850D01*
X1016083Y163933D01*
X1015833Y163850D01*
X1015625Y163642D01*
X1015500Y163267D01*
X1015542Y162892D01*
X1015708Y162517D01*
G01X1012017Y168000D02*
Y170500D01*
X1013017D01*
X1013350Y170375D01*
X1013600Y170083D01*
X1013683Y169750D01*
X1013600Y169417D01*
X1013392Y169167D01*
X1013017Y169042D01*
X1012017D01*
G01X1015117Y168000D02*
Y170500D01*
X1016158D01*
X1016492Y170375D01*
X1016700Y170208D01*
X1016783Y169875D01*
X1016700Y169542D01*
X1016450Y169333D01*
X1016158Y169208D01*
X1015117D01*
G01X1016158D02*
X1016783Y168000D01*
G01X1018133Y168375D02*
X1018383Y168167D01*
X1018675Y168042D01*
X1019050Y168000D01*
X1019425Y168083D01*
X1019717Y168250D01*
X1019925Y168542D01*
X1019967Y168875D01*
X1019883Y169208D01*
X1019675Y169417D01*
X1019383Y169583D01*
X1019092Y169625D01*
X1018800Y169583D01*
X1018425Y169417D01*
X1018550Y170500D01*
X1019675D01*
G01X1021358Y170083D02*
X1021608Y170333D01*
X1021900Y170458D01*
X1022233Y170500D01*
X1022650Y170417D01*
X1022942Y170208D01*
X1023025Y169958D01*
X1022983Y169708D01*
X1022817Y169500D01*
X1021983Y169083D01*
X1021608Y168792D01*
X1021358Y168375D01*
X1021275Y168000D01*
X1023025D01*
G01X1012017Y172500D02*
Y175000D01*
X1013017D01*
X1013350Y174875D01*
X1013600Y174583D01*
X1013683Y174250D01*
X1013600Y173917D01*
X1013392Y173667D01*
X1013017Y173542D01*
X1012017D01*
G01X1015117Y172500D02*
Y175000D01*
X1016158D01*
X1016492Y174875D01*
X1016700Y174708D01*
X1016783Y174375D01*
X1016700Y174042D01*
X1016450Y173833D01*
X1016158Y173708D01*
X1015117D01*
G01X1016158D02*
X1016783Y172500D01*
G01X1018133Y172875D02*
X1018383Y172667D01*
X1018675Y172542D01*
X1019050Y172500D01*
X1019425Y172583D01*
X1019717Y172750D01*
X1019925Y173042D01*
X1019967Y173375D01*
X1019883Y173708D01*
X1019675Y173917D01*
X1019383Y174083D01*
X1019092Y174125D01*
X1018800Y174083D01*
X1018425Y173917D01*
X1018550Y175000D01*
X1019675D01*
G01X1021233Y172875D02*
X1021483Y172667D01*
X1021775Y172542D01*
X1022150Y172500D01*
X1022525Y172583D01*
X1022817Y172750D01*
X1023025Y173042D01*
X1023067Y173375D01*
X1022983Y173708D01*
X1022775Y173917D01*
X1022483Y174083D01*
X1022192Y174125D01*
X1021900Y174083D01*
X1021525Y173917D01*
X1021650Y175000D01*
X1022775D01*
G01X1005274Y196378D02*
X1007074Y198478D01*
X1009274Y196378D01*
G01X1003975Y220833D02*
X1004308Y220625D01*
X1004683Y220500D01*
X1005017D01*
X1005350Y220625D01*
X1005600Y220833D01*
X1005725Y221125D01*
X1005642Y221417D01*
X1005433Y221667D01*
X1005058Y221833D01*
X1004558Y221917D01*
X1004267Y222083D01*
X1004142Y222375D01*
X1004225Y222667D01*
X1004433Y222875D01*
X1004725Y223000D01*
X1005017D01*
X1005308Y222917D01*
X1005558Y222708D01*
G01X1007033Y223000D02*
Y221208D01*
X1007200Y220833D01*
X1007533Y220583D01*
X1007950Y220500D01*
X1008367Y220583D01*
X1008700Y220833D01*
X1008867Y221208D01*
Y223000D01*
G01X1010258Y221542D02*
X1010550Y221833D01*
X1010800Y222000D01*
X1011133Y222083D01*
X1011425Y222000D01*
X1011633Y221833D01*
X1011800Y221583D01*
X1011842Y221292D01*
X1011800Y221042D01*
X1011633Y220792D01*
X1011383Y220583D01*
X1011092Y220500D01*
X1010758Y220583D01*
X1010467Y220833D01*
X1010300Y221208D01*
X1010258Y221625D01*
X1010342Y222167D01*
X1010467Y222458D01*
X1010675Y222750D01*
X1010967Y222958D01*
X1011258Y223000D01*
X1011550Y222917D01*
X1011758Y222708D01*
G01X1014150Y220500D02*
Y223000D01*
X1013650Y222500D01*
G01Y220500D02*
X1014650D01*
G01X1011500Y431967D02*
X1009000D01*
Y433008D01*
X1009125Y433342D01*
X1009292Y433550D01*
X1009625Y433633D01*
X1009958Y433550D01*
X1010167Y433300D01*
X1010292Y433008D01*
Y431967D01*
G01Y433008D02*
X1011500Y433633D01*
G01Y435817D02*
X1010958Y435900D01*
X1010500Y436025D01*
X1010083Y436192D01*
X1009625Y436400D01*
X1009000Y436733D01*
Y435067D01*
G01X1011208Y438292D02*
X1011417Y438583D01*
X1011500Y438917D01*
X1011417Y439250D01*
X1011167Y439542D01*
X1010792Y439750D01*
X1010417Y439833D01*
X1009958D01*
X1009583Y439750D01*
X1009250Y439542D01*
X1009083Y439292D01*
X1009000Y439000D01*
X1009083Y438667D01*
X1009250Y438417D01*
X1009500Y438250D01*
X1009833Y438167D01*
X1010125Y438250D01*
X1010417Y438458D01*
X1010583Y438708D01*
X1010625Y439000D01*
X1010542Y439333D01*
X1010333Y439583D01*
X1009958Y439833D01*
G01X1009000Y442100D02*
X1009083Y441767D01*
X1009292Y441517D01*
X1009542Y441350D01*
X1009875Y441225D01*
X1010250Y441183D01*
X1010625Y441225D01*
X1010958Y441350D01*
X1011208Y441517D01*
X1011417Y441767D01*
X1011500Y442100D01*
X1011417Y442433D01*
X1011208Y442683D01*
X1010958Y442850D01*
X1010625Y442975D01*
X1010250Y443017D01*
X1009875Y442975D01*
X1009542Y442850D01*
X1009292Y442683D01*
X1009083Y442433D01*
X1009000Y442100D01*
G01X1011500Y445200D02*
X1009000D01*
X1009500Y444700D01*
G01X1011500D02*
Y445700D01*
G01X1012500Y457200D02*
X1008500D01*
Y449800D01*
G01X1017000Y462983D02*
X1018792D01*
X1019167Y463150D01*
X1019417Y463483D01*
X1019500Y463900D01*
X1019417Y464317D01*
X1019167Y464650D01*
X1018792Y464817D01*
X1017000D01*
G01X1019500Y467500D02*
X1017000D01*
X1018792Y465958D01*
Y468042D01*
G01X1018458Y469308D02*
X1018167Y469600D01*
X1018000Y469850D01*
X1017917Y470183D01*
X1018000Y470475D01*
X1018167Y470683D01*
X1018417Y470850D01*
X1018708Y470892D01*
X1018958Y470850D01*
X1019208Y470683D01*
X1019417Y470433D01*
X1019500Y470142D01*
X1019417Y469808D01*
X1019167Y469517D01*
X1018792Y469350D01*
X1018375Y469308D01*
X1017833Y469392D01*
X1017542Y469517D01*
X1017250Y469725D01*
X1017042Y470017D01*
X1017000Y470308D01*
X1017083Y470600D01*
X1017292Y470808D01*
G01X1013700Y472000D02*
Y462000D01*
G01X1016767Y481792D02*
X1016517Y481917D01*
X1016225Y482000D01*
X1015892D01*
X1015517Y481875D01*
X1015225Y481667D01*
X1015017Y481417D01*
X1014850Y481000D01*
X1014808Y480625D01*
X1014892Y480250D01*
X1015017Y480000D01*
X1015267Y479750D01*
X1015558Y479583D01*
X1015850Y479500D01*
X1016142D01*
X1016433Y479583D01*
X1016683Y479708D01*
X1016892Y479875D01*
G01X1018033Y480000D02*
X1018283Y479708D01*
X1018617Y479542D01*
X1018992Y479500D01*
X1019325Y479542D01*
X1019658Y479750D01*
X1019867Y480000D01*
X1019908Y480250D01*
X1019825Y480542D01*
X1019533Y480750D01*
X1019242Y480833D01*
X1018867D01*
G01X1019242D02*
X1019492Y480958D01*
X1019700Y481167D01*
X1019783Y481417D01*
X1019700Y481667D01*
X1019492Y481875D01*
X1019117Y482000D01*
X1018742Y481958D01*
X1018367Y481792D01*
G01X1022550Y479500D02*
Y482000D01*
X1021008Y480208D01*
X1023092D01*
G01X1025150Y482000D02*
X1024817Y481917D01*
X1024567Y481708D01*
X1024400Y481458D01*
X1024275Y481125D01*
X1024233Y480750D01*
X1024275Y480375D01*
X1024400Y480042D01*
X1024567Y479792D01*
X1024817Y479583D01*
X1025150Y479500D01*
X1025483Y479583D01*
X1025733Y479792D01*
X1025900Y480042D01*
X1026025Y480375D01*
X1026067Y480750D01*
X1026025Y481125D01*
X1025900Y481458D01*
X1025733Y481708D01*
X1025483Y481917D01*
X1025150Y482000D01*
G01X1013000Y502200D02*
X1009000D01*
Y494800D01*
G01X1007000Y520000D02*
X1005800Y518800D01*
G01X1007000Y520000D02*
X1005800Y521200D01*
G01Y522300D02*
Y517700D01*
G01X1016700D02*
X1005800D01*
G01X1016700Y522300D02*
Y517700D01*
G01X1005800Y522300D02*
X1016700D01*
G01X1019000Y542200D02*
X1015000D01*
Y534800D01*
G01Y542200D02*
X1011000D01*
Y534800D01*
G01X1017216Y851985D02*
X1014716D01*
Y852985D01*
X1014841Y853318D01*
X1015133Y853568D01*
X1015466Y853651D01*
X1015799Y853568D01*
X1016049Y853360D01*
X1016174Y852985D01*
Y851985D01*
G01X1017216Y855085D02*
X1014716D01*
Y856126D01*
X1014841Y856460D01*
X1015008Y856668D01*
X1015341Y856751D01*
X1015674Y856668D01*
X1015883Y856418D01*
X1016008Y856126D01*
Y855085D01*
G01Y856126D02*
X1017216Y856751D01*
G01Y859018D02*
X1017174Y859310D01*
X1017049Y859643D01*
X1016841Y859851D01*
X1016549Y859935D01*
X1016258Y859851D01*
X1016008Y859601D01*
X1015883Y859226D01*
Y858810D01*
X1015799Y858560D01*
X1015591Y858351D01*
X1015299Y858268D01*
X1015008Y858393D01*
X1014799Y858685D01*
X1014716Y859018D01*
X1014799Y859351D01*
X1015008Y859643D01*
X1015299Y859768D01*
X1015591Y859685D01*
X1015799Y859476D01*
X1015883Y859226D01*
Y858810D01*
X1016008Y858435D01*
X1016258Y858185D01*
X1016549Y858101D01*
X1016841Y858185D01*
X1017049Y858393D01*
X1017174Y858726D01*
X1017216Y859018D01*
G01X1016174Y861326D02*
X1015883Y861618D01*
X1015716Y861868D01*
X1015633Y862201D01*
X1015716Y862493D01*
X1015883Y862701D01*
X1016133Y862868D01*
X1016424Y862910D01*
X1016674Y862868D01*
X1016924Y862701D01*
X1017133Y862451D01*
X1017216Y862160D01*
X1017133Y861826D01*
X1016883Y861535D01*
X1016508Y861368D01*
X1016091Y861326D01*
X1015549Y861410D01*
X1015258Y861535D01*
X1014966Y861743D01*
X1014758Y862035D01*
X1014716Y862326D01*
X1014799Y862618D01*
X1015008Y862826D01*
G01X1013216Y851985D02*
X1010716D01*
Y852985D01*
X1010841Y853318D01*
X1011133Y853568D01*
X1011466Y853651D01*
X1011799Y853568D01*
X1012049Y853360D01*
X1012174Y852985D01*
Y851985D01*
G01X1010924Y856835D02*
X1010799Y856585D01*
X1010716Y856293D01*
Y855960D01*
X1010841Y855585D01*
X1011049Y855293D01*
X1011299Y855085D01*
X1011716Y854918D01*
X1012091Y854876D01*
X1012466Y854960D01*
X1012716Y855085D01*
X1012966Y855335D01*
X1013133Y855626D01*
X1013216Y855918D01*
Y856210D01*
X1013133Y856501D01*
X1013008Y856751D01*
X1012841Y856960D01*
G01X1012924Y858310D02*
X1013133Y858601D01*
X1013216Y858935D01*
X1013133Y859268D01*
X1012883Y859560D01*
X1012508Y859768D01*
X1012133Y859851D01*
X1011674D01*
X1011299Y859768D01*
X1010966Y859560D01*
X1010799Y859310D01*
X1010716Y859018D01*
X1010799Y858685D01*
X1010966Y858435D01*
X1011216Y858268D01*
X1011549Y858185D01*
X1011841Y858268D01*
X1012133Y858476D01*
X1012299Y858726D01*
X1012341Y859018D01*
X1012258Y859351D01*
X1012049Y859601D01*
X1011674Y859851D01*
G01X1012716Y861201D02*
X1013008Y861451D01*
X1013174Y861785D01*
X1013216Y862160D01*
X1013174Y862493D01*
X1012966Y862826D01*
X1012716Y863035D01*
X1012466Y863076D01*
X1012174Y862993D01*
X1011966Y862701D01*
X1011883Y862410D01*
Y862035D01*
G01Y862410D02*
X1011758Y862660D01*
X1011549Y862868D01*
X1011299Y862951D01*
X1011049Y862868D01*
X1010841Y862660D01*
X1010716Y862285D01*
X1010758Y861910D01*
X1010924Y861535D01*
G01X1010017Y865500D02*
Y868000D01*
X1011017D01*
X1011350Y867875D01*
X1011600Y867583D01*
X1011683Y867250D01*
X1011600Y866917D01*
X1011392Y866667D01*
X1011017Y866542D01*
X1010017D01*
G01X1013117Y865500D02*
Y868000D01*
X1014158D01*
X1014492Y867875D01*
X1014700Y867708D01*
X1014783Y867375D01*
X1014700Y867042D01*
X1014450Y866833D01*
X1014158Y866708D01*
X1013117D01*
G01X1014158D02*
X1014783Y865500D01*
G01X1017050D02*
X1017342Y865542D01*
X1017675Y865667D01*
X1017883Y865875D01*
X1017967Y866167D01*
X1017883Y866458D01*
X1017633Y866708D01*
X1017258Y866833D01*
X1016842D01*
X1016592Y866917D01*
X1016383Y867125D01*
X1016300Y867417D01*
X1016425Y867708D01*
X1016717Y867917D01*
X1017050Y868000D01*
X1017383Y867917D01*
X1017675Y867708D01*
X1017800Y867417D01*
X1017717Y867125D01*
X1017508Y866917D01*
X1017258Y866833D01*
X1016842D01*
X1016467Y866708D01*
X1016217Y866458D01*
X1016133Y866167D01*
X1016217Y865875D01*
X1016425Y865667D01*
X1016758Y865542D01*
X1017050Y865500D01*
G01X1020067D02*
X1020150Y866042D01*
X1020275Y866500D01*
X1020442Y866917D01*
X1020650Y867375D01*
X1020983Y868000D01*
X1019317D01*
G01X1009800Y909000D02*
Y905000D01*
X1017200D01*
G01X1010016Y904468D02*
Y900468D01*
X1017416D01*
G01X1024975Y47833D02*
X1025308Y47625D01*
X1025683Y47500D01*
X1026017D01*
X1026350Y47625D01*
X1026600Y47833D01*
X1026725Y48125D01*
X1026642Y48417D01*
X1026433Y48667D01*
X1026058Y48833D01*
X1025558Y48917D01*
X1025267Y49083D01*
X1025142Y49375D01*
X1025225Y49667D01*
X1025433Y49875D01*
X1025725Y50000D01*
X1026017D01*
X1026308Y49917D01*
X1026558Y49708D01*
G01X1028033Y47500D02*
Y50000D01*
G01X1029617D02*
X1028033Y48458D01*
G01X1029867Y47500D02*
X1028742Y49167D01*
G01X1032050Y50000D02*
Y47500D01*
G01X1031092Y50000D02*
X1033008D01*
G01X1035150Y47500D02*
Y50000D01*
X1034650Y49500D01*
G01Y47500D02*
X1035650D01*
G01X1023800Y61500D02*
Y55300D01*
X1036200D01*
Y61500D01*
G01Y67500D02*
Y73700D01*
X1023800D01*
Y67500D01*
G01X1020017Y83500D02*
Y86000D01*
X1021017D01*
X1021350Y85875D01*
X1021600Y85583D01*
X1021683Y85250D01*
X1021600Y84917D01*
X1021392Y84667D01*
X1021017Y84542D01*
X1020017D01*
G01X1024867Y85792D02*
X1024617Y85917D01*
X1024325Y86000D01*
X1023992D01*
X1023617Y85875D01*
X1023325Y85667D01*
X1023117Y85417D01*
X1022950Y85000D01*
X1022908Y84625D01*
X1022992Y84250D01*
X1023117Y84000D01*
X1023367Y83750D01*
X1023658Y83583D01*
X1023950Y83500D01*
X1024242D01*
X1024533Y83583D01*
X1024783Y83708D01*
X1024992Y83875D01*
G01X1026133D02*
X1026383Y83667D01*
X1026675Y83542D01*
X1027050Y83500D01*
X1027425Y83583D01*
X1027717Y83750D01*
X1027925Y84042D01*
X1027967Y84375D01*
X1027883Y84708D01*
X1027675Y84917D01*
X1027383Y85083D01*
X1027092Y85125D01*
X1026800Y85083D01*
X1026425Y84917D01*
X1026550Y86000D01*
X1027675D01*
G01X1030150Y83500D02*
X1030442Y83542D01*
X1030775Y83667D01*
X1030983Y83875D01*
X1031067Y84167D01*
X1030983Y84458D01*
X1030733Y84708D01*
X1030358Y84833D01*
X1029942D01*
X1029692Y84917D01*
X1029483Y85125D01*
X1029400Y85417D01*
X1029525Y85708D01*
X1029817Y85917D01*
X1030150Y86000D01*
X1030483Y85917D01*
X1030775Y85708D01*
X1030900Y85417D01*
X1030817Y85125D01*
X1030608Y84917D01*
X1030358Y84833D01*
X1029942D01*
X1029567Y84708D01*
X1029317Y84458D01*
X1029233Y84167D01*
X1029317Y83875D01*
X1029525Y83667D01*
X1029858Y83542D01*
X1030150Y83500D01*
G01X1034700Y84500D02*
X1040200D01*
G01X1034700Y76500D02*
Y84500D01*
G01X1040200Y76500D02*
X1034700D01*
G01X1020017Y88000D02*
Y90500D01*
X1021017D01*
X1021350Y90375D01*
X1021600Y90083D01*
X1021683Y89750D01*
X1021600Y89417D01*
X1021392Y89167D01*
X1021017Y89042D01*
X1020017D01*
G01X1024867Y90292D02*
X1024617Y90417D01*
X1024325Y90500D01*
X1023992D01*
X1023617Y90375D01*
X1023325Y90167D01*
X1023117Y89917D01*
X1022950Y89500D01*
X1022908Y89125D01*
X1022992Y88750D01*
X1023117Y88500D01*
X1023367Y88250D01*
X1023658Y88083D01*
X1023950Y88000D01*
X1024242D01*
X1024533Y88083D01*
X1024783Y88208D01*
X1024992Y88375D01*
G01X1026133D02*
X1026383Y88167D01*
X1026675Y88042D01*
X1027050Y88000D01*
X1027425Y88083D01*
X1027717Y88250D01*
X1027925Y88542D01*
X1027967Y88875D01*
X1027883Y89208D01*
X1027675Y89417D01*
X1027383Y89583D01*
X1027092Y89625D01*
X1026800Y89583D01*
X1026425Y89417D01*
X1026550Y90500D01*
X1027675D01*
G01X1029442Y88292D02*
X1029733Y88083D01*
X1030067Y88000D01*
X1030400Y88083D01*
X1030692Y88333D01*
X1030900Y88708D01*
X1030983Y89083D01*
Y89542D01*
X1030900Y89917D01*
X1030692Y90250D01*
X1030442Y90417D01*
X1030150Y90500D01*
X1029817Y90417D01*
X1029567Y90250D01*
X1029400Y90000D01*
X1029317Y89667D01*
X1029400Y89375D01*
X1029608Y89083D01*
X1029858Y88917D01*
X1030150Y88875D01*
X1030483Y88958D01*
X1030733Y89167D01*
X1030983Y89542D01*
G01X1034700Y85500D02*
Y93500D01*
G01X1040200Y85500D02*
X1034700D01*
G01X1020017Y92500D02*
Y95000D01*
X1021017D01*
X1021350Y94875D01*
X1021600Y94583D01*
X1021683Y94250D01*
X1021600Y93917D01*
X1021392Y93667D01*
X1021017Y93542D01*
X1020017D01*
G01X1024867Y94792D02*
X1024617Y94917D01*
X1024325Y95000D01*
X1023992D01*
X1023617Y94875D01*
X1023325Y94667D01*
X1023117Y94417D01*
X1022950Y94000D01*
X1022908Y93625D01*
X1022992Y93250D01*
X1023117Y93000D01*
X1023367Y92750D01*
X1023658Y92583D01*
X1023950Y92500D01*
X1024242D01*
X1024533Y92583D01*
X1024783Y92708D01*
X1024992Y92875D01*
G01X1026133D02*
X1026383Y92667D01*
X1026675Y92542D01*
X1027050Y92500D01*
X1027425Y92583D01*
X1027717Y92750D01*
X1027925Y93042D01*
X1027967Y93375D01*
X1027883Y93708D01*
X1027675Y93917D01*
X1027383Y94083D01*
X1027092Y94125D01*
X1026800Y94083D01*
X1026425Y93917D01*
X1026550Y95000D01*
X1027675D01*
G01X1030067Y92500D02*
X1030150Y93042D01*
X1030275Y93500D01*
X1030442Y93917D01*
X1030650Y94375D01*
X1030983Y95000D01*
X1029317D01*
G01X1034700Y102500D02*
X1040200D01*
G01X1034700Y94500D02*
Y102500D01*
G01X1040200Y94500D02*
X1034700D01*
G01Y93500D02*
X1040200D01*
G01X1020017Y102000D02*
Y104500D01*
X1021017D01*
X1021350Y104375D01*
X1021600Y104083D01*
X1021683Y103750D01*
X1021600Y103417D01*
X1021392Y103167D01*
X1021017Y103042D01*
X1020017D01*
G01X1024867Y104292D02*
X1024617Y104417D01*
X1024325Y104500D01*
X1023992D01*
X1023617Y104375D01*
X1023325Y104167D01*
X1023117Y103917D01*
X1022950Y103500D01*
X1022908Y103125D01*
X1022992Y102750D01*
X1023117Y102500D01*
X1023367Y102250D01*
X1023658Y102083D01*
X1023950Y102000D01*
X1024242D01*
X1024533Y102083D01*
X1024783Y102208D01*
X1024992Y102375D01*
G01X1026133D02*
X1026383Y102167D01*
X1026675Y102042D01*
X1027050Y102000D01*
X1027425Y102083D01*
X1027717Y102250D01*
X1027925Y102542D01*
X1027967Y102875D01*
X1027883Y103208D01*
X1027675Y103417D01*
X1027383Y103583D01*
X1027092Y103625D01*
X1026800Y103583D01*
X1026425Y103417D01*
X1026550Y104500D01*
X1027675D01*
G01X1029358Y103042D02*
X1029650Y103333D01*
X1029900Y103500D01*
X1030233Y103583D01*
X1030525Y103500D01*
X1030733Y103333D01*
X1030900Y103083D01*
X1030942Y102792D01*
X1030900Y102542D01*
X1030733Y102292D01*
X1030483Y102083D01*
X1030192Y102000D01*
X1029858Y102083D01*
X1029567Y102333D01*
X1029400Y102708D01*
X1029358Y103125D01*
X1029442Y103667D01*
X1029567Y103958D01*
X1029775Y104250D01*
X1030067Y104458D01*
X1030358Y104500D01*
X1030650Y104417D01*
X1030858Y104208D01*
G01X1020017Y97500D02*
Y100000D01*
X1021017D01*
X1021350Y99875D01*
X1021600Y99583D01*
X1021683Y99250D01*
X1021600Y98917D01*
X1021392Y98667D01*
X1021017Y98542D01*
X1020017D01*
G01X1024867Y99792D02*
X1024617Y99917D01*
X1024325Y100000D01*
X1023992D01*
X1023617Y99875D01*
X1023325Y99667D01*
X1023117Y99417D01*
X1022950Y99000D01*
X1022908Y98625D01*
X1022992Y98250D01*
X1023117Y98000D01*
X1023367Y97750D01*
X1023658Y97583D01*
X1023950Y97500D01*
X1024242D01*
X1024533Y97583D01*
X1024783Y97708D01*
X1024992Y97875D01*
G01X1026133D02*
X1026383Y97667D01*
X1026675Y97542D01*
X1027050Y97500D01*
X1027425Y97583D01*
X1027717Y97750D01*
X1027925Y98042D01*
X1027967Y98375D01*
X1027883Y98708D01*
X1027675Y98917D01*
X1027383Y99083D01*
X1027092Y99125D01*
X1026800Y99083D01*
X1026425Y98917D01*
X1026550Y100000D01*
X1027675D01*
G01X1029233Y97875D02*
X1029483Y97667D01*
X1029775Y97542D01*
X1030150Y97500D01*
X1030525Y97583D01*
X1030817Y97750D01*
X1031025Y98042D01*
X1031067Y98375D01*
X1030983Y98708D01*
X1030775Y98917D01*
X1030483Y99083D01*
X1030192Y99125D01*
X1029900Y99083D01*
X1029525Y98917D01*
X1029650Y100000D01*
X1030775D01*
G01X1031500Y126200D02*
X1027500D01*
Y118800D01*
G01X1043200Y117500D02*
Y121500D01*
X1035800D01*
G01X1043200Y126500D02*
Y130500D01*
X1035800D01*
G01X1027500Y138700D02*
X1023500D01*
Y131300D01*
G01X1027800Y130500D02*
Y126500D01*
X1035200D01*
G01Y131000D02*
Y135000D01*
X1027800D01*
G01X1029000Y143300D02*
X1033000D01*
Y150700D01*
G01X1040168Y169134D02*
X1035168D01*
Y164134D01*
G01X1023567Y160000D02*
Y162500D01*
X1024567D01*
X1024900Y162375D01*
X1025150Y162083D01*
X1025233Y161750D01*
X1025150Y161417D01*
X1024942Y161167D01*
X1024567Y161042D01*
X1023567D01*
G01X1027750Y161250D02*
X1028583D01*
Y160500D01*
X1028333Y160250D01*
X1028042Y160083D01*
X1027625Y160000D01*
X1027208Y160083D01*
X1026917Y160250D01*
X1026667Y160500D01*
X1026500Y160792D01*
X1026417Y161125D01*
Y161417D01*
X1026500Y161667D01*
X1026667Y161958D01*
X1026917Y162208D01*
X1027167Y162375D01*
X1027500Y162500D01*
X1027792D01*
X1028125Y162417D01*
X1028375Y162250D01*
G01X1031100Y160000D02*
Y162500D01*
X1029558Y160708D01*
X1031642D01*
G01X1024800Y175000D02*
Y171000D01*
X1032200D01*
G01X1024800Y170500D02*
Y166500D01*
X1032200D01*
G01X1038000Y183517D02*
X1035500D01*
Y184517D01*
X1035625Y184850D01*
X1035917Y185100D01*
X1036250Y185183D01*
X1036583Y185100D01*
X1036833Y184892D01*
X1036958Y184517D01*
Y183517D01*
G01X1038000Y186617D02*
X1035500D01*
Y187658D01*
X1035625Y187992D01*
X1035792Y188200D01*
X1036125Y188283D01*
X1036458Y188200D01*
X1036667Y187950D01*
X1036792Y187658D01*
Y186617D01*
G01Y187658D02*
X1038000Y188283D01*
G01X1037625Y189633D02*
X1037833Y189883D01*
X1037958Y190175D01*
X1038000Y190550D01*
X1037917Y190925D01*
X1037750Y191217D01*
X1037458Y191425D01*
X1037125Y191467D01*
X1036792Y191383D01*
X1036583Y191175D01*
X1036417Y190883D01*
X1036375Y190592D01*
X1036417Y190300D01*
X1036583Y189925D01*
X1035500Y190050D01*
Y191175D01*
G01Y193650D02*
X1035583Y193317D01*
X1035792Y193067D01*
X1036042Y192900D01*
X1036375Y192775D01*
X1036750Y192733D01*
X1037125Y192775D01*
X1037458Y192900D01*
X1037708Y193067D01*
X1037917Y193317D01*
X1038000Y193650D01*
X1037917Y193983D01*
X1037708Y194233D01*
X1037458Y194400D01*
X1037125Y194525D01*
X1036750Y194567D01*
X1036375Y194525D01*
X1036042Y194400D01*
X1035792Y194233D01*
X1035583Y193983D01*
X1035500Y193650D01*
G01X1033500Y183517D02*
X1031000D01*
Y184517D01*
X1031125Y184850D01*
X1031417Y185100D01*
X1031750Y185183D01*
X1032083Y185100D01*
X1032333Y184892D01*
X1032458Y184517D01*
Y183517D01*
G01X1033500Y186617D02*
X1031000D01*
Y187658D01*
X1031125Y187992D01*
X1031292Y188200D01*
X1031625Y188283D01*
X1031958Y188200D01*
X1032167Y187950D01*
X1032292Y187658D01*
Y186617D01*
G01Y187658D02*
X1033500Y188283D01*
G01X1033125Y189633D02*
X1033333Y189883D01*
X1033458Y190175D01*
X1033500Y190550D01*
X1033417Y190925D01*
X1033250Y191217D01*
X1032958Y191425D01*
X1032625Y191467D01*
X1032292Y191383D01*
X1032083Y191175D01*
X1031917Y190883D01*
X1031875Y190592D01*
X1031917Y190300D01*
X1032083Y189925D01*
X1031000Y190050D01*
Y191175D01*
G01X1033500Y193650D02*
X1031000D01*
X1031500Y193150D01*
G01X1033500D02*
Y194150D01*
G01X1037000Y180700D02*
X1033000D01*
Y173300D01*
G01X1026074Y201578D02*
Y197578D01*
X1033474D01*
G01X1026074Y206578D02*
Y202578D01*
X1033474D01*
G01Y212078D02*
Y216078D01*
X1026074D01*
G01X1022199Y217911D02*
X1022532Y217703D01*
X1022907Y217578D01*
X1023241D01*
X1023574Y217703D01*
X1023824Y217911D01*
X1023949Y218203D01*
X1023866Y218495D01*
X1023657Y218745D01*
X1023282Y218911D01*
X1022782Y218995D01*
X1022491Y219161D01*
X1022366Y219453D01*
X1022449Y219745D01*
X1022657Y219953D01*
X1022949Y220078D01*
X1023241D01*
X1023532Y219995D01*
X1023782Y219786D01*
G01X1025341Y217578D02*
Y220078D01*
X1026382D01*
X1026716Y219953D01*
X1026924Y219786D01*
X1027007Y219453D01*
X1026924Y219120D01*
X1026674Y218911D01*
X1026382Y218786D01*
X1025341D01*
G01X1026382D02*
X1027007Y217578D01*
G01X1029191D02*
X1029274Y218120D01*
X1029399Y218578D01*
X1029566Y218995D01*
X1029774Y219453D01*
X1030107Y220078D01*
X1028441D01*
G01X1032374Y217578D02*
Y220078D01*
X1031874Y219578D01*
G01Y217578D02*
X1032874D01*
G01X1034766Y217870D02*
X1035057Y217661D01*
X1035391Y217578D01*
X1035724Y217661D01*
X1036016Y217911D01*
X1036224Y218286D01*
X1036307Y218661D01*
Y219120D01*
X1036224Y219495D01*
X1036016Y219828D01*
X1035766Y219995D01*
X1035474Y220078D01*
X1035141Y219995D01*
X1034891Y219828D01*
X1034724Y219578D01*
X1034641Y219245D01*
X1034724Y218953D01*
X1034932Y218661D01*
X1035182Y218495D01*
X1035474Y218453D01*
X1035807Y218536D01*
X1036057Y218745D01*
X1036307Y219120D01*
G01X1026074Y211578D02*
Y207578D01*
X1033474D01*
G01X1022199Y232411D02*
X1022532Y232203D01*
X1022907Y232078D01*
X1023241D01*
X1023574Y232203D01*
X1023824Y232411D01*
X1023949Y232703D01*
X1023866Y232995D01*
X1023657Y233245D01*
X1023282Y233411D01*
X1022782Y233495D01*
X1022491Y233661D01*
X1022366Y233953D01*
X1022449Y234245D01*
X1022657Y234453D01*
X1022949Y234578D01*
X1023241D01*
X1023532Y234495D01*
X1023782Y234286D01*
G01X1025341Y232078D02*
Y234578D01*
X1026382D01*
X1026716Y234453D01*
X1026924Y234286D01*
X1027007Y233953D01*
X1026924Y233620D01*
X1026674Y233411D01*
X1026382Y233286D01*
X1025341D01*
G01X1026382D02*
X1027007Y232078D01*
G01X1029191D02*
X1029274Y232620D01*
X1029399Y233078D01*
X1029566Y233495D01*
X1029774Y233953D01*
X1030107Y234578D01*
X1028441D01*
G01X1032374Y232078D02*
Y234578D01*
X1031874Y234078D01*
G01Y232078D02*
X1032874D01*
G01X1035391D02*
X1035474Y232620D01*
X1035599Y233078D01*
X1035766Y233495D01*
X1035974Y233953D01*
X1036307Y234578D01*
X1034641D01*
G01X1022199Y222911D02*
X1022532Y222703D01*
X1022907Y222578D01*
X1023241D01*
X1023574Y222703D01*
X1023824Y222911D01*
X1023949Y223203D01*
X1023866Y223495D01*
X1023657Y223745D01*
X1023282Y223911D01*
X1022782Y223995D01*
X1022491Y224161D01*
X1022366Y224453D01*
X1022449Y224745D01*
X1022657Y224953D01*
X1022949Y225078D01*
X1023241D01*
X1023532Y224995D01*
X1023782Y224786D01*
G01X1025341Y222578D02*
Y225078D01*
X1026382D01*
X1026716Y224953D01*
X1026924Y224786D01*
X1027007Y224453D01*
X1026924Y224120D01*
X1026674Y223911D01*
X1026382Y223786D01*
X1025341D01*
G01X1026382D02*
X1027007Y222578D01*
G01X1029191D02*
X1029274Y223120D01*
X1029399Y223578D01*
X1029566Y223995D01*
X1029774Y224453D01*
X1030107Y225078D01*
X1028441D01*
G01X1031582Y224661D02*
X1031832Y224911D01*
X1032124Y225036D01*
X1032457Y225078D01*
X1032874Y224995D01*
X1033166Y224786D01*
X1033249Y224536D01*
X1033207Y224286D01*
X1033041Y224078D01*
X1032207Y223661D01*
X1031832Y223370D01*
X1031582Y222953D01*
X1031499Y222578D01*
X1033249D01*
G01X1035474Y225078D02*
X1035141Y224995D01*
X1034891Y224786D01*
X1034724Y224536D01*
X1034599Y224203D01*
X1034557Y223828D01*
X1034599Y223453D01*
X1034724Y223120D01*
X1034891Y222870D01*
X1035141Y222661D01*
X1035474Y222578D01*
X1035807Y222661D01*
X1036057Y222870D01*
X1036224Y223120D01*
X1036349Y223453D01*
X1036391Y223828D01*
X1036349Y224203D01*
X1036224Y224536D01*
X1036057Y224786D01*
X1035807Y224995D01*
X1035474Y225078D01*
G01X1022199Y227911D02*
X1022532Y227703D01*
X1022907Y227578D01*
X1023241D01*
X1023574Y227703D01*
X1023824Y227911D01*
X1023949Y228203D01*
X1023866Y228495D01*
X1023657Y228745D01*
X1023282Y228911D01*
X1022782Y228995D01*
X1022491Y229161D01*
X1022366Y229453D01*
X1022449Y229745D01*
X1022657Y229953D01*
X1022949Y230078D01*
X1023241D01*
X1023532Y229995D01*
X1023782Y229786D01*
G01X1025341Y227578D02*
Y230078D01*
X1026382D01*
X1026716Y229953D01*
X1026924Y229786D01*
X1027007Y229453D01*
X1026924Y229120D01*
X1026674Y228911D01*
X1026382Y228786D01*
X1025341D01*
G01X1026382D02*
X1027007Y227578D01*
G01X1029191D02*
X1029274Y228120D01*
X1029399Y228578D01*
X1029566Y228995D01*
X1029774Y229453D01*
X1030107Y230078D01*
X1028441D01*
G01X1031582Y229661D02*
X1031832Y229911D01*
X1032124Y230036D01*
X1032457Y230078D01*
X1032874Y229995D01*
X1033166Y229786D01*
X1033249Y229536D01*
X1033207Y229286D01*
X1033041Y229078D01*
X1032207Y228661D01*
X1031832Y228370D01*
X1031582Y227953D01*
X1031499Y227578D01*
X1033249D01*
G01X1035474D02*
Y230078D01*
X1034974Y229578D01*
G01Y227578D02*
X1035974D01*
G01X1025708Y268767D02*
X1025583Y268517D01*
X1025500Y268225D01*
Y267892D01*
X1025625Y267517D01*
X1025833Y267225D01*
X1026083Y267017D01*
X1026500Y266850D01*
X1026875Y266808D01*
X1027250Y266892D01*
X1027500Y267017D01*
X1027750Y267267D01*
X1027917Y267558D01*
X1028000Y267850D01*
Y268142D01*
X1027917Y268433D01*
X1027792Y268683D01*
X1027625Y268892D01*
G01X1025917Y270158D02*
X1025667Y270408D01*
X1025542Y270700D01*
X1025500Y271033D01*
X1025583Y271450D01*
X1025792Y271742D01*
X1026042Y271825D01*
X1026292Y271783D01*
X1026500Y271617D01*
X1026917Y270783D01*
X1027208Y270408D01*
X1027625Y270158D01*
X1028000Y270075D01*
Y271825D01*
G01X1027625Y273133D02*
X1027833Y273383D01*
X1027958Y273675D01*
X1028000Y274050D01*
X1027917Y274425D01*
X1027750Y274717D01*
X1027458Y274925D01*
X1027125Y274967D01*
X1026792Y274883D01*
X1026583Y274675D01*
X1026417Y274383D01*
X1026375Y274092D01*
X1026417Y273800D01*
X1026583Y273425D01*
X1025500Y273550D01*
Y274675D01*
G01X1028000Y277067D02*
X1027458Y277150D01*
X1027000Y277275D01*
X1026583Y277442D01*
X1026125Y277650D01*
X1025500Y277983D01*
Y276317D01*
G01X1033708Y268767D02*
X1033583Y268517D01*
X1033500Y268225D01*
Y267892D01*
X1033625Y267517D01*
X1033833Y267225D01*
X1034083Y267017D01*
X1034500Y266850D01*
X1034875Y266808D01*
X1035250Y266892D01*
X1035500Y267017D01*
X1035750Y267267D01*
X1035917Y267558D01*
X1036000Y267850D01*
Y268142D01*
X1035917Y268433D01*
X1035792Y268683D01*
X1035625Y268892D01*
G01X1035500Y270033D02*
X1035792Y270283D01*
X1035958Y270617D01*
X1036000Y270992D01*
X1035958Y271325D01*
X1035750Y271658D01*
X1035500Y271867D01*
X1035250Y271908D01*
X1034958Y271825D01*
X1034750Y271533D01*
X1034667Y271242D01*
Y270867D01*
G01Y271242D02*
X1034542Y271492D01*
X1034333Y271700D01*
X1034083Y271783D01*
X1033833Y271700D01*
X1033625Y271492D01*
X1033500Y271117D01*
X1033542Y270742D01*
X1033708Y270367D01*
G01X1033500Y274050D02*
X1033583Y273717D01*
X1033792Y273467D01*
X1034042Y273300D01*
X1034375Y273175D01*
X1034750Y273133D01*
X1035125Y273175D01*
X1035458Y273300D01*
X1035708Y273467D01*
X1035917Y273717D01*
X1036000Y274050D01*
X1035917Y274383D01*
X1035708Y274633D01*
X1035458Y274800D01*
X1035125Y274925D01*
X1034750Y274967D01*
X1034375Y274925D01*
X1034042Y274800D01*
X1033792Y274633D01*
X1033583Y274383D01*
X1033500Y274050D01*
G01X1036000Y277150D02*
X1035958Y277442D01*
X1035833Y277775D01*
X1035625Y277983D01*
X1035333Y278067D01*
X1035042Y277983D01*
X1034792Y277733D01*
X1034667Y277358D01*
Y276942D01*
X1034583Y276692D01*
X1034375Y276483D01*
X1034083Y276400D01*
X1033792Y276525D01*
X1033583Y276817D01*
X1033500Y277150D01*
X1033583Y277483D01*
X1033792Y277775D01*
X1034083Y277900D01*
X1034375Y277817D01*
X1034583Y277608D01*
X1034667Y277358D01*
Y276942D01*
X1034792Y276567D01*
X1035042Y276317D01*
X1035333Y276233D01*
X1035625Y276317D01*
X1035833Y276525D01*
X1035958Y276858D01*
X1036000Y277150D01*
G01X1033000Y488467D02*
X1030500D01*
Y489508D01*
X1030625Y489842D01*
X1030792Y490050D01*
X1031125Y490133D01*
X1031458Y490050D01*
X1031667Y489800D01*
X1031792Y489508D01*
Y488467D01*
G01Y489508D02*
X1033000Y490133D01*
G01X1032708Y491692D02*
X1032917Y491983D01*
X1033000Y492317D01*
X1032917Y492650D01*
X1032667Y492942D01*
X1032292Y493150D01*
X1031917Y493233D01*
X1031458D01*
X1031083Y493150D01*
X1030750Y492942D01*
X1030583Y492692D01*
X1030500Y492400D01*
X1030583Y492067D01*
X1030750Y491817D01*
X1031000Y491650D01*
X1031333Y491567D01*
X1031625Y491650D01*
X1031917Y491858D01*
X1032083Y492108D01*
X1032125Y492400D01*
X1032042Y492733D01*
X1031833Y492983D01*
X1031458Y493233D01*
G01X1030500Y495500D02*
X1030583Y495167D01*
X1030792Y494917D01*
X1031042Y494750D01*
X1031375Y494625D01*
X1031750Y494583D01*
X1032125Y494625D01*
X1032458Y494750D01*
X1032708Y494917D01*
X1032917Y495167D01*
X1033000Y495500D01*
X1032917Y495833D01*
X1032708Y496083D01*
X1032458Y496250D01*
X1032125Y496375D01*
X1031750Y496417D01*
X1031375Y496375D01*
X1031042Y496250D01*
X1030792Y496083D01*
X1030583Y495833D01*
X1030500Y495500D01*
G01X1030917Y497808D02*
X1030667Y498058D01*
X1030542Y498350D01*
X1030500Y498683D01*
X1030583Y499100D01*
X1030792Y499392D01*
X1031042Y499475D01*
X1031292Y499433D01*
X1031500Y499267D01*
X1031917Y498433D01*
X1032208Y498058D01*
X1032625Y497808D01*
X1033000Y497725D01*
Y499475D01*
G01X1032625Y500783D02*
X1032833Y501033D01*
X1032958Y501325D01*
X1033000Y501700D01*
X1032917Y502075D01*
X1032750Y502367D01*
X1032458Y502575D01*
X1032125Y502617D01*
X1031792Y502533D01*
X1031583Y502325D01*
X1031417Y502033D01*
X1031375Y501742D01*
X1031417Y501450D01*
X1031583Y501075D01*
X1030500Y501200D01*
Y502325D01*
G01X1028000Y488467D02*
X1025500D01*
Y489508D01*
X1025625Y489842D01*
X1025792Y490050D01*
X1026125Y490133D01*
X1026458Y490050D01*
X1026667Y489800D01*
X1026792Y489508D01*
Y488467D01*
G01Y489508D02*
X1028000Y490133D01*
G01Y492317D02*
X1027458Y492400D01*
X1027000Y492525D01*
X1026583Y492692D01*
X1026125Y492900D01*
X1025500Y493233D01*
Y491567D01*
G01X1027708Y494792D02*
X1027917Y495083D01*
X1028000Y495417D01*
X1027917Y495750D01*
X1027667Y496042D01*
X1027292Y496250D01*
X1026917Y496333D01*
X1026458D01*
X1026083Y496250D01*
X1025750Y496042D01*
X1025583Y495792D01*
X1025500Y495500D01*
X1025583Y495167D01*
X1025750Y494917D01*
X1026000Y494750D01*
X1026333Y494667D01*
X1026625Y494750D01*
X1026917Y494958D01*
X1027083Y495208D01*
X1027125Y495500D01*
X1027042Y495833D01*
X1026833Y496083D01*
X1026458Y496333D01*
G01X1025500Y498600D02*
X1025583Y498267D01*
X1025792Y498017D01*
X1026042Y497850D01*
X1026375Y497725D01*
X1026750Y497683D01*
X1027125Y497725D01*
X1027458Y497850D01*
X1027708Y498017D01*
X1027917Y498267D01*
X1028000Y498600D01*
X1027917Y498933D01*
X1027708Y499183D01*
X1027458Y499350D01*
X1027125Y499475D01*
X1026750Y499517D01*
X1026375Y499475D01*
X1026042Y499350D01*
X1025792Y499183D01*
X1025583Y498933D01*
X1025500Y498600D01*
G01Y501700D02*
X1025583Y501367D01*
X1025792Y501117D01*
X1026042Y500950D01*
X1026375Y500825D01*
X1026750Y500783D01*
X1027125Y500825D01*
X1027458Y500950D01*
X1027708Y501117D01*
X1027917Y501367D01*
X1028000Y501700D01*
X1027917Y502033D01*
X1027708Y502283D01*
X1027458Y502450D01*
X1027125Y502575D01*
X1026750Y502617D01*
X1026375Y502575D01*
X1026042Y502450D01*
X1025792Y502283D01*
X1025583Y502033D01*
X1025500Y501700D01*
G01X1025750Y522000D02*
X1029250Y527000D01*
G01X1025750D02*
X1029250Y522000D01*
G01X1031517Y526167D02*
X1032017Y526667D01*
X1032600Y526917D01*
X1033267Y527000D01*
X1034100Y526833D01*
X1034683Y526417D01*
X1034850Y525917D01*
X1034767Y525417D01*
X1034433Y525000D01*
X1032767Y524167D01*
X1032017Y523583D01*
X1031517Y522750D01*
X1031350Y522000D01*
X1034850D01*
G01X1038700Y521833D02*
X1038533Y521917D01*
Y522083D01*
X1038700Y522167D01*
X1038867Y522083D01*
Y521917D01*
X1038700Y521833D01*
G01Y524083D02*
X1038533Y524167D01*
Y524333D01*
X1038700Y524417D01*
X1038867Y524333D01*
Y524167D01*
X1038700Y524083D01*
G01X1042467Y523000D02*
X1042967Y522417D01*
X1043633Y522083D01*
X1044383Y522000D01*
X1045050Y522083D01*
X1045717Y522500D01*
X1046133Y523000D01*
X1046217Y523500D01*
X1046050Y524083D01*
X1045467Y524500D01*
X1044883Y524667D01*
X1044133D01*
G01X1044883D02*
X1045383Y524917D01*
X1045800Y525333D01*
X1045967Y525833D01*
X1045800Y526333D01*
X1045383Y526750D01*
X1044633Y527000D01*
X1043883Y526917D01*
X1043133Y526583D01*
G01X1048317Y526167D02*
X1048817Y526667D01*
X1049400Y526917D01*
X1050067Y527000D01*
X1050900Y526833D01*
X1051483Y526417D01*
X1051650Y525917D01*
X1051567Y525417D01*
X1051233Y525000D01*
X1049567Y524167D01*
X1048817Y523583D01*
X1048317Y522750D01*
X1048150Y522000D01*
X1051650D01*
G01X1055500Y521833D02*
X1055333Y521917D01*
Y522083D01*
X1055500Y522167D01*
X1055667Y522083D01*
Y521917D01*
X1055500Y521833D01*
G01X1060933Y522000D02*
X1061100Y523083D01*
X1061350Y524000D01*
X1061683Y524833D01*
X1062100Y525750D01*
X1062767Y527000D01*
X1059433D01*
G01X1065117Y524083D02*
X1065700Y524667D01*
X1066200Y525000D01*
X1066867Y525167D01*
X1067450Y525000D01*
X1067867Y524667D01*
X1068200Y524167D01*
X1068283Y523583D01*
X1068200Y523083D01*
X1067867Y522583D01*
X1067367Y522167D01*
X1066783Y522000D01*
X1066117Y522167D01*
X1065533Y522667D01*
X1065200Y523417D01*
X1065117Y524250D01*
X1065283Y525333D01*
X1065533Y525917D01*
X1065950Y526500D01*
X1066533Y526917D01*
X1067117Y527000D01*
X1067700Y526833D01*
X1068117Y526417D01*
G01X1072300Y522000D02*
X1072883Y522083D01*
X1073550Y522333D01*
X1073967Y522750D01*
X1074133Y523333D01*
X1073967Y523917D01*
X1073467Y524417D01*
X1072717Y524667D01*
X1071883D01*
X1071383Y524833D01*
X1070967Y525250D01*
X1070800Y525833D01*
X1071050Y526417D01*
X1071633Y526833D01*
X1072300Y527000D01*
X1072967Y526833D01*
X1073550Y526417D01*
X1073800Y525833D01*
X1073633Y525250D01*
X1073217Y524833D01*
X1072717Y524667D01*
X1071883D01*
X1071133Y524417D01*
X1070633Y523917D01*
X1070467Y523333D01*
X1070633Y522750D01*
X1071050Y522333D01*
X1071717Y522083D01*
X1072300Y522000D01*
G01X1076067D02*
Y527000D01*
G01X1079233D02*
X1076067Y523917D01*
G01X1079733Y522000D02*
X1077483Y525333D01*
G01X1081750Y522000D02*
Y527000D01*
G01X1085250D02*
Y522000D01*
G01Y524500D02*
X1081750D01*
G01X1087517Y527000D02*
X1090683D01*
X1087517Y522000D01*
X1090683D01*
G01X1032750Y532500D02*
X1036250Y537500D01*
G01X1032750D02*
X1036250Y532500D01*
G01X1040100D02*
Y537500D01*
X1039100Y536500D01*
G01Y532500D02*
X1041100D01*
G01X1045700D02*
Y537500D01*
X1044700Y536500D01*
G01Y532500D02*
X1046700D01*
G01X1051300Y532333D02*
X1051133Y532417D01*
Y532583D01*
X1051300Y532667D01*
X1051467Y532583D01*
Y532417D01*
X1051300Y532333D01*
G01Y534583D02*
X1051133Y534667D01*
Y534833D01*
X1051300Y534917D01*
X1051467Y534833D01*
Y534667D01*
X1051300Y534583D01*
G01X1055317Y536667D02*
X1055817Y537167D01*
X1056400Y537417D01*
X1057067Y537500D01*
X1057900Y537333D01*
X1058483Y536917D01*
X1058650Y536417D01*
X1058567Y535917D01*
X1058233Y535500D01*
X1056567Y534667D01*
X1055817Y534083D01*
X1055317Y533250D01*
X1055150Y532500D01*
X1058650D01*
G01X1063500D02*
Y537500D01*
X1060417Y533917D01*
X1064583D01*
G01X1065933Y532500D02*
Y537500D01*
X1068100Y533333D01*
X1070267Y537500D01*
Y532500D01*
G01X1071950D02*
Y537500D01*
G01X1075450D02*
Y532500D01*
G01Y535000D02*
X1071950D01*
G01X1077717Y537500D02*
X1080883D01*
X1077717Y532500D01*
X1080883D01*
G01X1032750Y543000D02*
X1036250Y548000D01*
G01X1032750D02*
X1036250Y543000D01*
G01X1040100D02*
Y548000D01*
X1039100Y547000D01*
G01Y543000D02*
X1041100D01*
G01X1045700Y548000D02*
X1045033Y547833D01*
X1044533Y547417D01*
X1044200Y546917D01*
X1043950Y546250D01*
X1043867Y545500D01*
X1043950Y544750D01*
X1044200Y544083D01*
X1044533Y543583D01*
X1045033Y543167D01*
X1045700Y543000D01*
X1046367Y543167D01*
X1046867Y543583D01*
X1047200Y544083D01*
X1047450Y544750D01*
X1047533Y545500D01*
X1047450Y546250D01*
X1047200Y546917D01*
X1046867Y547417D01*
X1046367Y547833D01*
X1045700Y548000D01*
G01X1051300Y542833D02*
X1051133Y542917D01*
Y543083D01*
X1051300Y543167D01*
X1051467Y543083D01*
Y542917D01*
X1051300Y542833D01*
G01Y545083D02*
X1051133Y545167D01*
Y545333D01*
X1051300Y545417D01*
X1051467Y545333D01*
Y545167D01*
X1051300Y545083D01*
G01X1056900Y543000D02*
Y548000D01*
X1055900Y547000D01*
G01Y543000D02*
X1057900D01*
G01X1060917Y547167D02*
X1061417Y547667D01*
X1062000Y547917D01*
X1062667Y548000D01*
X1063500Y547833D01*
X1064083Y547417D01*
X1064250Y546917D01*
X1064167Y546417D01*
X1063833Y546000D01*
X1062167Y545167D01*
X1061417Y544583D01*
X1060917Y543750D01*
X1060750Y543000D01*
X1064250D01*
G01X1066267Y543750D02*
X1066767Y543333D01*
X1067350Y543083D01*
X1068100Y543000D01*
X1068850Y543167D01*
X1069433Y543500D01*
X1069850Y544083D01*
X1069933Y544750D01*
X1069767Y545417D01*
X1069350Y545833D01*
X1068767Y546167D01*
X1068183Y546250D01*
X1067600Y546167D01*
X1066850Y545833D01*
X1067100Y548000D01*
X1069350D01*
G01X1071533Y543000D02*
Y548000D01*
X1073700Y543833D01*
X1075867Y548000D01*
Y543000D01*
G01X1077550D02*
Y548000D01*
G01X1081050D02*
Y543000D01*
G01Y545500D02*
X1077550D01*
G01X1083317Y548000D02*
X1086483D01*
X1083317Y543000D01*
X1086483D01*
G01X1030017Y679500D02*
Y682000D01*
X1031058D01*
X1031392Y681875D01*
X1031600Y681708D01*
X1031683Y681375D01*
X1031600Y681042D01*
X1031350Y680833D01*
X1031058Y680708D01*
X1030017D01*
G01X1031058D02*
X1031683Y679500D01*
G01X1033033Y679875D02*
X1033283Y679667D01*
X1033575Y679542D01*
X1033950Y679500D01*
X1034325Y679583D01*
X1034617Y679750D01*
X1034825Y680042D01*
X1034867Y680375D01*
X1034783Y680708D01*
X1034575Y680917D01*
X1034283Y681083D01*
X1033992Y681125D01*
X1033700Y681083D01*
X1033325Y680917D01*
X1033450Y682000D01*
X1034575D01*
G01X1036258Y681583D02*
X1036508Y681833D01*
X1036800Y681958D01*
X1037133Y682000D01*
X1037550Y681917D01*
X1037842Y681708D01*
X1037925Y681458D01*
X1037883Y681208D01*
X1037717Y681000D01*
X1036883Y680583D01*
X1036508Y680292D01*
X1036258Y679875D01*
X1036175Y679500D01*
X1037925D01*
G01X1039358Y680542D02*
X1039650Y680833D01*
X1039900Y681000D01*
X1040233Y681083D01*
X1040525Y681000D01*
X1040733Y680833D01*
X1040900Y680583D01*
X1040942Y680292D01*
X1040900Y680042D01*
X1040733Y679792D01*
X1040483Y679583D01*
X1040192Y679500D01*
X1039858Y679583D01*
X1039567Y679833D01*
X1039400Y680208D01*
X1039358Y680625D01*
X1039442Y681167D01*
X1039567Y681458D01*
X1039775Y681750D01*
X1040067Y681958D01*
X1040358Y682000D01*
X1040650Y681917D01*
X1040858Y681708D01*
G01X1030017Y691500D02*
Y694000D01*
X1031058D01*
X1031392Y693875D01*
X1031600Y693708D01*
X1031683Y693375D01*
X1031600Y693042D01*
X1031350Y692833D01*
X1031058Y692708D01*
X1030017D01*
G01X1031058D02*
X1031683Y691500D01*
G01X1034450D02*
Y694000D01*
X1032908Y692208D01*
X1034992D01*
G01X1037550Y691500D02*
Y694000D01*
X1036008Y692208D01*
X1038092D01*
G01X1040067Y691500D02*
X1040150Y692042D01*
X1040275Y692500D01*
X1040442Y692917D01*
X1040650Y693375D01*
X1040983Y694000D01*
X1039317D01*
G01X1030017Y683500D02*
Y686000D01*
X1031058D01*
X1031392Y685875D01*
X1031600Y685708D01*
X1031683Y685375D01*
X1031600Y685042D01*
X1031350Y684833D01*
X1031058Y684708D01*
X1030017D01*
G01X1031058D02*
X1031683Y683500D01*
G01X1033033Y683875D02*
X1033283Y683667D01*
X1033575Y683542D01*
X1033950Y683500D01*
X1034325Y683583D01*
X1034617Y683750D01*
X1034825Y684042D01*
X1034867Y684375D01*
X1034783Y684708D01*
X1034575Y684917D01*
X1034283Y685083D01*
X1033992Y685125D01*
X1033700Y685083D01*
X1033325Y684917D01*
X1033450Y686000D01*
X1034575D01*
G01X1037550Y683500D02*
Y686000D01*
X1036008Y684208D01*
X1038092D01*
G01X1039358Y685583D02*
X1039608Y685833D01*
X1039900Y685958D01*
X1040233Y686000D01*
X1040650Y685917D01*
X1040942Y685708D01*
X1041025Y685458D01*
X1040983Y685208D01*
X1040817Y685000D01*
X1039983Y684583D01*
X1039608Y684292D01*
X1039358Y683875D01*
X1039275Y683500D01*
X1041025D01*
G01X1030017Y695500D02*
Y698000D01*
X1031058D01*
X1031392Y697875D01*
X1031600Y697708D01*
X1031683Y697375D01*
X1031600Y697042D01*
X1031350Y696833D01*
X1031058Y696708D01*
X1030017D01*
G01X1031058D02*
X1031683Y695500D01*
G01X1033033Y696000D02*
X1033283Y695708D01*
X1033617Y695542D01*
X1033992Y695500D01*
X1034325Y695542D01*
X1034658Y695750D01*
X1034867Y696000D01*
X1034908Y696250D01*
X1034825Y696542D01*
X1034533Y696750D01*
X1034242Y696833D01*
X1033867D01*
G01X1034242D02*
X1034492Y696958D01*
X1034700Y697167D01*
X1034783Y697417D01*
X1034700Y697667D01*
X1034492Y697875D01*
X1034117Y698000D01*
X1033742Y697958D01*
X1033367Y697792D01*
G01X1036258Y696542D02*
X1036550Y696833D01*
X1036800Y697000D01*
X1037133Y697083D01*
X1037425Y697000D01*
X1037633Y696833D01*
X1037800Y696583D01*
X1037842Y696292D01*
X1037800Y696042D01*
X1037633Y695792D01*
X1037383Y695583D01*
X1037092Y695500D01*
X1036758Y695583D01*
X1036467Y695833D01*
X1036300Y696208D01*
X1036258Y696625D01*
X1036342Y697167D01*
X1036467Y697458D01*
X1036675Y697750D01*
X1036967Y697958D01*
X1037258Y698000D01*
X1037550Y697917D01*
X1037758Y697708D01*
G01X1039442Y695792D02*
X1039733Y695583D01*
X1040067Y695500D01*
X1040400Y695583D01*
X1040692Y695833D01*
X1040900Y696208D01*
X1040983Y696583D01*
Y697042D01*
X1040900Y697417D01*
X1040692Y697750D01*
X1040442Y697917D01*
X1040150Y698000D01*
X1039817Y697917D01*
X1039567Y697750D01*
X1039400Y697500D01*
X1039317Y697167D01*
X1039400Y696875D01*
X1039608Y696583D01*
X1039858Y696417D01*
X1040150Y696375D01*
X1040483Y696458D01*
X1040733Y696667D01*
X1040983Y697042D01*
G01X1030017Y711500D02*
Y714000D01*
X1031058D01*
X1031392Y713875D01*
X1031600Y713708D01*
X1031683Y713375D01*
X1031600Y713042D01*
X1031350Y712833D01*
X1031058Y712708D01*
X1030017D01*
G01X1031058D02*
X1031683Y711500D01*
G01X1033033Y711875D02*
X1033283Y711667D01*
X1033575Y711542D01*
X1033950Y711500D01*
X1034325Y711583D01*
X1034617Y711750D01*
X1034825Y712042D01*
X1034867Y712375D01*
X1034783Y712708D01*
X1034575Y712917D01*
X1034283Y713083D01*
X1033992Y713125D01*
X1033700Y713083D01*
X1033325Y712917D01*
X1033450Y714000D01*
X1034575D01*
G01X1036258Y713583D02*
X1036508Y713833D01*
X1036800Y713958D01*
X1037133Y714000D01*
X1037550Y713917D01*
X1037842Y713708D01*
X1037925Y713458D01*
X1037883Y713208D01*
X1037717Y713000D01*
X1036883Y712583D01*
X1036508Y712292D01*
X1036258Y711875D01*
X1036175Y711500D01*
X1037925D01*
G01X1039233Y712000D02*
X1039483Y711708D01*
X1039817Y711542D01*
X1040192Y711500D01*
X1040525Y711542D01*
X1040858Y711750D01*
X1041067Y712000D01*
X1041108Y712250D01*
X1041025Y712542D01*
X1040733Y712750D01*
X1040442Y712833D01*
X1040067D01*
G01X1040442D02*
X1040692Y712958D01*
X1040900Y713167D01*
X1040983Y713417D01*
X1040900Y713667D01*
X1040692Y713875D01*
X1040317Y714000D01*
X1039942Y713958D01*
X1039567Y713792D01*
G01X1030017Y707500D02*
Y710000D01*
X1031058D01*
X1031392Y709875D01*
X1031600Y709708D01*
X1031683Y709375D01*
X1031600Y709042D01*
X1031350Y708833D01*
X1031058Y708708D01*
X1030017D01*
G01X1031058D02*
X1031683Y707500D01*
G01X1033033Y708000D02*
X1033283Y707708D01*
X1033617Y707542D01*
X1033992Y707500D01*
X1034325Y707542D01*
X1034658Y707750D01*
X1034867Y708000D01*
X1034908Y708250D01*
X1034825Y708542D01*
X1034533Y708750D01*
X1034242Y708833D01*
X1033867D01*
G01X1034242D02*
X1034492Y708958D01*
X1034700Y709167D01*
X1034783Y709417D01*
X1034700Y709667D01*
X1034492Y709875D01*
X1034117Y710000D01*
X1033742Y709958D01*
X1033367Y709792D01*
G01X1037550Y707500D02*
Y710000D01*
X1036008Y708208D01*
X1038092D01*
G01X1040150Y707500D02*
Y710000D01*
X1039650Y709500D01*
G01Y707500D02*
X1040650D01*
G01X1030017Y699500D02*
Y702000D01*
X1031058D01*
X1031392Y701875D01*
X1031600Y701708D01*
X1031683Y701375D01*
X1031600Y701042D01*
X1031350Y700833D01*
X1031058Y700708D01*
X1030017D01*
G01X1031058D02*
X1031683Y699500D01*
G01X1033033Y700000D02*
X1033283Y699708D01*
X1033617Y699542D01*
X1033992Y699500D01*
X1034325Y699542D01*
X1034658Y699750D01*
X1034867Y700000D01*
X1034908Y700250D01*
X1034825Y700542D01*
X1034533Y700750D01*
X1034242Y700833D01*
X1033867D01*
G01X1034242D02*
X1034492Y700958D01*
X1034700Y701167D01*
X1034783Y701417D01*
X1034700Y701667D01*
X1034492Y701875D01*
X1034117Y702000D01*
X1033742Y701958D01*
X1033367Y701792D01*
G01X1037550Y699500D02*
Y702000D01*
X1036008Y700208D01*
X1038092D01*
G01X1039233Y699875D02*
X1039483Y699667D01*
X1039775Y699542D01*
X1040150Y699500D01*
X1040525Y699583D01*
X1040817Y699750D01*
X1041025Y700042D01*
X1041067Y700375D01*
X1040983Y700708D01*
X1040775Y700917D01*
X1040483Y701083D01*
X1040192Y701125D01*
X1039900Y701083D01*
X1039525Y700917D01*
X1039650Y702000D01*
X1040775D01*
G01X1030017Y703500D02*
Y706000D01*
X1031058D01*
X1031392Y705875D01*
X1031600Y705708D01*
X1031683Y705375D01*
X1031600Y705042D01*
X1031350Y704833D01*
X1031058Y704708D01*
X1030017D01*
G01X1031058D02*
X1031683Y703500D01*
G01X1033033Y704000D02*
X1033283Y703708D01*
X1033617Y703542D01*
X1033992Y703500D01*
X1034325Y703542D01*
X1034658Y703750D01*
X1034867Y704000D01*
X1034908Y704250D01*
X1034825Y704542D01*
X1034533Y704750D01*
X1034242Y704833D01*
X1033867D01*
G01X1034242D02*
X1034492Y704958D01*
X1034700Y705167D01*
X1034783Y705417D01*
X1034700Y705667D01*
X1034492Y705875D01*
X1034117Y706000D01*
X1033742Y705958D01*
X1033367Y705792D01*
G01X1036133Y703875D02*
X1036383Y703667D01*
X1036675Y703542D01*
X1037050Y703500D01*
X1037425Y703583D01*
X1037717Y703750D01*
X1037925Y704042D01*
X1037967Y704375D01*
X1037883Y704708D01*
X1037675Y704917D01*
X1037383Y705083D01*
X1037092Y705125D01*
X1036800Y705083D01*
X1036425Y704917D01*
X1036550Y706000D01*
X1037675D01*
G01X1040150Y703500D02*
Y706000D01*
X1039650Y705500D01*
G01Y703500D02*
X1040650D01*
G01X1026716Y856768D02*
X1030716D01*
Y864168D01*
G01X1021366Y875618D02*
Y870618D01*
X1026366D01*
G01X1030416Y864968D02*
Y868968D01*
X1023016D01*
G01X1026366Y898318D02*
X1021366D01*
Y893318D01*
G01X1022773Y879350D02*
X1020773D01*
G01X1032567Y901500D02*
Y904000D01*
X1033567D01*
X1033900Y903875D01*
X1034150Y903583D01*
X1034233Y903250D01*
X1034150Y902917D01*
X1033942Y902667D01*
X1033567Y902542D01*
X1032567D01*
G01X1035583Y904000D02*
Y902208D01*
X1035750Y901833D01*
X1036083Y901583D01*
X1036500Y901500D01*
X1036917Y901583D01*
X1037250Y901833D01*
X1037417Y902208D01*
Y904000D01*
G01X1038808Y902542D02*
X1039100Y902833D01*
X1039350Y903000D01*
X1039683Y903083D01*
X1039975Y903000D01*
X1040183Y902833D01*
X1040350Y902583D01*
X1040392Y902292D01*
X1040350Y902042D01*
X1040183Y901792D01*
X1039933Y901583D01*
X1039642Y901500D01*
X1039308Y901583D01*
X1039017Y901833D01*
X1038850Y902208D01*
X1038808Y902625D01*
X1038892Y903167D01*
X1039017Y903458D01*
X1039225Y903750D01*
X1039517Y903958D01*
X1039808Y904000D01*
X1040100Y903917D01*
X1040308Y903708D01*
G01X1030098Y896911D02*
Y899911D01*
G01X1029716Y913168D02*
X1025716D01*
Y905768D01*
G01X1034216Y913168D02*
X1030216D01*
Y905768D01*
G01X1027216Y915485D02*
X1024716D01*
Y916485D01*
X1024841Y916818D01*
X1025133Y917068D01*
X1025466Y917151D01*
X1025799Y917068D01*
X1026049Y916860D01*
X1026174Y916485D01*
Y915485D01*
G01X1027216Y918585D02*
X1024716D01*
Y919626D01*
X1024841Y919960D01*
X1025008Y920168D01*
X1025341Y920251D01*
X1025674Y920168D01*
X1025883Y919918D01*
X1026008Y919626D01*
Y918585D01*
G01Y919626D02*
X1027216Y920251D01*
G01X1026924Y921810D02*
X1027133Y922101D01*
X1027216Y922435D01*
X1027133Y922768D01*
X1026883Y923060D01*
X1026508Y923268D01*
X1026133Y923351D01*
X1025674D01*
X1025299Y923268D01*
X1024966Y923060D01*
X1024799Y922810D01*
X1024716Y922518D01*
X1024799Y922185D01*
X1024966Y921935D01*
X1025216Y921768D01*
X1025549Y921685D01*
X1025841Y921768D01*
X1026133Y921976D01*
X1026299Y922226D01*
X1026341Y922518D01*
X1026258Y922851D01*
X1026049Y923101D01*
X1025674Y923351D01*
G01X1024716Y925618D02*
X1024799Y925285D01*
X1025008Y925035D01*
X1025258Y924868D01*
X1025591Y924743D01*
X1025966Y924701D01*
X1026341Y924743D01*
X1026674Y924868D01*
X1026924Y925035D01*
X1027133Y925285D01*
X1027216Y925618D01*
X1027133Y925951D01*
X1026924Y926201D01*
X1026674Y926368D01*
X1026341Y926493D01*
X1025966Y926535D01*
X1025591Y926493D01*
X1025258Y926368D01*
X1025008Y926201D01*
X1024799Y925951D01*
X1024716Y925618D01*
G01X1031716Y915485D02*
X1029216D01*
Y916485D01*
X1029341Y916818D01*
X1029633Y917068D01*
X1029966Y917151D01*
X1030299Y917068D01*
X1030549Y916860D01*
X1030674Y916485D01*
Y915485D01*
G01X1031716Y918585D02*
X1029216D01*
Y919626D01*
X1029341Y919960D01*
X1029508Y920168D01*
X1029841Y920251D01*
X1030174Y920168D01*
X1030383Y919918D01*
X1030508Y919626D01*
Y918585D01*
G01Y919626D02*
X1031716Y920251D01*
G01Y922518D02*
X1031674Y922810D01*
X1031549Y923143D01*
X1031341Y923351D01*
X1031049Y923435D01*
X1030758Y923351D01*
X1030508Y923101D01*
X1030383Y922726D01*
Y922310D01*
X1030299Y922060D01*
X1030091Y921851D01*
X1029799Y921768D01*
X1029508Y921893D01*
X1029299Y922185D01*
X1029216Y922518D01*
X1029299Y922851D01*
X1029508Y923143D01*
X1029799Y923268D01*
X1030091Y923185D01*
X1030299Y922976D01*
X1030383Y922726D01*
Y922310D01*
X1030508Y921935D01*
X1030758Y921685D01*
X1031049Y921601D01*
X1031341Y921685D01*
X1031549Y921893D01*
X1031674Y922226D01*
X1031716Y922518D01*
G01X1031424Y924910D02*
X1031633Y925201D01*
X1031716Y925535D01*
X1031633Y925868D01*
X1031383Y926160D01*
X1031008Y926368D01*
X1030633Y926451D01*
X1030174D01*
X1029799Y926368D01*
X1029466Y926160D01*
X1029299Y925910D01*
X1029216Y925618D01*
X1029299Y925285D01*
X1029466Y925035D01*
X1029716Y924868D01*
X1030049Y924785D01*
X1030341Y924868D01*
X1030633Y925076D01*
X1030799Y925326D01*
X1030841Y925618D01*
X1030758Y925951D01*
X1030549Y926201D01*
X1030174Y926451D01*
G01X1023000Y915467D02*
X1020500D01*
Y916467D01*
X1020625Y916800D01*
X1020917Y917050D01*
X1021250Y917133D01*
X1021583Y917050D01*
X1021833Y916842D01*
X1021958Y916467D01*
Y915467D01*
G01X1020708Y920317D02*
X1020583Y920067D01*
X1020500Y919775D01*
Y919442D01*
X1020625Y919067D01*
X1020833Y918775D01*
X1021083Y918567D01*
X1021500Y918400D01*
X1021875Y918358D01*
X1022250Y918442D01*
X1022500Y918567D01*
X1022750Y918817D01*
X1022917Y919108D01*
X1023000Y919400D01*
Y919692D01*
X1022917Y919983D01*
X1022792Y920233D01*
X1022625Y920442D01*
G01X1023000Y922500D02*
X1020500D01*
X1021000Y922000D01*
G01X1023000D02*
Y923000D01*
G01X1020500Y925600D02*
X1020583Y925267D01*
X1020792Y925017D01*
X1021042Y924850D01*
X1021375Y924725D01*
X1021750Y924683D01*
X1022125Y924725D01*
X1022458Y924850D01*
X1022708Y925017D01*
X1022917Y925267D01*
X1023000Y925600D01*
X1022917Y925933D01*
X1022708Y926183D01*
X1022458Y926350D01*
X1022125Y926475D01*
X1021750Y926517D01*
X1021375Y926475D01*
X1021042Y926350D01*
X1020792Y926183D01*
X1020583Y925933D01*
X1020500Y925600D01*
G01X1020917Y927908D02*
X1020667Y928158D01*
X1020542Y928450D01*
X1020500Y928783D01*
X1020583Y929200D01*
X1020792Y929492D01*
X1021042Y929575D01*
X1021292Y929533D01*
X1021500Y929367D01*
X1021917Y928533D01*
X1022208Y928158D01*
X1022625Y927908D01*
X1023000Y927825D01*
Y929575D01*
G01X1041516Y-7874D02*
X1100216D01*
G01Y-8902D02*
X1041516D01*
Y26848D01*
X1038666D01*
Y38348D01*
X1041516D01*
Y53198D01*
X1100216D01*
Y38348D01*
X1103066D01*
Y26848D01*
X1100216D01*
Y-8902D01*
G01X1050800Y61500D02*
Y55300D01*
X1063200D01*
Y61500D01*
G01X1037300D02*
Y55300D01*
X1049700D01*
Y61500D01*
G01X1063200Y67500D02*
Y73700D01*
X1050800D01*
Y67500D01*
G01X1049700D02*
Y73700D01*
X1037300D01*
Y67500D01*
G01X1052300Y76500D02*
X1046800D01*
G01Y84500D02*
X1052300D01*
G01Y85500D02*
X1046800D01*
G01X1075750Y137500D02*
Y103500D01*
X1048250D01*
Y137500D01*
X1075750D01*
G01X1052300Y94500D02*
X1046800D01*
G01Y102500D02*
X1052300D01*
G01X1046800Y93500D02*
X1052300D01*
G01X1046999Y142441D02*
Y140441D01*
G01X1043062Y168127D02*
Y171127D01*
G01X1053500Y186017D02*
X1051000D01*
Y187017D01*
X1051125Y187350D01*
X1051417Y187600D01*
X1051750Y187683D01*
X1052083Y187600D01*
X1052333Y187392D01*
X1052458Y187017D01*
Y186017D01*
G01X1053500Y189117D02*
X1051000D01*
Y190158D01*
X1051125Y190492D01*
X1051292Y190700D01*
X1051625Y190783D01*
X1051958Y190700D01*
X1052167Y190450D01*
X1052292Y190158D01*
Y189117D01*
G01Y190158D02*
X1053500Y190783D01*
G01X1053000Y192133D02*
X1053292Y192383D01*
X1053458Y192717D01*
X1053500Y193092D01*
X1053458Y193425D01*
X1053250Y193758D01*
X1053000Y193967D01*
X1052750Y194008D01*
X1052458Y193925D01*
X1052250Y193633D01*
X1052167Y193342D01*
Y192967D01*
G01Y193342D02*
X1052042Y193592D01*
X1051833Y193800D01*
X1051583Y193883D01*
X1051333Y193800D01*
X1051125Y193592D01*
X1051000Y193217D01*
X1051042Y192842D01*
X1051208Y192467D01*
G01X1053208Y195442D02*
X1053417Y195733D01*
X1053500Y196067D01*
X1053417Y196400D01*
X1053167Y196692D01*
X1052792Y196900D01*
X1052417Y196983D01*
X1051958D01*
X1051583Y196900D01*
X1051250Y196692D01*
X1051083Y196442D01*
X1051000Y196150D01*
X1051083Y195817D01*
X1051250Y195567D01*
X1051500Y195400D01*
X1051833Y195317D01*
X1052125Y195400D01*
X1052417Y195608D01*
X1052583Y195858D01*
X1052625Y196150D01*
X1052542Y196483D01*
X1052333Y196733D01*
X1051958Y196983D01*
G01X1046000Y186517D02*
X1043500D01*
Y187517D01*
X1043625Y187850D01*
X1043917Y188100D01*
X1044250Y188183D01*
X1044583Y188100D01*
X1044833Y187892D01*
X1044958Y187517D01*
Y186517D01*
G01X1043708Y191367D02*
X1043583Y191117D01*
X1043500Y190825D01*
Y190492D01*
X1043625Y190117D01*
X1043833Y189825D01*
X1044083Y189617D01*
X1044500Y189450D01*
X1044875Y189408D01*
X1045250Y189492D01*
X1045500Y189617D01*
X1045750Y189867D01*
X1045917Y190158D01*
X1046000Y190450D01*
Y190742D01*
X1045917Y191033D01*
X1045792Y191283D01*
X1045625Y191492D01*
G01X1046000Y194050D02*
X1043500D01*
X1045292Y192508D01*
Y194592D01*
G01X1044958Y195858D02*
X1044667Y196150D01*
X1044500Y196400D01*
X1044417Y196733D01*
X1044500Y197025D01*
X1044667Y197233D01*
X1044917Y197400D01*
X1045208Y197442D01*
X1045458Y197400D01*
X1045708Y197233D01*
X1045917Y196983D01*
X1046000Y196692D01*
X1045917Y196358D01*
X1045667Y196067D01*
X1045292Y195900D01*
X1044875Y195858D01*
X1044333Y195942D01*
X1044042Y196067D01*
X1043750Y196275D01*
X1043542Y196567D01*
X1043500Y196858D01*
X1043583Y197150D01*
X1043792Y197358D01*
G01X1041500Y180700D02*
X1037500D01*
Y173300D01*
G01X1040935Y218784D02*
Y221284D01*
X1041935D01*
X1042268Y221159D01*
X1042518Y220867D01*
X1042601Y220534D01*
X1042518Y220201D01*
X1042310Y219951D01*
X1041935Y219826D01*
X1040935D01*
G01X1044035Y218784D02*
Y221284D01*
X1045076D01*
X1045410Y221159D01*
X1045618Y220992D01*
X1045701Y220659D01*
X1045618Y220326D01*
X1045368Y220117D01*
X1045076Y219992D01*
X1044035D01*
G01X1045076D02*
X1045701Y218784D01*
G01X1047968D02*
Y221284D01*
X1047468Y220784D01*
G01Y218784D02*
X1048468D01*
G01X1051068D02*
Y221284D01*
X1050568Y220784D01*
G01Y218784D02*
X1051568D01*
G01X1054085D02*
X1054168Y219326D01*
X1054293Y219784D01*
X1054460Y220201D01*
X1054668Y220659D01*
X1055001Y221284D01*
X1053335D01*
G01X1040967Y209000D02*
Y211500D01*
X1041967D01*
X1042300Y211375D01*
X1042550Y211083D01*
X1042633Y210750D01*
X1042550Y210417D01*
X1042342Y210167D01*
X1041967Y210042D01*
X1040967D01*
G01X1044067Y209000D02*
Y211500D01*
X1045108D01*
X1045442Y211375D01*
X1045650Y211208D01*
X1045733Y210875D01*
X1045650Y210542D01*
X1045400Y210333D01*
X1045108Y210208D01*
X1044067D01*
G01X1045108D02*
X1045733Y209000D01*
G01X1048000D02*
Y211500D01*
X1047500Y211000D01*
G01Y209000D02*
X1048500D01*
G01X1050183Y209500D02*
X1050433Y209208D01*
X1050767Y209042D01*
X1051142Y209000D01*
X1051475Y209042D01*
X1051808Y209250D01*
X1052017Y209500D01*
X1052058Y209750D01*
X1051975Y210042D01*
X1051683Y210250D01*
X1051392Y210333D01*
X1051017D01*
G01X1051392D02*
X1051642Y210458D01*
X1051850Y210667D01*
X1051933Y210917D01*
X1051850Y211167D01*
X1051642Y211375D01*
X1051267Y211500D01*
X1050892Y211458D01*
X1050517Y211292D01*
G01X1054200Y209000D02*
Y211500D01*
X1053700Y211000D01*
G01Y209000D02*
X1054700D01*
G01X1041650Y234200D02*
X1063350D01*
G01X1041650Y264200D02*
Y234200D01*
G01X1043435Y226784D02*
Y229284D01*
X1044435D01*
X1044768Y229159D01*
X1045018Y228867D01*
X1045101Y228534D01*
X1045018Y228201D01*
X1044810Y227951D01*
X1044435Y227826D01*
X1043435D01*
G01X1046535Y226784D02*
Y229284D01*
X1047576D01*
X1047910Y229159D01*
X1048118Y228992D01*
X1048201Y228659D01*
X1048118Y228326D01*
X1047868Y228117D01*
X1047576Y227992D01*
X1046535D01*
G01X1047576D02*
X1048201Y226784D01*
G01X1050468D02*
Y229284D01*
X1049968Y228784D01*
G01Y226784D02*
X1050968D01*
G01X1053568D02*
Y229284D01*
X1053068Y228784D01*
G01Y226784D02*
X1054068D01*
G01X1057168D02*
Y229284D01*
X1055626Y227492D01*
X1057710D01*
G01X1040935Y222784D02*
Y225284D01*
X1041935D01*
X1042268Y225159D01*
X1042518Y224867D01*
X1042601Y224534D01*
X1042518Y224201D01*
X1042310Y223951D01*
X1041935Y223826D01*
X1040935D01*
G01X1044035Y222784D02*
Y225284D01*
X1045076D01*
X1045410Y225159D01*
X1045618Y224992D01*
X1045701Y224659D01*
X1045618Y224326D01*
X1045368Y224117D01*
X1045076Y223992D01*
X1044035D01*
G01X1045076D02*
X1045701Y222784D01*
G01X1047968D02*
Y225284D01*
X1047468Y224784D01*
G01Y222784D02*
X1048468D01*
G01X1051068D02*
Y225284D01*
X1050568Y224784D01*
G01Y222784D02*
X1051568D01*
G01X1053251Y223159D02*
X1053501Y222951D01*
X1053793Y222826D01*
X1054168Y222784D01*
X1054543Y222867D01*
X1054835Y223034D01*
X1055043Y223326D01*
X1055085Y223659D01*
X1055001Y223992D01*
X1054793Y224201D01*
X1054501Y224367D01*
X1054210Y224409D01*
X1053918Y224367D01*
X1053543Y224201D01*
X1053668Y225284D01*
X1054793D01*
G01X1047432Y267716D02*
X1047099Y267758D01*
X1046807Y267924D01*
X1046557Y268174D01*
X1046390Y268466D01*
X1046307Y268799D01*
Y269133D01*
X1046390Y269466D01*
X1046557Y269758D01*
X1046807Y270008D01*
X1047099Y270174D01*
X1047432Y270216D01*
X1047765Y270174D01*
X1048057Y270008D01*
X1048307Y269758D01*
X1048474Y269466D01*
X1048557Y269133D01*
Y268799D01*
X1048474Y268466D01*
X1048307Y268174D01*
X1048057Y267924D01*
X1047765Y267758D01*
X1047432Y267716D01*
G01X1047765Y268383D02*
X1048265Y267716D01*
G01X1050449D02*
X1050532Y268258D01*
X1050657Y268716D01*
X1050824Y269133D01*
X1051032Y269591D01*
X1051365Y270216D01*
X1049699D01*
G01X1052840Y268758D02*
X1053132Y269049D01*
X1053382Y269216D01*
X1053715Y269299D01*
X1054007Y269216D01*
X1054215Y269049D01*
X1054382Y268799D01*
X1054424Y268508D01*
X1054382Y268258D01*
X1054215Y268008D01*
X1053965Y267799D01*
X1053674Y267716D01*
X1053340Y267799D01*
X1053049Y268049D01*
X1052882Y268424D01*
X1052840Y268841D01*
X1052924Y269383D01*
X1053049Y269674D01*
X1053257Y269966D01*
X1053549Y270174D01*
X1053840Y270216D01*
X1054132Y270133D01*
X1054340Y269924D01*
G01X1063350Y264200D02*
X1041650D01*
G01X1038250Y555000D02*
X1041750Y560000D01*
G01X1038250D02*
X1041750Y555000D01*
G01X1045600D02*
Y560000D01*
X1044600Y559000D01*
G01Y555000D02*
X1046600D01*
G01X1051200Y554833D02*
X1051033Y554917D01*
Y555083D01*
X1051200Y555167D01*
X1051367Y555083D01*
Y554917D01*
X1051200Y554833D01*
G01Y557083D02*
X1051033Y557167D01*
Y557333D01*
X1051200Y557417D01*
X1051367Y557333D01*
Y557167D01*
X1051200Y557083D01*
G01X1054967Y555750D02*
X1055467Y555333D01*
X1056050Y555083D01*
X1056800Y555000D01*
X1057550Y555167D01*
X1058133Y555500D01*
X1058550Y556083D01*
X1058633Y556750D01*
X1058467Y557417D01*
X1058050Y557833D01*
X1057467Y558167D01*
X1056883Y558250D01*
X1056300Y558167D01*
X1055550Y557833D01*
X1055800Y560000D01*
X1058050D01*
G01X1062400D02*
X1061733Y559833D01*
X1061233Y559417D01*
X1060900Y558917D01*
X1060650Y558250D01*
X1060567Y557500D01*
X1060650Y556750D01*
X1060900Y556083D01*
X1061233Y555583D01*
X1061733Y555167D01*
X1062400Y555000D01*
X1063067Y555167D01*
X1063567Y555583D01*
X1063900Y556083D01*
X1064150Y556750D01*
X1064233Y557500D01*
X1064150Y558250D01*
X1063900Y558917D01*
X1063567Y559417D01*
X1063067Y559833D01*
X1062400Y560000D01*
G01X1065833Y555000D02*
Y560000D01*
X1068000Y555833D01*
X1070167Y560000D01*
Y555000D01*
G01X1071850D02*
Y560000D01*
G01X1075350D02*
Y555000D01*
G01Y557500D02*
X1071850D01*
G01X1077617Y560000D02*
X1080783D01*
X1077617Y555000D01*
X1080783D01*
G01X1042000Y656350D02*
X1044500D01*
G01X1042000Y655392D02*
Y657308D01*
G01X1044500Y658617D02*
X1042000D01*
Y659617D01*
X1042125Y659950D01*
X1042417Y660200D01*
X1042750Y660283D01*
X1043083Y660200D01*
X1043333Y659992D01*
X1043458Y659617D01*
Y658617D01*
G01X1044500Y662550D02*
X1044458Y662842D01*
X1044333Y663175D01*
X1044125Y663383D01*
X1043833Y663467D01*
X1043542Y663383D01*
X1043292Y663133D01*
X1043167Y662758D01*
Y662342D01*
X1043083Y662092D01*
X1042875Y661883D01*
X1042583Y661800D01*
X1042292Y661925D01*
X1042083Y662217D01*
X1042000Y662550D01*
X1042083Y662883D01*
X1042292Y663175D01*
X1042583Y663300D01*
X1042875Y663217D01*
X1043083Y663008D01*
X1043167Y662758D01*
Y662342D01*
X1043292Y661967D01*
X1043542Y661717D01*
X1043833Y661633D01*
X1044125Y661717D01*
X1044333Y661925D01*
X1044458Y662258D01*
X1044500Y662550D01*
G01X1042417Y664858D02*
X1042167Y665108D01*
X1042042Y665400D01*
X1042000Y665733D01*
X1042083Y666150D01*
X1042292Y666442D01*
X1042542Y666525D01*
X1042792Y666483D01*
X1043000Y666317D01*
X1043417Y665483D01*
X1043708Y665108D01*
X1044125Y664858D01*
X1044500Y664775D01*
Y666525D01*
G01X1037000Y656350D02*
X1039500D01*
G01X1037000Y655392D02*
Y657308D01*
G01X1039500Y658617D02*
X1037000D01*
Y659617D01*
X1037125Y659950D01*
X1037417Y660200D01*
X1037750Y660283D01*
X1038083Y660200D01*
X1038333Y659992D01*
X1038458Y659617D01*
Y658617D01*
G01X1039500Y662550D02*
X1039458Y662842D01*
X1039333Y663175D01*
X1039125Y663383D01*
X1038833Y663467D01*
X1038542Y663383D01*
X1038292Y663133D01*
X1038167Y662758D01*
Y662342D01*
X1038083Y662092D01*
X1037875Y661883D01*
X1037583Y661800D01*
X1037292Y661925D01*
X1037083Y662217D01*
X1037000Y662550D01*
X1037083Y662883D01*
X1037292Y663175D01*
X1037583Y663300D01*
X1037875Y663217D01*
X1038083Y663008D01*
X1038167Y662758D01*
Y662342D01*
X1038292Y661967D01*
X1038542Y661717D01*
X1038833Y661633D01*
X1039125Y661717D01*
X1039333Y661925D01*
X1039458Y662258D01*
X1039500Y662550D01*
G01Y665567D02*
X1038958Y665650D01*
X1038500Y665775D01*
X1038083Y665942D01*
X1037625Y666150D01*
X1037000Y666483D01*
Y664817D01*
G01X1047017Y658000D02*
Y660500D01*
X1048058D01*
X1048392Y660375D01*
X1048600Y660208D01*
X1048683Y659875D01*
X1048600Y659542D01*
X1048350Y659333D01*
X1048058Y659208D01*
X1047017D01*
G01X1048058D02*
X1048683Y658000D01*
G01X1050158Y660083D02*
X1050408Y660333D01*
X1050700Y660458D01*
X1051033Y660500D01*
X1051450Y660417D01*
X1051742Y660208D01*
X1051825Y659958D01*
X1051783Y659708D01*
X1051617Y659500D01*
X1050783Y659083D01*
X1050408Y658792D01*
X1050158Y658375D01*
X1050075Y658000D01*
X1051825D01*
G01X1053258Y659042D02*
X1053550Y659333D01*
X1053800Y659500D01*
X1054133Y659583D01*
X1054425Y659500D01*
X1054633Y659333D01*
X1054800Y659083D01*
X1054842Y658792D01*
X1054800Y658542D01*
X1054633Y658292D01*
X1054383Y658083D01*
X1054092Y658000D01*
X1053758Y658083D01*
X1053467Y658333D01*
X1053300Y658708D01*
X1053258Y659125D01*
X1053342Y659667D01*
X1053467Y659958D01*
X1053675Y660250D01*
X1053967Y660458D01*
X1054258Y660500D01*
X1054550Y660417D01*
X1054758Y660208D01*
G01X1057150Y658000D02*
X1057442Y658042D01*
X1057775Y658167D01*
X1057983Y658375D01*
X1058067Y658667D01*
X1057983Y658958D01*
X1057733Y659208D01*
X1057358Y659333D01*
X1056942D01*
X1056692Y659417D01*
X1056483Y659625D01*
X1056400Y659917D01*
X1056525Y660208D01*
X1056817Y660417D01*
X1057150Y660500D01*
X1057483Y660417D01*
X1057775Y660208D01*
X1057900Y659917D01*
X1057817Y659625D01*
X1057608Y659417D01*
X1057358Y659333D01*
X1056942D01*
X1056567Y659208D01*
X1056317Y658958D01*
X1056233Y658667D01*
X1056317Y658375D01*
X1056525Y658167D01*
X1056858Y658042D01*
X1057150Y658000D01*
G01X1047017Y663000D02*
Y665500D01*
X1048058D01*
X1048392Y665375D01*
X1048600Y665208D01*
X1048683Y664875D01*
X1048600Y664542D01*
X1048350Y664333D01*
X1048058Y664208D01*
X1047017D01*
G01X1048058D02*
X1048683Y663000D01*
G01X1050158Y665083D02*
X1050408Y665333D01*
X1050700Y665458D01*
X1051033Y665500D01*
X1051450Y665417D01*
X1051742Y665208D01*
X1051825Y664958D01*
X1051783Y664708D01*
X1051617Y664500D01*
X1050783Y664083D01*
X1050408Y663792D01*
X1050158Y663375D01*
X1050075Y663000D01*
X1051825D01*
G01X1053258Y664042D02*
X1053550Y664333D01*
X1053800Y664500D01*
X1054133Y664583D01*
X1054425Y664500D01*
X1054633Y664333D01*
X1054800Y664083D01*
X1054842Y663792D01*
X1054800Y663542D01*
X1054633Y663292D01*
X1054383Y663083D01*
X1054092Y663000D01*
X1053758Y663083D01*
X1053467Y663333D01*
X1053300Y663708D01*
X1053258Y664125D01*
X1053342Y664667D01*
X1053467Y664958D01*
X1053675Y665250D01*
X1053967Y665458D01*
X1054258Y665500D01*
X1054550Y665417D01*
X1054758Y665208D01*
G01X1056442Y663292D02*
X1056733Y663083D01*
X1057067Y663000D01*
X1057400Y663083D01*
X1057692Y663333D01*
X1057900Y663708D01*
X1057983Y664083D01*
Y664542D01*
X1057900Y664917D01*
X1057692Y665250D01*
X1057442Y665417D01*
X1057150Y665500D01*
X1056817Y665417D01*
X1056567Y665250D01*
X1056400Y665000D01*
X1056317Y664667D01*
X1056400Y664375D01*
X1056608Y664083D01*
X1056858Y663917D01*
X1057150Y663875D01*
X1057483Y663958D01*
X1057733Y664167D01*
X1057983Y664542D01*
G01X1043800Y683000D02*
Y679000D01*
X1051200D01*
G01X1043800Y695000D02*
Y691000D01*
X1051200D01*
G01X1043800Y687000D02*
Y683000D01*
X1051200D01*
G01X1043800Y699000D02*
Y695000D01*
X1051200D01*
G01Y711000D02*
Y715000D01*
X1043800D01*
G01Y711000D02*
Y707000D01*
X1051200D01*
G01X1043800Y703000D02*
Y699000D01*
X1051200D01*
G01X1043800Y707000D02*
Y703000D01*
X1051200D01*
G01X1049017Y733000D02*
Y735500D01*
X1050058D01*
X1050392Y735375D01*
X1050600Y735208D01*
X1050683Y734875D01*
X1050600Y734542D01*
X1050350Y734333D01*
X1050058Y734208D01*
X1049017D01*
G01X1050058D02*
X1050683Y733000D01*
G01X1052158Y734042D02*
X1052450Y734333D01*
X1052700Y734500D01*
X1053033Y734583D01*
X1053325Y734500D01*
X1053533Y734333D01*
X1053700Y734083D01*
X1053742Y733792D01*
X1053700Y733542D01*
X1053533Y733292D01*
X1053283Y733083D01*
X1052992Y733000D01*
X1052658Y733083D01*
X1052367Y733333D01*
X1052200Y733708D01*
X1052158Y734125D01*
X1052242Y734667D01*
X1052367Y734958D01*
X1052575Y735250D01*
X1052867Y735458D01*
X1053158Y735500D01*
X1053450Y735417D01*
X1053658Y735208D01*
G01X1056050Y735500D02*
X1055717Y735417D01*
X1055467Y735208D01*
X1055300Y734958D01*
X1055175Y734625D01*
X1055133Y734250D01*
X1055175Y733875D01*
X1055300Y733542D01*
X1055467Y733292D01*
X1055717Y733083D01*
X1056050Y733000D01*
X1056383Y733083D01*
X1056633Y733292D01*
X1056800Y733542D01*
X1056925Y733875D01*
X1056967Y734250D01*
X1056925Y734625D01*
X1056800Y734958D01*
X1056633Y735208D01*
X1056383Y735417D01*
X1056050Y735500D01*
G01X1059067Y733000D02*
X1059150Y733542D01*
X1059275Y734000D01*
X1059442Y734417D01*
X1059650Y734875D01*
X1059983Y735500D01*
X1058317D01*
G01X1049017Y741000D02*
Y743500D01*
X1050058D01*
X1050392Y743375D01*
X1050600Y743208D01*
X1050683Y742875D01*
X1050600Y742542D01*
X1050350Y742333D01*
X1050058Y742208D01*
X1049017D01*
G01X1050058D02*
X1050683Y741000D01*
G01X1052950D02*
Y743500D01*
X1052450Y743000D01*
G01Y741000D02*
X1053450D01*
G01X1055967D02*
X1056050Y741542D01*
X1056175Y742000D01*
X1056342Y742417D01*
X1056550Y742875D01*
X1056883Y743500D01*
X1055217D01*
G01X1059650Y741000D02*
Y743500D01*
X1058108Y741708D01*
X1060192D01*
G01X1050767Y739292D02*
X1050517Y739417D01*
X1050225Y739500D01*
X1049892D01*
X1049517Y739375D01*
X1049225Y739167D01*
X1049017Y738917D01*
X1048850Y738500D01*
X1048808Y738125D01*
X1048892Y737750D01*
X1049017Y737500D01*
X1049267Y737250D01*
X1049558Y737083D01*
X1049850Y737000D01*
X1050142D01*
X1050433Y737083D01*
X1050683Y737208D01*
X1050892Y737375D01*
G01X1052033Y737500D02*
X1052283Y737208D01*
X1052617Y737042D01*
X1052992Y737000D01*
X1053325Y737042D01*
X1053658Y737250D01*
X1053867Y737500D01*
X1053908Y737750D01*
X1053825Y738042D01*
X1053533Y738250D01*
X1053242Y738333D01*
X1052867D01*
G01X1053242D02*
X1053492Y738458D01*
X1053700Y738667D01*
X1053783Y738917D01*
X1053700Y739167D01*
X1053492Y739375D01*
X1053117Y739500D01*
X1052742Y739458D01*
X1052367Y739292D01*
G01X1055258Y739083D02*
X1055508Y739333D01*
X1055800Y739458D01*
X1056133Y739500D01*
X1056550Y739417D01*
X1056842Y739208D01*
X1056925Y738958D01*
X1056883Y738708D01*
X1056717Y738500D01*
X1055883Y738083D01*
X1055508Y737792D01*
X1055258Y737375D01*
X1055175Y737000D01*
X1056925D01*
G01X1058358Y739083D02*
X1058608Y739333D01*
X1058900Y739458D01*
X1059233Y739500D01*
X1059650Y739417D01*
X1059942Y739208D01*
X1060025Y738958D01*
X1059983Y738708D01*
X1059817Y738500D01*
X1058983Y738083D01*
X1058608Y737792D01*
X1058358Y737375D01*
X1058275Y737000D01*
X1060025D01*
G01X1050978Y747241D02*
X1048478D01*
Y748282D01*
X1048603Y748616D01*
X1048770Y748824D01*
X1049103Y748907D01*
X1049436Y748824D01*
X1049645Y748574D01*
X1049770Y748282D01*
Y747241D01*
G01Y748282D02*
X1050978Y748907D01*
G01X1048895Y750382D02*
X1048645Y750632D01*
X1048520Y750924D01*
X1048478Y751257D01*
X1048561Y751674D01*
X1048770Y751966D01*
X1049020Y752049D01*
X1049270Y752007D01*
X1049478Y751841D01*
X1049895Y751007D01*
X1050186Y750632D01*
X1050603Y750382D01*
X1050978Y750299D01*
Y752049D01*
G01X1050686Y753566D02*
X1050895Y753857D01*
X1050978Y754191D01*
X1050895Y754524D01*
X1050645Y754816D01*
X1050270Y755024D01*
X1049895Y755107D01*
X1049436D01*
X1049061Y755024D01*
X1048728Y754816D01*
X1048561Y754566D01*
X1048478Y754274D01*
X1048561Y753941D01*
X1048728Y753691D01*
X1048978Y753524D01*
X1049311Y753441D01*
X1049603Y753524D01*
X1049895Y753732D01*
X1050061Y753982D01*
X1050103Y754274D01*
X1050020Y754607D01*
X1049811Y754857D01*
X1049436Y755107D01*
G01X1050686Y756666D02*
X1050895Y756957D01*
X1050978Y757291D01*
X1050895Y757624D01*
X1050645Y757916D01*
X1050270Y758124D01*
X1049895Y758207D01*
X1049436D01*
X1049061Y758124D01*
X1048728Y757916D01*
X1048561Y757666D01*
X1048478Y757374D01*
X1048561Y757041D01*
X1048728Y756791D01*
X1048978Y756624D01*
X1049311Y756541D01*
X1049603Y756624D01*
X1049895Y756832D01*
X1050061Y757082D01*
X1050103Y757374D01*
X1050020Y757707D01*
X1049811Y757957D01*
X1049436Y758207D01*
G01X1046188Y747121D02*
X1043688D01*
Y748162D01*
X1043813Y748496D01*
X1043980Y748704D01*
X1044313Y748787D01*
X1044646Y748704D01*
X1044855Y748454D01*
X1044980Y748162D01*
Y747121D01*
G01Y748162D02*
X1046188Y748787D01*
G01X1045688Y750137D02*
X1045980Y750387D01*
X1046146Y750721D01*
X1046188Y751096D01*
X1046146Y751429D01*
X1045938Y751762D01*
X1045688Y751971D01*
X1045438Y752012D01*
X1045146Y751929D01*
X1044938Y751637D01*
X1044855Y751346D01*
Y750971D01*
G01Y751346D02*
X1044730Y751596D01*
X1044521Y751804D01*
X1044271Y751887D01*
X1044021Y751804D01*
X1043813Y751596D01*
X1043688Y751221D01*
X1043730Y750846D01*
X1043896Y750471D01*
G01X1044105Y753362D02*
X1043855Y753612D01*
X1043730Y753904D01*
X1043688Y754237D01*
X1043771Y754654D01*
X1043980Y754946D01*
X1044230Y755029D01*
X1044480Y754987D01*
X1044688Y754821D01*
X1045105Y753987D01*
X1045396Y753612D01*
X1045813Y753362D01*
X1046188Y753279D01*
Y755029D01*
G01Y757754D02*
X1043688D01*
X1045480Y756212D01*
Y758296D01*
G01X1050598Y760101D02*
X1048098D01*
Y761142D01*
X1048223Y761476D01*
X1048390Y761684D01*
X1048723Y761767D01*
X1049056Y761684D01*
X1049265Y761434D01*
X1049390Y761142D01*
Y760101D01*
G01Y761142D02*
X1050598Y761767D01*
G01X1050098Y763117D02*
X1050390Y763367D01*
X1050556Y763701D01*
X1050598Y764076D01*
X1050556Y764409D01*
X1050348Y764742D01*
X1050098Y764951D01*
X1049848Y764992D01*
X1049556Y764909D01*
X1049348Y764617D01*
X1049265Y764326D01*
Y763951D01*
G01Y764326D02*
X1049140Y764576D01*
X1048931Y764784D01*
X1048681Y764867D01*
X1048431Y764784D01*
X1048223Y764576D01*
X1048098Y764201D01*
X1048140Y763826D01*
X1048306Y763451D01*
G01X1050098Y766217D02*
X1050390Y766467D01*
X1050556Y766801D01*
X1050598Y767176D01*
X1050556Y767509D01*
X1050348Y767842D01*
X1050098Y768051D01*
X1049848Y768092D01*
X1049556Y768009D01*
X1049348Y767717D01*
X1049265Y767426D01*
Y767051D01*
G01Y767426D02*
X1049140Y767676D01*
X1048931Y767884D01*
X1048681Y767967D01*
X1048431Y767884D01*
X1048223Y767676D01*
X1048098Y767301D01*
X1048140Y766926D01*
X1048306Y766551D01*
G01X1050098Y769317D02*
X1050390Y769567D01*
X1050556Y769901D01*
X1050598Y770276D01*
X1050556Y770609D01*
X1050348Y770942D01*
X1050098Y771151D01*
X1049848Y771192D01*
X1049556Y771109D01*
X1049348Y770817D01*
X1049265Y770526D01*
Y770151D01*
G01Y770526D02*
X1049140Y770776D01*
X1048931Y770984D01*
X1048681Y771067D01*
X1048431Y770984D01*
X1048223Y770776D01*
X1048098Y770401D01*
X1048140Y770026D01*
X1048306Y769651D01*
G01X1046338Y760061D02*
X1043838D01*
Y761102D01*
X1043963Y761436D01*
X1044130Y761644D01*
X1044463Y761727D01*
X1044796Y761644D01*
X1045005Y761394D01*
X1045130Y761102D01*
Y760061D01*
G01Y761102D02*
X1046338Y761727D01*
G01X1045838Y763077D02*
X1046130Y763327D01*
X1046296Y763661D01*
X1046338Y764036D01*
X1046296Y764369D01*
X1046088Y764702D01*
X1045838Y764911D01*
X1045588Y764952D01*
X1045296Y764869D01*
X1045088Y764577D01*
X1045005Y764286D01*
Y763911D01*
G01Y764286D02*
X1044880Y764536D01*
X1044671Y764744D01*
X1044421Y764827D01*
X1044171Y764744D01*
X1043963Y764536D01*
X1043838Y764161D01*
X1043880Y763786D01*
X1044046Y763411D01*
G01X1045838Y766177D02*
X1046130Y766427D01*
X1046296Y766761D01*
X1046338Y767136D01*
X1046296Y767469D01*
X1046088Y767802D01*
X1045838Y768011D01*
X1045588Y768052D01*
X1045296Y767969D01*
X1045088Y767677D01*
X1045005Y767386D01*
Y767011D01*
G01Y767386D02*
X1044880Y767636D01*
X1044671Y767844D01*
X1044421Y767927D01*
X1044171Y767844D01*
X1043963Y767636D01*
X1043838Y767261D01*
X1043880Y766886D01*
X1044046Y766511D01*
G01X1046338Y770694D02*
X1043838D01*
X1045630Y769152D01*
Y771236D01*
G01X1051500Y828200D02*
X1043500D01*
Y845800D01*
X1051500D01*
Y828200D01*
G01X1041000Y831517D02*
X1038500D01*
Y832517D01*
X1038625Y832850D01*
X1038917Y833100D01*
X1039250Y833183D01*
X1039583Y833100D01*
X1039833Y832892D01*
X1039958Y832517D01*
Y831517D01*
G01X1041000Y834617D02*
X1038500D01*
Y835658D01*
X1038625Y835992D01*
X1038792Y836200D01*
X1039125Y836283D01*
X1039458Y836200D01*
X1039667Y835950D01*
X1039792Y835658D01*
Y834617D01*
G01Y835658D02*
X1041000Y836283D01*
G01Y838550D02*
X1040958Y838842D01*
X1040833Y839175D01*
X1040625Y839383D01*
X1040333Y839467D01*
X1040042Y839383D01*
X1039792Y839133D01*
X1039667Y838758D01*
Y838342D01*
X1039583Y838092D01*
X1039375Y837883D01*
X1039083Y837800D01*
X1038792Y837925D01*
X1038583Y838217D01*
X1038500Y838550D01*
X1038583Y838883D01*
X1038792Y839175D01*
X1039083Y839300D01*
X1039375Y839217D01*
X1039583Y839008D01*
X1039667Y838758D01*
Y838342D01*
X1039792Y837967D01*
X1040042Y837717D01*
X1040333Y837633D01*
X1040625Y837717D01*
X1040833Y837925D01*
X1040958Y838258D01*
X1041000Y838550D01*
G01X1040625Y840733D02*
X1040833Y840983D01*
X1040958Y841275D01*
X1041000Y841650D01*
X1040917Y842025D01*
X1040750Y842317D01*
X1040458Y842525D01*
X1040125Y842567D01*
X1039792Y842483D01*
X1039583Y842275D01*
X1039417Y841983D01*
X1039375Y841692D01*
X1039417Y841400D01*
X1039583Y841025D01*
X1038500Y841150D01*
Y842275D01*
G01X1040334Y872025D02*
Y869025D01*
G01X1049066Y893318D02*
Y898318D01*
X1044066D01*
G01X1047659Y889586D02*
X1049659D01*
G01X1057300Y927500D02*
Y919500D01*
X1039700D01*
Y927500D01*
X1057300D01*
G01X1046817Y935292D02*
X1046567Y935417D01*
X1046275Y935500D01*
X1045942D01*
X1045567Y935375D01*
X1045275Y935167D01*
X1045067Y934917D01*
X1044900Y934500D01*
X1044858Y934125D01*
X1044942Y933750D01*
X1045067Y933500D01*
X1045317Y933250D01*
X1045608Y933083D01*
X1045900Y933000D01*
X1046192D01*
X1046483Y933083D01*
X1046733Y933208D01*
X1046942Y933375D01*
G01X1049000Y933000D02*
X1049292Y933042D01*
X1049625Y933167D01*
X1049833Y933375D01*
X1049917Y933667D01*
X1049833Y933958D01*
X1049583Y934208D01*
X1049208Y934333D01*
X1048792D01*
X1048542Y934417D01*
X1048333Y934625D01*
X1048250Y934917D01*
X1048375Y935208D01*
X1048667Y935417D01*
X1049000Y935500D01*
X1049333Y935417D01*
X1049625Y935208D01*
X1049750Y934917D01*
X1049667Y934625D01*
X1049458Y934417D01*
X1049208Y934333D01*
X1048792D01*
X1048417Y934208D01*
X1048167Y933958D01*
X1048083Y933667D01*
X1048167Y933375D01*
X1048375Y933167D01*
X1048708Y933042D01*
X1049000Y933000D01*
G01X1051308Y934042D02*
X1051600Y934333D01*
X1051850Y934500D01*
X1052183Y934583D01*
X1052475Y934500D01*
X1052683Y934333D01*
X1052850Y934083D01*
X1052892Y933792D01*
X1052850Y933542D01*
X1052683Y933292D01*
X1052433Y933083D01*
X1052142Y933000D01*
X1051808Y933083D01*
X1051517Y933333D01*
X1051350Y933708D01*
X1051308Y934125D01*
X1051392Y934667D01*
X1051517Y934958D01*
X1051725Y935250D01*
X1052017Y935458D01*
X1052308Y935500D01*
X1052600Y935417D01*
X1052808Y935208D01*
G01X1065708Y74267D02*
X1065583Y74017D01*
X1065500Y73725D01*
Y73392D01*
X1065625Y73017D01*
X1065833Y72725D01*
X1066083Y72517D01*
X1066500Y72350D01*
X1066875Y72308D01*
X1067250Y72392D01*
X1067500Y72517D01*
X1067750Y72767D01*
X1067917Y73058D01*
X1068000Y73350D01*
Y73642D01*
X1067917Y73933D01*
X1067792Y74183D01*
X1067625Y74392D01*
G01X1065917Y75658D02*
X1065667Y75908D01*
X1065542Y76200D01*
X1065500Y76533D01*
X1065583Y76950D01*
X1065792Y77242D01*
X1066042Y77325D01*
X1066292Y77283D01*
X1066500Y77117D01*
X1066917Y76283D01*
X1067208Y75908D01*
X1067625Y75658D01*
X1068000Y75575D01*
Y77325D01*
G01X1067500Y78633D02*
X1067792Y78883D01*
X1067958Y79217D01*
X1068000Y79592D01*
X1067958Y79925D01*
X1067750Y80258D01*
X1067500Y80467D01*
X1067250Y80508D01*
X1066958Y80425D01*
X1066750Y80133D01*
X1066667Y79842D01*
Y79467D01*
G01Y79842D02*
X1066542Y80092D01*
X1066333Y80300D01*
X1066083Y80383D01*
X1065833Y80300D01*
X1065625Y80092D01*
X1065500Y79717D01*
X1065542Y79342D01*
X1065708Y78967D01*
G01X1068000Y82650D02*
X1067958Y82942D01*
X1067833Y83275D01*
X1067625Y83483D01*
X1067333Y83567D01*
X1067042Y83483D01*
X1066792Y83233D01*
X1066667Y82858D01*
Y82442D01*
X1066583Y82192D01*
X1066375Y81983D01*
X1066083Y81900D01*
X1065792Y82025D01*
X1065583Y82317D01*
X1065500Y82650D01*
X1065583Y82983D01*
X1065792Y83275D01*
X1066083Y83400D01*
X1066375Y83317D01*
X1066583Y83108D01*
X1066667Y82858D01*
Y82442D01*
X1066792Y82067D01*
X1067042Y81817D01*
X1067333Y81733D01*
X1067625Y81817D01*
X1067833Y82025D01*
X1067958Y82358D01*
X1068000Y82650D01*
G01X1052300Y84500D02*
Y76500D01*
G01Y93500D02*
Y85500D01*
G01Y102500D02*
Y94500D01*
G01X1057768Y141434D02*
X1062768D01*
Y146434D01*
G01X1056842Y142441D02*
Y139441D01*
G01X1066017Y146000D02*
Y148500D01*
X1067017D01*
X1067350Y148375D01*
X1067600Y148083D01*
X1067683Y147750D01*
X1067600Y147417D01*
X1067392Y147167D01*
X1067017Y147042D01*
X1066017D01*
G01X1070867Y148292D02*
X1070617Y148417D01*
X1070325Y148500D01*
X1069992D01*
X1069617Y148375D01*
X1069325Y148167D01*
X1069117Y147917D01*
X1068950Y147500D01*
X1068908Y147125D01*
X1068992Y146750D01*
X1069117Y146500D01*
X1069367Y146250D01*
X1069658Y146083D01*
X1069950Y146000D01*
X1070242D01*
X1070533Y146083D01*
X1070783Y146208D01*
X1070992Y146375D01*
G01X1073550Y146000D02*
Y148500D01*
X1072008Y146708D01*
X1074092D01*
G01X1076150Y146000D02*
X1076442Y146042D01*
X1076775Y146167D01*
X1076983Y146375D01*
X1077067Y146667D01*
X1076983Y146958D01*
X1076733Y147208D01*
X1076358Y147333D01*
X1075942D01*
X1075692Y147417D01*
X1075483Y147625D01*
X1075400Y147917D01*
X1075525Y148208D01*
X1075817Y148417D01*
X1076150Y148500D01*
X1076483Y148417D01*
X1076775Y148208D01*
X1076900Y147917D01*
X1076817Y147625D01*
X1076608Y147417D01*
X1076358Y147333D01*
X1075942D01*
X1075567Y147208D01*
X1075317Y146958D01*
X1075233Y146667D01*
X1075317Y146375D01*
X1075525Y146167D01*
X1075858Y146042D01*
X1076150Y146000D01*
G01X1062768Y164134D02*
Y169134D01*
X1057768D01*
G01X1052905Y168127D02*
Y170127D01*
G01X1059000Y183017D02*
X1056500D01*
Y184017D01*
X1056625Y184350D01*
X1056917Y184600D01*
X1057250Y184683D01*
X1057583Y184600D01*
X1057833Y184392D01*
X1057958Y184017D01*
Y183017D01*
G01X1056708Y187867D02*
X1056583Y187617D01*
X1056500Y187325D01*
Y186992D01*
X1056625Y186617D01*
X1056833Y186325D01*
X1057083Y186117D01*
X1057500Y185950D01*
X1057875Y185908D01*
X1058250Y185992D01*
X1058500Y186117D01*
X1058750Y186367D01*
X1058917Y186658D01*
X1059000Y186950D01*
Y187242D01*
X1058917Y187533D01*
X1058792Y187783D01*
X1058625Y187992D01*
G01X1059000Y190550D02*
X1056500D01*
X1058292Y189008D01*
Y191092D01*
G01X1058708Y192442D02*
X1058917Y192733D01*
X1059000Y193067D01*
X1058917Y193400D01*
X1058667Y193692D01*
X1058292Y193900D01*
X1057917Y193983D01*
X1057458D01*
X1057083Y193900D01*
X1056750Y193692D01*
X1056583Y193442D01*
X1056500Y193150D01*
X1056583Y192817D01*
X1056750Y192567D01*
X1057000Y192400D01*
X1057333Y192317D01*
X1057625Y192400D01*
X1057917Y192608D01*
X1058083Y192858D01*
X1058125Y193150D01*
X1058042Y193483D01*
X1057833Y193733D01*
X1057458Y193983D01*
G01X1059000Y198567D02*
X1056500D01*
Y199567D01*
X1056625Y199900D01*
X1056917Y200150D01*
X1057250Y200233D01*
X1057583Y200150D01*
X1057833Y199942D01*
X1057958Y199567D01*
Y198567D01*
G01X1056500Y201583D02*
X1058292D01*
X1058667Y201750D01*
X1058917Y202083D01*
X1059000Y202500D01*
X1058917Y202917D01*
X1058667Y203250D01*
X1058292Y203417D01*
X1056500D01*
G01X1058708Y204892D02*
X1058917Y205183D01*
X1059000Y205517D01*
X1058917Y205850D01*
X1058667Y206142D01*
X1058292Y206350D01*
X1057917Y206433D01*
X1057458D01*
X1057083Y206350D01*
X1056750Y206142D01*
X1056583Y205892D01*
X1056500Y205600D01*
X1056583Y205267D01*
X1056750Y205017D01*
X1057000Y204850D01*
X1057333Y204767D01*
X1057625Y204850D01*
X1057917Y205058D01*
X1058083Y205308D01*
X1058125Y205600D01*
X1058042Y205933D01*
X1057833Y206183D01*
X1057458Y206433D01*
G01X1061068Y198524D02*
X1072468D01*
G01X1061068Y211924D02*
Y198524D01*
G01X1072468Y211924D02*
X1061068D01*
G01X1058268Y221284D02*
Y217284D01*
X1065668D01*
G01X1058300Y217000D02*
Y213000D01*
X1065700D01*
G01X1063350Y234200D02*
Y264200D01*
G01X1068168Y225284D02*
Y229284D01*
X1060768D01*
G01X1065668Y221284D02*
Y225284D01*
X1058268D01*
G01X1062267Y280292D02*
X1062017Y280417D01*
X1061725Y280500D01*
X1061392D01*
X1061017Y280375D01*
X1060725Y280167D01*
X1060517Y279917D01*
X1060350Y279500D01*
X1060308Y279125D01*
X1060392Y278750D01*
X1060517Y278500D01*
X1060767Y278250D01*
X1061058Y278083D01*
X1061350Y278000D01*
X1061642D01*
X1061933Y278083D01*
X1062183Y278208D01*
X1062392Y278375D01*
G01X1063658Y280083D02*
X1063908Y280333D01*
X1064200Y280458D01*
X1064533Y280500D01*
X1064950Y280417D01*
X1065242Y280208D01*
X1065325Y279958D01*
X1065283Y279708D01*
X1065117Y279500D01*
X1064283Y279083D01*
X1063908Y278792D01*
X1063658Y278375D01*
X1063575Y278000D01*
X1065325D01*
G01X1066633Y278375D02*
X1066883Y278167D01*
X1067175Y278042D01*
X1067550Y278000D01*
X1067925Y278083D01*
X1068217Y278250D01*
X1068425Y278542D01*
X1068467Y278875D01*
X1068383Y279208D01*
X1068175Y279417D01*
X1067883Y279583D01*
X1067592Y279625D01*
X1067300Y279583D01*
X1066925Y279417D01*
X1067050Y280500D01*
X1068175D01*
G01X1069733Y278500D02*
X1069983Y278208D01*
X1070317Y278042D01*
X1070692Y278000D01*
X1071025Y278042D01*
X1071358Y278250D01*
X1071567Y278500D01*
X1071608Y278750D01*
X1071525Y279042D01*
X1071233Y279250D01*
X1070942Y279333D01*
X1070567D01*
G01X1070942D02*
X1071192Y279458D01*
X1071400Y279667D01*
X1071483Y279917D01*
X1071400Y280167D01*
X1071192Y280375D01*
X1070817Y280500D01*
X1070442Y280458D01*
X1070067Y280292D01*
G01X1062267Y284792D02*
X1062017Y284917D01*
X1061725Y285000D01*
X1061392D01*
X1061017Y284875D01*
X1060725Y284667D01*
X1060517Y284417D01*
X1060350Y284000D01*
X1060308Y283625D01*
X1060392Y283250D01*
X1060517Y283000D01*
X1060767Y282750D01*
X1061058Y282583D01*
X1061350Y282500D01*
X1061642D01*
X1061933Y282583D01*
X1062183Y282708D01*
X1062392Y282875D01*
G01X1063658Y284583D02*
X1063908Y284833D01*
X1064200Y284958D01*
X1064533Y285000D01*
X1064950Y284917D01*
X1065242Y284708D01*
X1065325Y284458D01*
X1065283Y284208D01*
X1065117Y284000D01*
X1064283Y283583D01*
X1063908Y283292D01*
X1063658Y282875D01*
X1063575Y282500D01*
X1065325D01*
G01X1066633Y282875D02*
X1066883Y282667D01*
X1067175Y282542D01*
X1067550Y282500D01*
X1067925Y282583D01*
X1068217Y282750D01*
X1068425Y283042D01*
X1068467Y283375D01*
X1068383Y283708D01*
X1068175Y283917D01*
X1067883Y284083D01*
X1067592Y284125D01*
X1067300Y284083D01*
X1066925Y283917D01*
X1067050Y285000D01*
X1068175D01*
G01X1070650Y282500D02*
X1070942Y282542D01*
X1071275Y282667D01*
X1071483Y282875D01*
X1071567Y283167D01*
X1071483Y283458D01*
X1071233Y283708D01*
X1070858Y283833D01*
X1070442D01*
X1070192Y283917D01*
X1069983Y284125D01*
X1069900Y284417D01*
X1070025Y284708D01*
X1070317Y284917D01*
X1070650Y285000D01*
X1070983Y284917D01*
X1071275Y284708D01*
X1071400Y284417D01*
X1071317Y284125D01*
X1071108Y283917D01*
X1070858Y283833D01*
X1070442D01*
X1070067Y283708D01*
X1069817Y283458D01*
X1069733Y283167D01*
X1069817Y282875D01*
X1070025Y282667D01*
X1070358Y282542D01*
X1070650Y282500D01*
G01X1064267Y289292D02*
X1064017Y289417D01*
X1063725Y289500D01*
X1063392D01*
X1063017Y289375D01*
X1062725Y289167D01*
X1062517Y288917D01*
X1062350Y288500D01*
X1062308Y288125D01*
X1062392Y287750D01*
X1062517Y287500D01*
X1062767Y287250D01*
X1063058Y287083D01*
X1063350Y287000D01*
X1063642D01*
X1063933Y287083D01*
X1064183Y287208D01*
X1064392Y287375D01*
G01X1065658Y289083D02*
X1065908Y289333D01*
X1066200Y289458D01*
X1066533Y289500D01*
X1066950Y289417D01*
X1067242Y289208D01*
X1067325Y288958D01*
X1067283Y288708D01*
X1067117Y288500D01*
X1066283Y288083D01*
X1065908Y287792D01*
X1065658Y287375D01*
X1065575Y287000D01*
X1067325D01*
G01X1068633Y287375D02*
X1068883Y287167D01*
X1069175Y287042D01*
X1069550Y287000D01*
X1069925Y287083D01*
X1070217Y287250D01*
X1070425Y287542D01*
X1070467Y287875D01*
X1070383Y288208D01*
X1070175Y288417D01*
X1069883Y288583D01*
X1069592Y288625D01*
X1069300Y288583D01*
X1068925Y288417D01*
X1069050Y289500D01*
X1070175D01*
G01X1071858Y288042D02*
X1072150Y288333D01*
X1072400Y288500D01*
X1072733Y288583D01*
X1073025Y288500D01*
X1073233Y288333D01*
X1073400Y288083D01*
X1073442Y287792D01*
X1073400Y287542D01*
X1073233Y287292D01*
X1072983Y287083D01*
X1072692Y287000D01*
X1072358Y287083D01*
X1072067Y287333D01*
X1071900Y287708D01*
X1071858Y288125D01*
X1071942Y288667D01*
X1072067Y288958D01*
X1072275Y289250D01*
X1072567Y289458D01*
X1072858Y289500D01*
X1073150Y289417D01*
X1073358Y289208D01*
G01X1063991Y293548D02*
X1063741Y293673D01*
X1063449Y293756D01*
X1063116D01*
X1062741Y293631D01*
X1062449Y293423D01*
X1062241Y293173D01*
X1062074Y292756D01*
X1062032Y292381D01*
X1062116Y292006D01*
X1062241Y291756D01*
X1062491Y291506D01*
X1062782Y291339D01*
X1063074Y291256D01*
X1063366D01*
X1063657Y291339D01*
X1063907Y291464D01*
X1064116Y291631D01*
G01X1065382Y293339D02*
X1065632Y293589D01*
X1065924Y293714D01*
X1066257Y293756D01*
X1066674Y293673D01*
X1066966Y293464D01*
X1067049Y293214D01*
X1067007Y292964D01*
X1066841Y292756D01*
X1066007Y292339D01*
X1065632Y292048D01*
X1065382Y291631D01*
X1065299Y291256D01*
X1067049D01*
G01X1068357Y291631D02*
X1068607Y291423D01*
X1068899Y291298D01*
X1069274Y291256D01*
X1069649Y291339D01*
X1069941Y291506D01*
X1070149Y291798D01*
X1070191Y292131D01*
X1070107Y292464D01*
X1069899Y292673D01*
X1069607Y292839D01*
X1069316Y292881D01*
X1069024Y292839D01*
X1068649Y292673D01*
X1068774Y293756D01*
X1069899D01*
G01X1071666Y291548D02*
X1071957Y291339D01*
X1072291Y291256D01*
X1072624Y291339D01*
X1072916Y291589D01*
X1073124Y291964D01*
X1073207Y292339D01*
Y292798D01*
X1073124Y293173D01*
X1072916Y293506D01*
X1072666Y293673D01*
X1072374Y293756D01*
X1072041Y293673D01*
X1071791Y293506D01*
X1071624Y293256D01*
X1071541Y292923D01*
X1071624Y292631D01*
X1071832Y292339D01*
X1072082Y292173D01*
X1072374Y292131D01*
X1072707Y292214D01*
X1072957Y292423D01*
X1073207Y292798D01*
G01X1063991Y297948D02*
X1063741Y298073D01*
X1063449Y298156D01*
X1063116D01*
X1062741Y298031D01*
X1062449Y297823D01*
X1062241Y297573D01*
X1062074Y297156D01*
X1062032Y296781D01*
X1062116Y296406D01*
X1062241Y296156D01*
X1062491Y295906D01*
X1062782Y295739D01*
X1063074Y295656D01*
X1063366D01*
X1063657Y295739D01*
X1063907Y295864D01*
X1064116Y296031D01*
G01X1065382Y297739D02*
X1065632Y297989D01*
X1065924Y298114D01*
X1066257Y298156D01*
X1066674Y298073D01*
X1066966Y297864D01*
X1067049Y297614D01*
X1067007Y297364D01*
X1066841Y297156D01*
X1066007Y296739D01*
X1065632Y296448D01*
X1065382Y296031D01*
X1065299Y295656D01*
X1067049D01*
G01X1068482Y296698D02*
X1068774Y296989D01*
X1069024Y297156D01*
X1069357Y297239D01*
X1069649Y297156D01*
X1069857Y296989D01*
X1070024Y296739D01*
X1070066Y296448D01*
X1070024Y296198D01*
X1069857Y295948D01*
X1069607Y295739D01*
X1069316Y295656D01*
X1068982Y295739D01*
X1068691Y295989D01*
X1068524Y296364D01*
X1068482Y296781D01*
X1068566Y297323D01*
X1068691Y297614D01*
X1068899Y297906D01*
X1069191Y298114D01*
X1069482Y298156D01*
X1069774Y298073D01*
X1069982Y297864D01*
G01X1072374Y295656D02*
Y298156D01*
X1071874Y297656D01*
G01Y295656D02*
X1072874D01*
G01X1063967Y301392D02*
X1063717Y301517D01*
X1063425Y301600D01*
X1063092D01*
X1062717Y301475D01*
X1062425Y301267D01*
X1062217Y301017D01*
X1062050Y300600D01*
X1062008Y300225D01*
X1062092Y299850D01*
X1062217Y299600D01*
X1062467Y299350D01*
X1062758Y299183D01*
X1063050Y299100D01*
X1063342D01*
X1063633Y299183D01*
X1063883Y299308D01*
X1064092Y299475D01*
G01X1065358Y301183D02*
X1065608Y301433D01*
X1065900Y301558D01*
X1066233Y301600D01*
X1066650Y301517D01*
X1066942Y301308D01*
X1067025Y301058D01*
X1066983Y300808D01*
X1066817Y300600D01*
X1065983Y300183D01*
X1065608Y299892D01*
X1065358Y299475D01*
X1065275Y299100D01*
X1067025D01*
G01X1068458Y300142D02*
X1068750Y300433D01*
X1069000Y300600D01*
X1069333Y300683D01*
X1069625Y300600D01*
X1069833Y300433D01*
X1070000Y300183D01*
X1070042Y299892D01*
X1070000Y299642D01*
X1069833Y299392D01*
X1069583Y299183D01*
X1069292Y299100D01*
X1068958Y299183D01*
X1068667Y299433D01*
X1068500Y299808D01*
X1068458Y300225D01*
X1068542Y300767D01*
X1068667Y301058D01*
X1068875Y301350D01*
X1069167Y301558D01*
X1069458Y301600D01*
X1069750Y301517D01*
X1069958Y301308D01*
G01X1071558Y301183D02*
X1071808Y301433D01*
X1072100Y301558D01*
X1072433Y301600D01*
X1072850Y301517D01*
X1073142Y301308D01*
X1073225Y301058D01*
X1073183Y300808D01*
X1073017Y300600D01*
X1072183Y300183D01*
X1071808Y299892D01*
X1071558Y299475D01*
X1071475Y299100D01*
X1073225D01*
G01X1062017Y632000D02*
Y634500D01*
X1063058D01*
X1063392Y634375D01*
X1063600Y634208D01*
X1063683Y633875D01*
X1063600Y633542D01*
X1063350Y633333D01*
X1063058Y633208D01*
X1062017D01*
G01X1063058D02*
X1063683Y632000D01*
G01X1065158Y633042D02*
X1065450Y633333D01*
X1065700Y633500D01*
X1066033Y633583D01*
X1066325Y633500D01*
X1066533Y633333D01*
X1066700Y633083D01*
X1066742Y632792D01*
X1066700Y632542D01*
X1066533Y632292D01*
X1066283Y632083D01*
X1065992Y632000D01*
X1065658Y632083D01*
X1065367Y632333D01*
X1065200Y632708D01*
X1065158Y633125D01*
X1065242Y633667D01*
X1065367Y633958D01*
X1065575Y634250D01*
X1065867Y634458D01*
X1066158Y634500D01*
X1066450Y634417D01*
X1066658Y634208D01*
G01X1068967Y632000D02*
X1069050Y632542D01*
X1069175Y633000D01*
X1069342Y633417D01*
X1069550Y633875D01*
X1069883Y634500D01*
X1068217D01*
G01X1072150Y632000D02*
Y634500D01*
X1071650Y634000D01*
G01Y632000D02*
X1072650D01*
G01X1062017Y644000D02*
Y646500D01*
X1063058D01*
X1063392Y646375D01*
X1063600Y646208D01*
X1063683Y645875D01*
X1063600Y645542D01*
X1063350Y645333D01*
X1063058Y645208D01*
X1062017D01*
G01X1063058D02*
X1063683Y644000D01*
G01X1065033Y644375D02*
X1065283Y644167D01*
X1065575Y644042D01*
X1065950Y644000D01*
X1066325Y644083D01*
X1066617Y644250D01*
X1066825Y644542D01*
X1066867Y644875D01*
X1066783Y645208D01*
X1066575Y645417D01*
X1066283Y645583D01*
X1065992Y645625D01*
X1065700Y645583D01*
X1065325Y645417D01*
X1065450Y646500D01*
X1066575D01*
G01X1068133Y644500D02*
X1068383Y644208D01*
X1068717Y644042D01*
X1069092Y644000D01*
X1069425Y644042D01*
X1069758Y644250D01*
X1069967Y644500D01*
X1070008Y644750D01*
X1069925Y645042D01*
X1069633Y645250D01*
X1069342Y645333D01*
X1068967D01*
G01X1069342D02*
X1069592Y645458D01*
X1069800Y645667D01*
X1069883Y645917D01*
X1069800Y646167D01*
X1069592Y646375D01*
X1069217Y646500D01*
X1068842Y646458D01*
X1068467Y646292D01*
G01X1071442Y644292D02*
X1071733Y644083D01*
X1072067Y644000D01*
X1072400Y644083D01*
X1072692Y644333D01*
X1072900Y644708D01*
X1072983Y645083D01*
Y645542D01*
X1072900Y645917D01*
X1072692Y646250D01*
X1072442Y646417D01*
X1072150Y646500D01*
X1071817Y646417D01*
X1071567Y646250D01*
X1071400Y646000D01*
X1071317Y645667D01*
X1071400Y645375D01*
X1071608Y645083D01*
X1071858Y644917D01*
X1072150Y644875D01*
X1072483Y644958D01*
X1072733Y645167D01*
X1072983Y645542D01*
G01X1062017Y636000D02*
Y638500D01*
X1063058D01*
X1063392Y638375D01*
X1063600Y638208D01*
X1063683Y637875D01*
X1063600Y637542D01*
X1063350Y637333D01*
X1063058Y637208D01*
X1062017D01*
G01X1063058D02*
X1063683Y636000D01*
G01X1065033Y636375D02*
X1065283Y636167D01*
X1065575Y636042D01*
X1065950Y636000D01*
X1066325Y636083D01*
X1066617Y636250D01*
X1066825Y636542D01*
X1066867Y636875D01*
X1066783Y637208D01*
X1066575Y637417D01*
X1066283Y637583D01*
X1065992Y637625D01*
X1065700Y637583D01*
X1065325Y637417D01*
X1065450Y638500D01*
X1066575D01*
G01X1069550Y636000D02*
Y638500D01*
X1068008Y636708D01*
X1070092D01*
G01X1072150Y636000D02*
Y638500D01*
X1071650Y638000D01*
G01Y636000D02*
X1072650D01*
G01X1062017Y640000D02*
Y642500D01*
X1063058D01*
X1063392Y642375D01*
X1063600Y642208D01*
X1063683Y641875D01*
X1063600Y641542D01*
X1063350Y641333D01*
X1063058Y641208D01*
X1062017D01*
G01X1063058D02*
X1063683Y640000D01*
G01X1065033Y640500D02*
X1065283Y640208D01*
X1065617Y640042D01*
X1065992Y640000D01*
X1066325Y640042D01*
X1066658Y640250D01*
X1066867Y640500D01*
X1066908Y640750D01*
X1066825Y641042D01*
X1066533Y641250D01*
X1066242Y641333D01*
X1065867D01*
G01X1066242D02*
X1066492Y641458D01*
X1066700Y641667D01*
X1066783Y641917D01*
X1066700Y642167D01*
X1066492Y642375D01*
X1066117Y642500D01*
X1065742Y642458D01*
X1065367Y642292D01*
G01X1068133Y640500D02*
X1068383Y640208D01*
X1068717Y640042D01*
X1069092Y640000D01*
X1069425Y640042D01*
X1069758Y640250D01*
X1069967Y640500D01*
X1070008Y640750D01*
X1069925Y641042D01*
X1069633Y641250D01*
X1069342Y641333D01*
X1068967D01*
G01X1069342D02*
X1069592Y641458D01*
X1069800Y641667D01*
X1069883Y641917D01*
X1069800Y642167D01*
X1069592Y642375D01*
X1069217Y642500D01*
X1068842Y642458D01*
X1068467Y642292D01*
G01X1072150Y642500D02*
X1071817Y642417D01*
X1071567Y642208D01*
X1071400Y641958D01*
X1071275Y641625D01*
X1071233Y641250D01*
X1071275Y640875D01*
X1071400Y640542D01*
X1071567Y640292D01*
X1071817Y640083D01*
X1072150Y640000D01*
X1072483Y640083D01*
X1072733Y640292D01*
X1072900Y640542D01*
X1073025Y640875D01*
X1073067Y641250D01*
X1073025Y641625D01*
X1072900Y641958D01*
X1072733Y642208D01*
X1072483Y642417D01*
X1072150Y642500D01*
G01X1062017Y661500D02*
Y664000D01*
X1063058D01*
X1063392Y663875D01*
X1063600Y663708D01*
X1063683Y663375D01*
X1063600Y663042D01*
X1063350Y662833D01*
X1063058Y662708D01*
X1062017D01*
G01X1063058D02*
X1063683Y661500D01*
G01X1065158Y663583D02*
X1065408Y663833D01*
X1065700Y663958D01*
X1066033Y664000D01*
X1066450Y663917D01*
X1066742Y663708D01*
X1066825Y663458D01*
X1066783Y663208D01*
X1066617Y663000D01*
X1065783Y662583D01*
X1065408Y662292D01*
X1065158Y661875D01*
X1065075Y661500D01*
X1066825D01*
G01X1068133Y662000D02*
X1068383Y661708D01*
X1068717Y661542D01*
X1069092Y661500D01*
X1069425Y661542D01*
X1069758Y661750D01*
X1069967Y662000D01*
X1070008Y662250D01*
X1069925Y662542D01*
X1069633Y662750D01*
X1069342Y662833D01*
X1068967D01*
G01X1069342D02*
X1069592Y662958D01*
X1069800Y663167D01*
X1069883Y663417D01*
X1069800Y663667D01*
X1069592Y663875D01*
X1069217Y664000D01*
X1068842Y663958D01*
X1068467Y663792D01*
G01X1072150Y661500D02*
X1072442Y661542D01*
X1072775Y661667D01*
X1072983Y661875D01*
X1073067Y662167D01*
X1072983Y662458D01*
X1072733Y662708D01*
X1072358Y662833D01*
X1071942D01*
X1071692Y662917D01*
X1071483Y663125D01*
X1071400Y663417D01*
X1071525Y663708D01*
X1071817Y663917D01*
X1072150Y664000D01*
X1072483Y663917D01*
X1072775Y663708D01*
X1072900Y663417D01*
X1072817Y663125D01*
X1072608Y662917D01*
X1072358Y662833D01*
X1071942D01*
X1071567Y662708D01*
X1071317Y662458D01*
X1071233Y662167D01*
X1071317Y661875D01*
X1071525Y661667D01*
X1071858Y661542D01*
X1072150Y661500D01*
G01X1062017Y657500D02*
Y660000D01*
X1063058D01*
X1063392Y659875D01*
X1063600Y659708D01*
X1063683Y659375D01*
X1063600Y659042D01*
X1063350Y658833D01*
X1063058Y658708D01*
X1062017D01*
G01X1063058D02*
X1063683Y657500D01*
G01X1065158Y659583D02*
X1065408Y659833D01*
X1065700Y659958D01*
X1066033Y660000D01*
X1066450Y659917D01*
X1066742Y659708D01*
X1066825Y659458D01*
X1066783Y659208D01*
X1066617Y659000D01*
X1065783Y658583D01*
X1065408Y658292D01*
X1065158Y657875D01*
X1065075Y657500D01*
X1066825D01*
G01X1068133Y658000D02*
X1068383Y657708D01*
X1068717Y657542D01*
X1069092Y657500D01*
X1069425Y657542D01*
X1069758Y657750D01*
X1069967Y658000D01*
X1070008Y658250D01*
X1069925Y658542D01*
X1069633Y658750D01*
X1069342Y658833D01*
X1068967D01*
G01X1069342D02*
X1069592Y658958D01*
X1069800Y659167D01*
X1069883Y659417D01*
X1069800Y659667D01*
X1069592Y659875D01*
X1069217Y660000D01*
X1068842Y659958D01*
X1068467Y659792D01*
G01X1071442Y657792D02*
X1071733Y657583D01*
X1072067Y657500D01*
X1072400Y657583D01*
X1072692Y657833D01*
X1072900Y658208D01*
X1072983Y658583D01*
Y659042D01*
X1072900Y659417D01*
X1072692Y659750D01*
X1072442Y659917D01*
X1072150Y660000D01*
X1071817Y659917D01*
X1071567Y659750D01*
X1071400Y659500D01*
X1071317Y659167D01*
X1071400Y658875D01*
X1071608Y658583D01*
X1071858Y658417D01*
X1072150Y658375D01*
X1072483Y658458D01*
X1072733Y658667D01*
X1072983Y659042D01*
G01X1062017Y649500D02*
Y652000D01*
X1063058D01*
X1063392Y651875D01*
X1063600Y651708D01*
X1063683Y651375D01*
X1063600Y651042D01*
X1063350Y650833D01*
X1063058Y650708D01*
X1062017D01*
G01X1063058D02*
X1063683Y649500D01*
G01X1066450D02*
Y652000D01*
X1064908Y650208D01*
X1066992D01*
G01X1069550Y649500D02*
Y652000D01*
X1068008Y650208D01*
X1070092D01*
G01X1072150Y649500D02*
X1072442Y649542D01*
X1072775Y649667D01*
X1072983Y649875D01*
X1073067Y650167D01*
X1072983Y650458D01*
X1072733Y650708D01*
X1072358Y650833D01*
X1071942D01*
X1071692Y650917D01*
X1071483Y651125D01*
X1071400Y651417D01*
X1071525Y651708D01*
X1071817Y651917D01*
X1072150Y652000D01*
X1072483Y651917D01*
X1072775Y651708D01*
X1072900Y651417D01*
X1072817Y651125D01*
X1072608Y650917D01*
X1072358Y650833D01*
X1071942D01*
X1071567Y650708D01*
X1071317Y650458D01*
X1071233Y650167D01*
X1071317Y649875D01*
X1071525Y649667D01*
X1071858Y649542D01*
X1072150Y649500D01*
G01X1062017Y653500D02*
Y656000D01*
X1063058D01*
X1063392Y655875D01*
X1063600Y655708D01*
X1063683Y655375D01*
X1063600Y655042D01*
X1063350Y654833D01*
X1063058Y654708D01*
X1062017D01*
G01X1063058D02*
X1063683Y653500D01*
G01X1066450D02*
Y656000D01*
X1064908Y654208D01*
X1066992D01*
G01X1068967Y653500D02*
X1069050Y654042D01*
X1069175Y654500D01*
X1069342Y654917D01*
X1069550Y655375D01*
X1069883Y656000D01*
X1068217D01*
G01X1071358Y655583D02*
X1071608Y655833D01*
X1071900Y655958D01*
X1072233Y656000D01*
X1072650Y655917D01*
X1072942Y655708D01*
X1073025Y655458D01*
X1072983Y655208D01*
X1072817Y655000D01*
X1071983Y654583D01*
X1071608Y654292D01*
X1071358Y653875D01*
X1071275Y653500D01*
X1073025D01*
G01X1064300Y670000D02*
Y666000D01*
X1071700D01*
G01X1064300Y675000D02*
Y671000D01*
X1071700D01*
G01X1062517Y679000D02*
Y681500D01*
X1063558D01*
X1063892Y681375D01*
X1064100Y681208D01*
X1064183Y680875D01*
X1064100Y680542D01*
X1063850Y680333D01*
X1063558Y680208D01*
X1062517D01*
G01X1063558D02*
X1064183Y679000D01*
G01X1065533Y679500D02*
X1065783Y679208D01*
X1066117Y679042D01*
X1066492Y679000D01*
X1066825Y679042D01*
X1067158Y679250D01*
X1067367Y679500D01*
X1067408Y679750D01*
X1067325Y680042D01*
X1067033Y680250D01*
X1066742Y680333D01*
X1066367D01*
G01X1066742D02*
X1066992Y680458D01*
X1067200Y680667D01*
X1067283Y680917D01*
X1067200Y681167D01*
X1066992Y681375D01*
X1066617Y681500D01*
X1066242Y681458D01*
X1065867Y681292D01*
G01X1068758Y680042D02*
X1069050Y680333D01*
X1069300Y680500D01*
X1069633Y680583D01*
X1069925Y680500D01*
X1070133Y680333D01*
X1070300Y680083D01*
X1070342Y679792D01*
X1070300Y679542D01*
X1070133Y679292D01*
X1069883Y679083D01*
X1069592Y679000D01*
X1069258Y679083D01*
X1068967Y679333D01*
X1068800Y679708D01*
X1068758Y680125D01*
X1068842Y680667D01*
X1068967Y680958D01*
X1069175Y681250D01*
X1069467Y681458D01*
X1069758Y681500D01*
X1070050Y681417D01*
X1070258Y681208D01*
G01X1071733Y679375D02*
X1071983Y679167D01*
X1072275Y679042D01*
X1072650Y679000D01*
X1073025Y679083D01*
X1073317Y679250D01*
X1073525Y679542D01*
X1073567Y679875D01*
X1073483Y680208D01*
X1073275Y680417D01*
X1072983Y680583D01*
X1072692Y680625D01*
X1072400Y680583D01*
X1072025Y680417D01*
X1072150Y681500D01*
X1073275D01*
G01X1062517Y691000D02*
Y693500D01*
X1063558D01*
X1063892Y693375D01*
X1064100Y693208D01*
X1064183Y692875D01*
X1064100Y692542D01*
X1063850Y692333D01*
X1063558Y692208D01*
X1062517D01*
G01X1063558D02*
X1064183Y691000D01*
G01X1065533Y691500D02*
X1065783Y691208D01*
X1066117Y691042D01*
X1066492Y691000D01*
X1066825Y691042D01*
X1067158Y691250D01*
X1067367Y691500D01*
X1067408Y691750D01*
X1067325Y692042D01*
X1067033Y692250D01*
X1066742Y692333D01*
X1066367D01*
G01X1066742D02*
X1066992Y692458D01*
X1067200Y692667D01*
X1067283Y692917D01*
X1067200Y693167D01*
X1066992Y693375D01*
X1066617Y693500D01*
X1066242Y693458D01*
X1065867Y693292D01*
G01X1070050Y691000D02*
Y693500D01*
X1068508Y691708D01*
X1070592D01*
G01X1072650Y691000D02*
X1072942Y691042D01*
X1073275Y691167D01*
X1073483Y691375D01*
X1073567Y691667D01*
X1073483Y691958D01*
X1073233Y692208D01*
X1072858Y692333D01*
X1072442D01*
X1072192Y692417D01*
X1071983Y692625D01*
X1071900Y692917D01*
X1072025Y693208D01*
X1072317Y693417D01*
X1072650Y693500D01*
X1072983Y693417D01*
X1073275Y693208D01*
X1073400Y692917D01*
X1073317Y692625D01*
X1073108Y692417D01*
X1072858Y692333D01*
X1072442D01*
X1072067Y692208D01*
X1071817Y691958D01*
X1071733Y691667D01*
X1071817Y691375D01*
X1072025Y691167D01*
X1072358Y691042D01*
X1072650Y691000D01*
G01X1062517Y687000D02*
Y689500D01*
X1063558D01*
X1063892Y689375D01*
X1064100Y689208D01*
X1064183Y688875D01*
X1064100Y688542D01*
X1063850Y688333D01*
X1063558Y688208D01*
X1062517D01*
G01X1063558D02*
X1064183Y687000D01*
G01X1065533Y687500D02*
X1065783Y687208D01*
X1066117Y687042D01*
X1066492Y687000D01*
X1066825Y687042D01*
X1067158Y687250D01*
X1067367Y687500D01*
X1067408Y687750D01*
X1067325Y688042D01*
X1067033Y688250D01*
X1066742Y688333D01*
X1066367D01*
G01X1066742D02*
X1066992Y688458D01*
X1067200Y688667D01*
X1067283Y688917D01*
X1067200Y689167D01*
X1066992Y689375D01*
X1066617Y689500D01*
X1066242Y689458D01*
X1065867Y689292D01*
G01X1068633Y687375D02*
X1068883Y687167D01*
X1069175Y687042D01*
X1069550Y687000D01*
X1069925Y687083D01*
X1070217Y687250D01*
X1070425Y687542D01*
X1070467Y687875D01*
X1070383Y688208D01*
X1070175Y688417D01*
X1069883Y688583D01*
X1069592Y688625D01*
X1069300Y688583D01*
X1068925Y688417D01*
X1069050Y689500D01*
X1070175D01*
G01X1071858Y689083D02*
X1072108Y689333D01*
X1072400Y689458D01*
X1072733Y689500D01*
X1073150Y689417D01*
X1073442Y689208D01*
X1073525Y688958D01*
X1073483Y688708D01*
X1073317Y688500D01*
X1072483Y688083D01*
X1072108Y687792D01*
X1071858Y687375D01*
X1071775Y687000D01*
X1073525D01*
G01X1062517Y695000D02*
Y697500D01*
X1063558D01*
X1063892Y697375D01*
X1064100Y697208D01*
X1064183Y696875D01*
X1064100Y696542D01*
X1063850Y696333D01*
X1063558Y696208D01*
X1062517D01*
G01X1063558D02*
X1064183Y695000D01*
G01X1065533Y695500D02*
X1065783Y695208D01*
X1066117Y695042D01*
X1066492Y695000D01*
X1066825Y695042D01*
X1067158Y695250D01*
X1067367Y695500D01*
X1067408Y695750D01*
X1067325Y696042D01*
X1067033Y696250D01*
X1066742Y696333D01*
X1066367D01*
G01X1066742D02*
X1066992Y696458D01*
X1067200Y696667D01*
X1067283Y696917D01*
X1067200Y697167D01*
X1066992Y697375D01*
X1066617Y697500D01*
X1066242Y697458D01*
X1065867Y697292D01*
G01X1068633Y695375D02*
X1068883Y695167D01*
X1069175Y695042D01*
X1069550Y695000D01*
X1069925Y695083D01*
X1070217Y695250D01*
X1070425Y695542D01*
X1070467Y695875D01*
X1070383Y696208D01*
X1070175Y696417D01*
X1069883Y696583D01*
X1069592Y696625D01*
X1069300Y696583D01*
X1068925Y696417D01*
X1069050Y697500D01*
X1070175D01*
G01X1072567Y695000D02*
X1072650Y695542D01*
X1072775Y696000D01*
X1072942Y696417D01*
X1073150Y696875D01*
X1073483Y697500D01*
X1071817D01*
G01X1062517Y683000D02*
Y685500D01*
X1063558D01*
X1063892Y685375D01*
X1064100Y685208D01*
X1064183Y684875D01*
X1064100Y684542D01*
X1063850Y684333D01*
X1063558Y684208D01*
X1062517D01*
G01X1063558D02*
X1064183Y683000D01*
G01X1065533Y683500D02*
X1065783Y683208D01*
X1066117Y683042D01*
X1066492Y683000D01*
X1066825Y683042D01*
X1067158Y683250D01*
X1067367Y683500D01*
X1067408Y683750D01*
X1067325Y684042D01*
X1067033Y684250D01*
X1066742Y684333D01*
X1066367D01*
G01X1066742D02*
X1066992Y684458D01*
X1067200Y684667D01*
X1067283Y684917D01*
X1067200Y685167D01*
X1066992Y685375D01*
X1066617Y685500D01*
X1066242Y685458D01*
X1065867Y685292D01*
G01X1068758Y684042D02*
X1069050Y684333D01*
X1069300Y684500D01*
X1069633Y684583D01*
X1069925Y684500D01*
X1070133Y684333D01*
X1070300Y684083D01*
X1070342Y683792D01*
X1070300Y683542D01*
X1070133Y683292D01*
X1069883Y683083D01*
X1069592Y683000D01*
X1069258Y683083D01*
X1068967Y683333D01*
X1068800Y683708D01*
X1068758Y684125D01*
X1068842Y684667D01*
X1068967Y684958D01*
X1069175Y685250D01*
X1069467Y685458D01*
X1069758Y685500D01*
X1070050Y685417D01*
X1070258Y685208D01*
G01X1072650Y683000D02*
X1072942Y683042D01*
X1073275Y683167D01*
X1073483Y683375D01*
X1073567Y683667D01*
X1073483Y683958D01*
X1073233Y684208D01*
X1072858Y684333D01*
X1072442D01*
X1072192Y684417D01*
X1071983Y684625D01*
X1071900Y684917D01*
X1072025Y685208D01*
X1072317Y685417D01*
X1072650Y685500D01*
X1072983Y685417D01*
X1073275Y685208D01*
X1073400Y684917D01*
X1073317Y684625D01*
X1073108Y684417D01*
X1072858Y684333D01*
X1072442D01*
X1072067Y684208D01*
X1071817Y683958D01*
X1071733Y683667D01*
X1071817Y683375D01*
X1072025Y683167D01*
X1072358Y683042D01*
X1072650Y683000D01*
G01X1062517Y711000D02*
Y713500D01*
X1063558D01*
X1063892Y713375D01*
X1064100Y713208D01*
X1064183Y712875D01*
X1064100Y712542D01*
X1063850Y712333D01*
X1063558Y712208D01*
X1062517D01*
G01X1063558D02*
X1064183Y711000D01*
G01X1065533Y711500D02*
X1065783Y711208D01*
X1066117Y711042D01*
X1066492Y711000D01*
X1066825Y711042D01*
X1067158Y711250D01*
X1067367Y711500D01*
X1067408Y711750D01*
X1067325Y712042D01*
X1067033Y712250D01*
X1066742Y712333D01*
X1066367D01*
G01X1066742D02*
X1066992Y712458D01*
X1067200Y712667D01*
X1067283Y712917D01*
X1067200Y713167D01*
X1066992Y713375D01*
X1066617Y713500D01*
X1066242Y713458D01*
X1065867Y713292D01*
G01X1070050Y711000D02*
Y713500D01*
X1068508Y711708D01*
X1070592D01*
G01X1072567Y711000D02*
X1072650Y711542D01*
X1072775Y712000D01*
X1072942Y712417D01*
X1073150Y712875D01*
X1073483Y713500D01*
X1071817D01*
G01X1062517Y699000D02*
Y701500D01*
X1063558D01*
X1063892Y701375D01*
X1064100Y701208D01*
X1064183Y700875D01*
X1064100Y700542D01*
X1063850Y700333D01*
X1063558Y700208D01*
X1062517D01*
G01X1063558D02*
X1064183Y699000D01*
G01X1065533Y699500D02*
X1065783Y699208D01*
X1066117Y699042D01*
X1066492Y699000D01*
X1066825Y699042D01*
X1067158Y699250D01*
X1067367Y699500D01*
X1067408Y699750D01*
X1067325Y700042D01*
X1067033Y700250D01*
X1066742Y700333D01*
X1066367D01*
G01X1066742D02*
X1066992Y700458D01*
X1067200Y700667D01*
X1067283Y700917D01*
X1067200Y701167D01*
X1066992Y701375D01*
X1066617Y701500D01*
X1066242Y701458D01*
X1065867Y701292D01*
G01X1068758Y700042D02*
X1069050Y700333D01*
X1069300Y700500D01*
X1069633Y700583D01*
X1069925Y700500D01*
X1070133Y700333D01*
X1070300Y700083D01*
X1070342Y699792D01*
X1070300Y699542D01*
X1070133Y699292D01*
X1069883Y699083D01*
X1069592Y699000D01*
X1069258Y699083D01*
X1068967Y699333D01*
X1068800Y699708D01*
X1068758Y700125D01*
X1068842Y700667D01*
X1068967Y700958D01*
X1069175Y701250D01*
X1069467Y701458D01*
X1069758Y701500D01*
X1070050Y701417D01*
X1070258Y701208D01*
G01X1072650Y699000D02*
Y701500D01*
X1072150Y701000D01*
G01Y699000D02*
X1073150D01*
G01X1062517Y707000D02*
Y709500D01*
X1063558D01*
X1063892Y709375D01*
X1064100Y709208D01*
X1064183Y708875D01*
X1064100Y708542D01*
X1063850Y708333D01*
X1063558Y708208D01*
X1062517D01*
G01X1063558D02*
X1064183Y707000D01*
G01X1065533Y707500D02*
X1065783Y707208D01*
X1066117Y707042D01*
X1066492Y707000D01*
X1066825Y707042D01*
X1067158Y707250D01*
X1067367Y707500D01*
X1067408Y707750D01*
X1067325Y708042D01*
X1067033Y708250D01*
X1066742Y708333D01*
X1066367D01*
G01X1066742D02*
X1066992Y708458D01*
X1067200Y708667D01*
X1067283Y708917D01*
X1067200Y709167D01*
X1066992Y709375D01*
X1066617Y709500D01*
X1066242Y709458D01*
X1065867Y709292D01*
G01X1068758Y708042D02*
X1069050Y708333D01*
X1069300Y708500D01*
X1069633Y708583D01*
X1069925Y708500D01*
X1070133Y708333D01*
X1070300Y708083D01*
X1070342Y707792D01*
X1070300Y707542D01*
X1070133Y707292D01*
X1069883Y707083D01*
X1069592Y707000D01*
X1069258Y707083D01*
X1068967Y707333D01*
X1068800Y707708D01*
X1068758Y708125D01*
X1068842Y708667D01*
X1068967Y708958D01*
X1069175Y709250D01*
X1069467Y709458D01*
X1069758Y709500D01*
X1070050Y709417D01*
X1070258Y709208D01*
G01X1071733Y707500D02*
X1071983Y707208D01*
X1072317Y707042D01*
X1072692Y707000D01*
X1073025Y707042D01*
X1073358Y707250D01*
X1073567Y707500D01*
X1073608Y707750D01*
X1073525Y708042D01*
X1073233Y708250D01*
X1072942Y708333D01*
X1072567D01*
G01X1072942D02*
X1073192Y708458D01*
X1073400Y708667D01*
X1073483Y708917D01*
X1073400Y709167D01*
X1073192Y709375D01*
X1072817Y709500D01*
X1072442Y709458D01*
X1072067Y709292D01*
G01X1062517Y703000D02*
Y705500D01*
X1063558D01*
X1063892Y705375D01*
X1064100Y705208D01*
X1064183Y704875D01*
X1064100Y704542D01*
X1063850Y704333D01*
X1063558Y704208D01*
X1062517D01*
G01X1063558D02*
X1064183Y703000D01*
G01X1065533Y703500D02*
X1065783Y703208D01*
X1066117Y703042D01*
X1066492Y703000D01*
X1066825Y703042D01*
X1067158Y703250D01*
X1067367Y703500D01*
X1067408Y703750D01*
X1067325Y704042D01*
X1067033Y704250D01*
X1066742Y704333D01*
X1066367D01*
G01X1066742D02*
X1066992Y704458D01*
X1067200Y704667D01*
X1067283Y704917D01*
X1067200Y705167D01*
X1066992Y705375D01*
X1066617Y705500D01*
X1066242Y705458D01*
X1065867Y705292D01*
G01X1068758Y704042D02*
X1069050Y704333D01*
X1069300Y704500D01*
X1069633Y704583D01*
X1069925Y704500D01*
X1070133Y704333D01*
X1070300Y704083D01*
X1070342Y703792D01*
X1070300Y703542D01*
X1070133Y703292D01*
X1069883Y703083D01*
X1069592Y703000D01*
X1069258Y703083D01*
X1068967Y703333D01*
X1068800Y703708D01*
X1068758Y704125D01*
X1068842Y704667D01*
X1068967Y704958D01*
X1069175Y705250D01*
X1069467Y705458D01*
X1069758Y705500D01*
X1070050Y705417D01*
X1070258Y705208D01*
G01X1072567Y703000D02*
X1072650Y703542D01*
X1072775Y704000D01*
X1072942Y704417D01*
X1073150Y704875D01*
X1073483Y705500D01*
X1071817D01*
G01X1062517Y715000D02*
Y717500D01*
X1063558D01*
X1063892Y717375D01*
X1064100Y717208D01*
X1064183Y716875D01*
X1064100Y716542D01*
X1063850Y716333D01*
X1063558Y716208D01*
X1062517D01*
G01X1063558D02*
X1064183Y715000D01*
G01X1065533Y715500D02*
X1065783Y715208D01*
X1066117Y715042D01*
X1066492Y715000D01*
X1066825Y715042D01*
X1067158Y715250D01*
X1067367Y715500D01*
X1067408Y715750D01*
X1067325Y716042D01*
X1067033Y716250D01*
X1066742Y716333D01*
X1066367D01*
G01X1066742D02*
X1066992Y716458D01*
X1067200Y716667D01*
X1067283Y716917D01*
X1067200Y717167D01*
X1066992Y717375D01*
X1066617Y717500D01*
X1066242Y717458D01*
X1065867Y717292D01*
G01X1070050Y715000D02*
Y717500D01*
X1068508Y715708D01*
X1070592D01*
G01X1071733Y715500D02*
X1071983Y715208D01*
X1072317Y715042D01*
X1072692Y715000D01*
X1073025Y715042D01*
X1073358Y715250D01*
X1073567Y715500D01*
X1073608Y715750D01*
X1073525Y716042D01*
X1073233Y716250D01*
X1072942Y716333D01*
X1072567D01*
G01X1072942D02*
X1073192Y716458D01*
X1073400Y716667D01*
X1073483Y716917D01*
X1073400Y717167D01*
X1073192Y717375D01*
X1072817Y717500D01*
X1072442Y717458D01*
X1072067Y717292D01*
G01X1062517Y719500D02*
Y722000D01*
X1063558D01*
X1063892Y721875D01*
X1064100Y721708D01*
X1064183Y721375D01*
X1064100Y721042D01*
X1063850Y720833D01*
X1063558Y720708D01*
X1062517D01*
G01X1063558D02*
X1064183Y719500D01*
G01X1065533Y720000D02*
X1065783Y719708D01*
X1066117Y719542D01*
X1066492Y719500D01*
X1066825Y719542D01*
X1067158Y719750D01*
X1067367Y720000D01*
X1067408Y720250D01*
X1067325Y720542D01*
X1067033Y720750D01*
X1066742Y720833D01*
X1066367D01*
G01X1066742D02*
X1066992Y720958D01*
X1067200Y721167D01*
X1067283Y721417D01*
X1067200Y721667D01*
X1066992Y721875D01*
X1066617Y722000D01*
X1066242Y721958D01*
X1065867Y721792D01*
G01X1068633Y719875D02*
X1068883Y719667D01*
X1069175Y719542D01*
X1069550Y719500D01*
X1069925Y719583D01*
X1070217Y719750D01*
X1070425Y720042D01*
X1070467Y720375D01*
X1070383Y720708D01*
X1070175Y720917D01*
X1069883Y721083D01*
X1069592Y721125D01*
X1069300Y721083D01*
X1068925Y720917D01*
X1069050Y722000D01*
X1070175D01*
G01X1073150Y719500D02*
Y722000D01*
X1071608Y720208D01*
X1073692D01*
G01X1062517Y723500D02*
Y726000D01*
X1063558D01*
X1063892Y725875D01*
X1064100Y725708D01*
X1064183Y725375D01*
X1064100Y725042D01*
X1063850Y724833D01*
X1063558Y724708D01*
X1062517D01*
G01X1063558D02*
X1064183Y723500D01*
G01X1065533Y724000D02*
X1065783Y723708D01*
X1066117Y723542D01*
X1066492Y723500D01*
X1066825Y723542D01*
X1067158Y723750D01*
X1067367Y724000D01*
X1067408Y724250D01*
X1067325Y724542D01*
X1067033Y724750D01*
X1066742Y724833D01*
X1066367D01*
G01X1066742D02*
X1066992Y724958D01*
X1067200Y725167D01*
X1067283Y725417D01*
X1067200Y725667D01*
X1066992Y725875D01*
X1066617Y726000D01*
X1066242Y725958D01*
X1065867Y725792D01*
G01X1068633Y723875D02*
X1068883Y723667D01*
X1069175Y723542D01*
X1069550Y723500D01*
X1069925Y723583D01*
X1070217Y723750D01*
X1070425Y724042D01*
X1070467Y724375D01*
X1070383Y724708D01*
X1070175Y724917D01*
X1069883Y725083D01*
X1069592Y725125D01*
X1069300Y725083D01*
X1068925Y724917D01*
X1069050Y726000D01*
X1070175D01*
G01X1072650Y723500D02*
X1072942Y723542D01*
X1073275Y723667D01*
X1073483Y723875D01*
X1073567Y724167D01*
X1073483Y724458D01*
X1073233Y724708D01*
X1072858Y724833D01*
X1072442D01*
X1072192Y724917D01*
X1071983Y725125D01*
X1071900Y725417D01*
X1072025Y725708D01*
X1072317Y725917D01*
X1072650Y726000D01*
X1072983Y725917D01*
X1073275Y725708D01*
X1073400Y725417D01*
X1073317Y725125D01*
X1073108Y724917D01*
X1072858Y724833D01*
X1072442D01*
X1072067Y724708D01*
X1071817Y724458D01*
X1071733Y724167D01*
X1071817Y723875D01*
X1072025Y723667D01*
X1072358Y723542D01*
X1072650Y723500D01*
G01X1062517Y727500D02*
Y730000D01*
X1063558D01*
X1063892Y729875D01*
X1064100Y729708D01*
X1064183Y729375D01*
X1064100Y729042D01*
X1063850Y728833D01*
X1063558Y728708D01*
X1062517D01*
G01X1063558D02*
X1064183Y727500D01*
G01X1065533Y728000D02*
X1065783Y727708D01*
X1066117Y727542D01*
X1066492Y727500D01*
X1066825Y727542D01*
X1067158Y727750D01*
X1067367Y728000D01*
X1067408Y728250D01*
X1067325Y728542D01*
X1067033Y728750D01*
X1066742Y728833D01*
X1066367D01*
G01X1066742D02*
X1066992Y728958D01*
X1067200Y729167D01*
X1067283Y729417D01*
X1067200Y729667D01*
X1066992Y729875D01*
X1066617Y730000D01*
X1066242Y729958D01*
X1065867Y729792D01*
G01X1068758Y728542D02*
X1069050Y728833D01*
X1069300Y729000D01*
X1069633Y729083D01*
X1069925Y729000D01*
X1070133Y728833D01*
X1070300Y728583D01*
X1070342Y728292D01*
X1070300Y728042D01*
X1070133Y727792D01*
X1069883Y727583D01*
X1069592Y727500D01*
X1069258Y727583D01*
X1068967Y727833D01*
X1068800Y728208D01*
X1068758Y728625D01*
X1068842Y729167D01*
X1068967Y729458D01*
X1069175Y729750D01*
X1069467Y729958D01*
X1069758Y730000D01*
X1070050Y729917D01*
X1070258Y729708D01*
G01X1071858Y728542D02*
X1072150Y728833D01*
X1072400Y729000D01*
X1072733Y729083D01*
X1073025Y729000D01*
X1073233Y728833D01*
X1073400Y728583D01*
X1073442Y728292D01*
X1073400Y728042D01*
X1073233Y727792D01*
X1072983Y727583D01*
X1072692Y727500D01*
X1072358Y727583D01*
X1072067Y727833D01*
X1071900Y728208D01*
X1071858Y728625D01*
X1071942Y729167D01*
X1072067Y729458D01*
X1072275Y729750D01*
X1072567Y729958D01*
X1072858Y730000D01*
X1073150Y729917D01*
X1073358Y729708D01*
G01X1069700Y731500D02*
Y735500D01*
X1062300D01*
G01X1069700Y739500D02*
Y743500D01*
X1062300D01*
G01X1072478Y755424D02*
X1068478D01*
Y748024D01*
G01X1055468Y747201D02*
X1052968D01*
Y748242D01*
X1053093Y748576D01*
X1053260Y748784D01*
X1053593Y748867D01*
X1053926Y748784D01*
X1054135Y748534D01*
X1054260Y748242D01*
Y747201D01*
G01Y748242D02*
X1055468Y748867D01*
G01X1054968Y750217D02*
X1055260Y750467D01*
X1055426Y750801D01*
X1055468Y751176D01*
X1055426Y751509D01*
X1055218Y751842D01*
X1054968Y752051D01*
X1054718Y752092D01*
X1054426Y752009D01*
X1054218Y751717D01*
X1054135Y751426D01*
Y751051D01*
G01Y751426D02*
X1054010Y751676D01*
X1053801Y751884D01*
X1053551Y751967D01*
X1053301Y751884D01*
X1053093Y751676D01*
X1052968Y751301D01*
X1053010Y750926D01*
X1053176Y750551D01*
G01X1052968Y754234D02*
X1053051Y753901D01*
X1053260Y753651D01*
X1053510Y753484D01*
X1053843Y753359D01*
X1054218Y753317D01*
X1054593Y753359D01*
X1054926Y753484D01*
X1055176Y753651D01*
X1055385Y753901D01*
X1055468Y754234D01*
X1055385Y754567D01*
X1055176Y754817D01*
X1054926Y754984D01*
X1054593Y755109D01*
X1054218Y755151D01*
X1053843Y755109D01*
X1053510Y754984D01*
X1053260Y754817D01*
X1053051Y754567D01*
X1052968Y754234D01*
G01Y757334D02*
X1053051Y757001D01*
X1053260Y756751D01*
X1053510Y756584D01*
X1053843Y756459D01*
X1054218Y756417D01*
X1054593Y756459D01*
X1054926Y756584D01*
X1055176Y756751D01*
X1055385Y757001D01*
X1055468Y757334D01*
X1055385Y757667D01*
X1055176Y757917D01*
X1054926Y758084D01*
X1054593Y758209D01*
X1054218Y758251D01*
X1053843Y758209D01*
X1053510Y758084D01*
X1053260Y757917D01*
X1053051Y757667D01*
X1052968Y757334D01*
G01X1063688Y747904D02*
X1067688D01*
Y755304D01*
G01X1060188Y747251D02*
X1057688D01*
Y748292D01*
X1057813Y748626D01*
X1057980Y748834D01*
X1058313Y748917D01*
X1058646Y748834D01*
X1058855Y748584D01*
X1058980Y748292D01*
Y747251D01*
G01Y748292D02*
X1060188Y748917D01*
G01X1059688Y750267D02*
X1059980Y750517D01*
X1060146Y750851D01*
X1060188Y751226D01*
X1060146Y751559D01*
X1059938Y751892D01*
X1059688Y752101D01*
X1059438Y752142D01*
X1059146Y752059D01*
X1058938Y751767D01*
X1058855Y751476D01*
Y751101D01*
G01Y751476D02*
X1058730Y751726D01*
X1058521Y751934D01*
X1058271Y752017D01*
X1058021Y751934D01*
X1057813Y751726D01*
X1057688Y751351D01*
X1057730Y750976D01*
X1057896Y750601D01*
G01X1060188Y754284D02*
X1057688D01*
X1058188Y753784D01*
G01X1060188D02*
Y754784D01*
G01Y757301D02*
X1059646Y757384D01*
X1059188Y757509D01*
X1058771Y757676D01*
X1058313Y757884D01*
X1057688Y758217D01*
Y756551D01*
G01X1072098Y763284D02*
X1068098D01*
Y755884D01*
G01X1063838Y755844D02*
X1067838D01*
Y763244D01*
G01X1065517Y843500D02*
Y846000D01*
X1066517D01*
X1066850Y845875D01*
X1067100Y845583D01*
X1067183Y845250D01*
X1067100Y844917D01*
X1066892Y844667D01*
X1066517Y844542D01*
X1065517D01*
G01X1070367Y845792D02*
X1070117Y845917D01*
X1069825Y846000D01*
X1069492D01*
X1069117Y845875D01*
X1068825Y845667D01*
X1068617Y845417D01*
X1068450Y845000D01*
X1068408Y844625D01*
X1068492Y844250D01*
X1068617Y844000D01*
X1068867Y843750D01*
X1069158Y843583D01*
X1069450Y843500D01*
X1069742D01*
X1070033Y843583D01*
X1070283Y843708D01*
X1070492Y843875D01*
G01X1071842Y843792D02*
X1072133Y843583D01*
X1072467Y843500D01*
X1072800Y843583D01*
X1073092Y843833D01*
X1073300Y844208D01*
X1073383Y844583D01*
Y845042D01*
X1073300Y845417D01*
X1073092Y845750D01*
X1072842Y845917D01*
X1072550Y846000D01*
X1072217Y845917D01*
X1071967Y845750D01*
X1071800Y845500D01*
X1071717Y845167D01*
X1071800Y844875D01*
X1072008Y844583D01*
X1072258Y844417D01*
X1072550Y844375D01*
X1072883Y844458D01*
X1073133Y844667D01*
X1073383Y845042D01*
G01X1074942Y843792D02*
X1075233Y843583D01*
X1075567Y843500D01*
X1075900Y843583D01*
X1076192Y843833D01*
X1076400Y844208D01*
X1076483Y844583D01*
Y845042D01*
X1076400Y845417D01*
X1076192Y845750D01*
X1075942Y845917D01*
X1075650Y846000D01*
X1075317Y845917D01*
X1075067Y845750D01*
X1074900Y845500D01*
X1074817Y845167D01*
X1074900Y844875D01*
X1075108Y844583D01*
X1075358Y844417D01*
X1075650Y844375D01*
X1075983Y844458D01*
X1076233Y844667D01*
X1076483Y845042D01*
G01X1065017Y857000D02*
Y859500D01*
X1066017D01*
X1066350Y859375D01*
X1066600Y859083D01*
X1066683Y858750D01*
X1066600Y858417D01*
X1066392Y858167D01*
X1066017Y858042D01*
X1065017D01*
G01X1069867Y859292D02*
X1069617Y859417D01*
X1069325Y859500D01*
X1068992D01*
X1068617Y859375D01*
X1068325Y859167D01*
X1068117Y858917D01*
X1067950Y858500D01*
X1067908Y858125D01*
X1067992Y857750D01*
X1068117Y857500D01*
X1068367Y857250D01*
X1068658Y857083D01*
X1068950Y857000D01*
X1069242D01*
X1069533Y857083D01*
X1069783Y857208D01*
X1069992Y857375D01*
G01X1071342Y857292D02*
X1071633Y857083D01*
X1071967Y857000D01*
X1072300Y857083D01*
X1072592Y857333D01*
X1072800Y857708D01*
X1072883Y858083D01*
Y858542D01*
X1072800Y858917D01*
X1072592Y859250D01*
X1072342Y859417D01*
X1072050Y859500D01*
X1071717Y859417D01*
X1071467Y859250D01*
X1071300Y859000D01*
X1071217Y858667D01*
X1071300Y858375D01*
X1071508Y858083D01*
X1071758Y857917D01*
X1072050Y857875D01*
X1072383Y857958D01*
X1072633Y858167D01*
X1072883Y858542D01*
G01X1074358Y858042D02*
X1074650Y858333D01*
X1074900Y858500D01*
X1075233Y858583D01*
X1075525Y858500D01*
X1075733Y858333D01*
X1075900Y858083D01*
X1075942Y857792D01*
X1075900Y857542D01*
X1075733Y857292D01*
X1075483Y857083D01*
X1075192Y857000D01*
X1074858Y857083D01*
X1074567Y857333D01*
X1074400Y857708D01*
X1074358Y858125D01*
X1074442Y858667D01*
X1074567Y858958D01*
X1074775Y859250D01*
X1075067Y859458D01*
X1075358Y859500D01*
X1075650Y859417D01*
X1075858Y859208D01*
G01X1065017Y849000D02*
Y851500D01*
X1066017D01*
X1066350Y851375D01*
X1066600Y851083D01*
X1066683Y850750D01*
X1066600Y850417D01*
X1066392Y850167D01*
X1066017Y850042D01*
X1065017D01*
G01X1069867Y851292D02*
X1069617Y851417D01*
X1069325Y851500D01*
X1068992D01*
X1068617Y851375D01*
X1068325Y851167D01*
X1068117Y850917D01*
X1067950Y850500D01*
X1067908Y850125D01*
X1067992Y849750D01*
X1068117Y849500D01*
X1068367Y849250D01*
X1068658Y849083D01*
X1068950Y849000D01*
X1069242D01*
X1069533Y849083D01*
X1069783Y849208D01*
X1069992Y849375D01*
G01X1071342Y849292D02*
X1071633Y849083D01*
X1071967Y849000D01*
X1072300Y849083D01*
X1072592Y849333D01*
X1072800Y849708D01*
X1072883Y850083D01*
Y850542D01*
X1072800Y850917D01*
X1072592Y851250D01*
X1072342Y851417D01*
X1072050Y851500D01*
X1071717Y851417D01*
X1071467Y851250D01*
X1071300Y851000D01*
X1071217Y850667D01*
X1071300Y850375D01*
X1071508Y850083D01*
X1071758Y849917D01*
X1072050Y849875D01*
X1072383Y849958D01*
X1072633Y850167D01*
X1072883Y850542D01*
G01X1075067Y849000D02*
X1075150Y849542D01*
X1075275Y850000D01*
X1075442Y850417D01*
X1075650Y850875D01*
X1075983Y851500D01*
X1074317D01*
G01X1065017Y873000D02*
Y875500D01*
X1066017D01*
X1066350Y875375D01*
X1066600Y875083D01*
X1066683Y874750D01*
X1066600Y874417D01*
X1066392Y874167D01*
X1066017Y874042D01*
X1065017D01*
G01X1069867Y875292D02*
X1069617Y875417D01*
X1069325Y875500D01*
X1068992D01*
X1068617Y875375D01*
X1068325Y875167D01*
X1068117Y874917D01*
X1067950Y874500D01*
X1067908Y874125D01*
X1067992Y873750D01*
X1068117Y873500D01*
X1068367Y873250D01*
X1068658Y873083D01*
X1068950Y873000D01*
X1069242D01*
X1069533Y873083D01*
X1069783Y873208D01*
X1069992Y873375D01*
G01X1071342Y873292D02*
X1071633Y873083D01*
X1071967Y873000D01*
X1072300Y873083D01*
X1072592Y873333D01*
X1072800Y873708D01*
X1072883Y874083D01*
Y874542D01*
X1072800Y874917D01*
X1072592Y875250D01*
X1072342Y875417D01*
X1072050Y875500D01*
X1071717Y875417D01*
X1071467Y875250D01*
X1071300Y875000D01*
X1071217Y874667D01*
X1071300Y874375D01*
X1071508Y874083D01*
X1071758Y873917D01*
X1072050Y873875D01*
X1072383Y873958D01*
X1072633Y874167D01*
X1072883Y874542D01*
G01X1075650Y873000D02*
Y875500D01*
X1074108Y873708D01*
X1076192D01*
G01X1065017Y865000D02*
Y867500D01*
X1066017D01*
X1066350Y867375D01*
X1066600Y867083D01*
X1066683Y866750D01*
X1066600Y866417D01*
X1066392Y866167D01*
X1066017Y866042D01*
X1065017D01*
G01X1069867Y867292D02*
X1069617Y867417D01*
X1069325Y867500D01*
X1068992D01*
X1068617Y867375D01*
X1068325Y867167D01*
X1068117Y866917D01*
X1067950Y866500D01*
X1067908Y866125D01*
X1067992Y865750D01*
X1068117Y865500D01*
X1068367Y865250D01*
X1068658Y865083D01*
X1068950Y865000D01*
X1069242D01*
X1069533Y865083D01*
X1069783Y865208D01*
X1069992Y865375D01*
G01X1071342Y865292D02*
X1071633Y865083D01*
X1071967Y865000D01*
X1072300Y865083D01*
X1072592Y865333D01*
X1072800Y865708D01*
X1072883Y866083D01*
Y866542D01*
X1072800Y866917D01*
X1072592Y867250D01*
X1072342Y867417D01*
X1072050Y867500D01*
X1071717Y867417D01*
X1071467Y867250D01*
X1071300Y867000D01*
X1071217Y866667D01*
X1071300Y866375D01*
X1071508Y866083D01*
X1071758Y865917D01*
X1072050Y865875D01*
X1072383Y865958D01*
X1072633Y866167D01*
X1072883Y866542D01*
G01X1074233Y865375D02*
X1074483Y865167D01*
X1074775Y865042D01*
X1075150Y865000D01*
X1075525Y865083D01*
X1075817Y865250D01*
X1076025Y865542D01*
X1076067Y865875D01*
X1075983Y866208D01*
X1075775Y866417D01*
X1075483Y866583D01*
X1075192Y866625D01*
X1074900Y866583D01*
X1074525Y866417D01*
X1074650Y867500D01*
X1075775D01*
G01X1058017Y905000D02*
Y907500D01*
X1059017D01*
X1059350Y907375D01*
X1059600Y907083D01*
X1059683Y906750D01*
X1059600Y906417D01*
X1059392Y906167D01*
X1059017Y906042D01*
X1058017D01*
G01X1062867Y907292D02*
X1062617Y907417D01*
X1062325Y907500D01*
X1061992D01*
X1061617Y907375D01*
X1061325Y907167D01*
X1061117Y906917D01*
X1060950Y906500D01*
X1060908Y906125D01*
X1060992Y905750D01*
X1061117Y905500D01*
X1061367Y905250D01*
X1061658Y905083D01*
X1061950Y905000D01*
X1062242D01*
X1062533Y905083D01*
X1062783Y905208D01*
X1062992Y905375D01*
G01X1064342Y905292D02*
X1064633Y905083D01*
X1064967Y905000D01*
X1065300Y905083D01*
X1065592Y905333D01*
X1065800Y905708D01*
X1065883Y906083D01*
Y906542D01*
X1065800Y906917D01*
X1065592Y907250D01*
X1065342Y907417D01*
X1065050Y907500D01*
X1064717Y907417D01*
X1064467Y907250D01*
X1064300Y907000D01*
X1064217Y906667D01*
X1064300Y906375D01*
X1064508Y906083D01*
X1064758Y905917D01*
X1065050Y905875D01*
X1065383Y905958D01*
X1065633Y906167D01*
X1065883Y906542D01*
G01X1068150Y905000D02*
Y907500D01*
X1067650Y907000D01*
G01Y905000D02*
X1068650D01*
G01X1057017Y899000D02*
Y901500D01*
X1058017D01*
X1058350Y901375D01*
X1058600Y901083D01*
X1058683Y900750D01*
X1058600Y900417D01*
X1058392Y900167D01*
X1058017Y900042D01*
X1057017D01*
G01X1061867Y901292D02*
X1061617Y901417D01*
X1061325Y901500D01*
X1060992D01*
X1060617Y901375D01*
X1060325Y901167D01*
X1060117Y900917D01*
X1059950Y900500D01*
X1059908Y900125D01*
X1059992Y899750D01*
X1060117Y899500D01*
X1060367Y899250D01*
X1060658Y899083D01*
X1060950Y899000D01*
X1061242D01*
X1061533Y899083D01*
X1061783Y899208D01*
X1061992Y899375D01*
G01X1063342Y899292D02*
X1063633Y899083D01*
X1063967Y899000D01*
X1064300Y899083D01*
X1064592Y899333D01*
X1064800Y899708D01*
X1064883Y900083D01*
Y900542D01*
X1064800Y900917D01*
X1064592Y901250D01*
X1064342Y901417D01*
X1064050Y901500D01*
X1063717Y901417D01*
X1063467Y901250D01*
X1063300Y901000D01*
X1063217Y900667D01*
X1063300Y900375D01*
X1063508Y900083D01*
X1063758Y899917D01*
X1064050Y899875D01*
X1064383Y899958D01*
X1064633Y900167D01*
X1064883Y900542D01*
G01X1067150Y901500D02*
X1066817Y901417D01*
X1066567Y901208D01*
X1066400Y900958D01*
X1066275Y900625D01*
X1066233Y900250D01*
X1066275Y899875D01*
X1066400Y899542D01*
X1066567Y899292D01*
X1066817Y899083D01*
X1067150Y899000D01*
X1067483Y899083D01*
X1067733Y899292D01*
X1067900Y899542D01*
X1068025Y899875D01*
X1068067Y900250D01*
X1068025Y900625D01*
X1067900Y900958D01*
X1067733Y901208D01*
X1067483Y901417D01*
X1067150Y901500D01*
G01X1060517Y923000D02*
Y925500D01*
X1061517D01*
X1061850Y925375D01*
X1062100Y925083D01*
X1062183Y924750D01*
X1062100Y924417D01*
X1061892Y924167D01*
X1061517Y924042D01*
X1060517D01*
G01X1063617Y923000D02*
Y925500D01*
X1064658D01*
X1064992Y925375D01*
X1065200Y925208D01*
X1065283Y924875D01*
X1065200Y924542D01*
X1064950Y924333D01*
X1064658Y924208D01*
X1063617D01*
G01X1064658D02*
X1065283Y923000D01*
G01X1067550D02*
X1067842Y923042D01*
X1068175Y923167D01*
X1068383Y923375D01*
X1068467Y923667D01*
X1068383Y923958D01*
X1068133Y924208D01*
X1067758Y924333D01*
X1067342D01*
X1067092Y924417D01*
X1066883Y924625D01*
X1066800Y924917D01*
X1066925Y925208D01*
X1067217Y925417D01*
X1067550Y925500D01*
X1067883Y925417D01*
X1068175Y925208D01*
X1068300Y924917D01*
X1068217Y924625D01*
X1068008Y924417D01*
X1067758Y924333D01*
X1067342D01*
X1066967Y924208D01*
X1066717Y923958D01*
X1066633Y923667D01*
X1066717Y923375D01*
X1066925Y923167D01*
X1067258Y923042D01*
X1067550Y923000D01*
G01X1071150D02*
Y925500D01*
X1069608Y923708D01*
X1071692D01*
G01X1058517Y913500D02*
Y916000D01*
X1059517D01*
X1059850Y915875D01*
X1060100Y915583D01*
X1060183Y915250D01*
X1060100Y914917D01*
X1059892Y914667D01*
X1059517Y914542D01*
X1058517D01*
G01X1063367Y915792D02*
X1063117Y915917D01*
X1062825Y916000D01*
X1062492D01*
X1062117Y915875D01*
X1061825Y915667D01*
X1061617Y915417D01*
X1061450Y915000D01*
X1061408Y914625D01*
X1061492Y914250D01*
X1061617Y914000D01*
X1061867Y913750D01*
X1062158Y913583D01*
X1062450Y913500D01*
X1062742D01*
X1063033Y913583D01*
X1063283Y913708D01*
X1063492Y913875D01*
G01X1064842Y913792D02*
X1065133Y913583D01*
X1065467Y913500D01*
X1065800Y913583D01*
X1066092Y913833D01*
X1066300Y914208D01*
X1066383Y914583D01*
Y915042D01*
X1066300Y915417D01*
X1066092Y915750D01*
X1065842Y915917D01*
X1065550Y916000D01*
X1065217Y915917D01*
X1064967Y915750D01*
X1064800Y915500D01*
X1064717Y915167D01*
X1064800Y914875D01*
X1065008Y914583D01*
X1065258Y914417D01*
X1065550Y914375D01*
X1065883Y914458D01*
X1066133Y914667D01*
X1066383Y915042D01*
G01X1067858Y915583D02*
X1068108Y915833D01*
X1068400Y915958D01*
X1068733Y916000D01*
X1069150Y915917D01*
X1069442Y915708D01*
X1069525Y915458D01*
X1069483Y915208D01*
X1069317Y915000D01*
X1068483Y914583D01*
X1068108Y914292D01*
X1067858Y913875D01*
X1067775Y913500D01*
X1069525D01*
G01X1075767Y69792D02*
X1075517Y69917D01*
X1075225Y70000D01*
X1074892D01*
X1074517Y69875D01*
X1074225Y69667D01*
X1074017Y69417D01*
X1073850Y69000D01*
X1073808Y68625D01*
X1073892Y68250D01*
X1074017Y68000D01*
X1074267Y67750D01*
X1074558Y67583D01*
X1074850Y67500D01*
X1075142D01*
X1075433Y67583D01*
X1075683Y67708D01*
X1075892Y67875D01*
G01X1077158Y69583D02*
X1077408Y69833D01*
X1077700Y69958D01*
X1078033Y70000D01*
X1078450Y69917D01*
X1078742Y69708D01*
X1078825Y69458D01*
X1078783Y69208D01*
X1078617Y69000D01*
X1077783Y68583D01*
X1077408Y68292D01*
X1077158Y67875D01*
X1077075Y67500D01*
X1078825D01*
G01X1081550D02*
Y70000D01*
X1080008Y68208D01*
X1082092D01*
G01X1084150Y70000D02*
X1083817Y69917D01*
X1083567Y69708D01*
X1083400Y69458D01*
X1083275Y69125D01*
X1083233Y68750D01*
X1083275Y68375D01*
X1083400Y68042D01*
X1083567Y67792D01*
X1083817Y67583D01*
X1084150Y67500D01*
X1084483Y67583D01*
X1084733Y67792D01*
X1084900Y68042D01*
X1085025Y68375D01*
X1085067Y68750D01*
X1085025Y69125D01*
X1084900Y69458D01*
X1084733Y69708D01*
X1084483Y69917D01*
X1084150Y70000D01*
G01X1078500Y80483D02*
X1080292D01*
X1080667Y80650D01*
X1080917Y80983D01*
X1081000Y81400D01*
X1080917Y81817D01*
X1080667Y82150D01*
X1080292Y82317D01*
X1078500D01*
G01X1078917Y83708D02*
X1078667Y83958D01*
X1078542Y84250D01*
X1078500Y84583D01*
X1078583Y85000D01*
X1078792Y85292D01*
X1079042Y85375D01*
X1079292Y85333D01*
X1079500Y85167D01*
X1079917Y84333D01*
X1080208Y83958D01*
X1080625Y83708D01*
X1081000Y83625D01*
Y85375D01*
G01X1078917Y86808D02*
X1078667Y87058D01*
X1078542Y87350D01*
X1078500Y87683D01*
X1078583Y88100D01*
X1078792Y88392D01*
X1079042Y88475D01*
X1079292Y88433D01*
X1079500Y88267D01*
X1079917Y87433D01*
X1080208Y87058D01*
X1080625Y86808D01*
X1081000Y86725D01*
Y88475D01*
G01X1083750Y82700D02*
X1098250D01*
G01X1083750Y87300D02*
Y82700D01*
G01X1098250Y87300D02*
X1083750D01*
G01X1077567Y120000D02*
Y122500D01*
X1078567D01*
X1078900Y122375D01*
X1079150Y122083D01*
X1079233Y121750D01*
X1079150Y121417D01*
X1078942Y121167D01*
X1078567Y121042D01*
X1077567D01*
G01X1080667Y122500D02*
Y120000D01*
X1082333D01*
G01X1083683Y120375D02*
X1083933Y120167D01*
X1084225Y120042D01*
X1084600Y120000D01*
X1084975Y120083D01*
X1085267Y120250D01*
X1085475Y120542D01*
X1085517Y120875D01*
X1085433Y121208D01*
X1085225Y121417D01*
X1084933Y121583D01*
X1084642Y121625D01*
X1084350Y121583D01*
X1083975Y121417D01*
X1084100Y122500D01*
X1085225D01*
G01X1080500Y138300D02*
Y143500D01*
G01Y138300D02*
X1087500D01*
G01X1080500Y151700D02*
Y143000D01*
G01X1087500Y151700D02*
X1080500D01*
G01X1079400Y170300D02*
X1086600D01*
G01X1079400Y183700D02*
Y170300D01*
G01X1086600Y183700D02*
X1079400D01*
G01X1072468Y198524D02*
Y211924D01*
G01X1074467Y194000D02*
Y196500D01*
X1075467D01*
X1075800Y196375D01*
X1076050Y196083D01*
X1076133Y195750D01*
X1076050Y195417D01*
X1075842Y195167D01*
X1075467Y195042D01*
X1074467D01*
G01X1077567Y194000D02*
Y196500D01*
X1078608D01*
X1078942Y196375D01*
X1079150Y196208D01*
X1079233Y195875D01*
X1079150Y195542D01*
X1078900Y195333D01*
X1078608Y195208D01*
X1077567D01*
G01X1078608D02*
X1079233Y194000D01*
G01X1081500D02*
Y196500D01*
X1081000Y196000D01*
G01Y194000D02*
X1082000D01*
G01X1084600D02*
Y196500D01*
X1084100Y196000D01*
G01Y194000D02*
X1085100D01*
G01X1086992Y194292D02*
X1087283Y194083D01*
X1087617Y194000D01*
X1087950Y194083D01*
X1088242Y194333D01*
X1088450Y194708D01*
X1088533Y195083D01*
Y195542D01*
X1088450Y195917D01*
X1088242Y196250D01*
X1087992Y196417D01*
X1087700Y196500D01*
X1087367Y196417D01*
X1087117Y196250D01*
X1086950Y196000D01*
X1086867Y195667D01*
X1086950Y195375D01*
X1087158Y195083D01*
X1087408Y194917D01*
X1087700Y194875D01*
X1088033Y194958D01*
X1088283Y195167D01*
X1088533Y195542D01*
G01X1080668Y198784D02*
Y202784D01*
X1073268D01*
G01X1083768Y213724D02*
Y226724D01*
G01X1069768Y213724D02*
X1083768D01*
G01X1069768Y226724D02*
Y213724D01*
G01X1078468Y205584D02*
X1082468D01*
Y212984D01*
G01X1085100Y264700D02*
X1068900D01*
Y233300D01*
X1085100D01*
Y264700D01*
G01X1077067Y228500D02*
Y231000D01*
X1078067D01*
X1078400Y230875D01*
X1078650Y230583D01*
X1078733Y230250D01*
X1078650Y229917D01*
X1078442Y229667D01*
X1078067Y229542D01*
X1077067D01*
G01X1081000Y228500D02*
X1080667Y228542D01*
X1080375Y228708D01*
X1080125Y228958D01*
X1079958Y229250D01*
X1079875Y229583D01*
Y229917D01*
X1079958Y230250D01*
X1080125Y230542D01*
X1080375Y230792D01*
X1080667Y230958D01*
X1081000Y231000D01*
X1081333Y230958D01*
X1081625Y230792D01*
X1081875Y230542D01*
X1082042Y230250D01*
X1082125Y229917D01*
Y229583D01*
X1082042Y229250D01*
X1081875Y228958D01*
X1081625Y228708D01*
X1081333Y228542D01*
X1081000Y228500D01*
G01X1081333Y229167D02*
X1081833Y228500D01*
G01X1083308Y230583D02*
X1083558Y230833D01*
X1083850Y230958D01*
X1084183Y231000D01*
X1084600Y230917D01*
X1084892Y230708D01*
X1084975Y230458D01*
X1084933Y230208D01*
X1084767Y230000D01*
X1083933Y229583D01*
X1083558Y229292D01*
X1083308Y228875D01*
X1083225Y228500D01*
X1084975D01*
G01X1083768Y226724D02*
X1069768D01*
G01X1072017Y266500D02*
Y269000D01*
X1073058D01*
X1073392Y268875D01*
X1073600Y268708D01*
X1073683Y268375D01*
X1073600Y268042D01*
X1073350Y267833D01*
X1073058Y267708D01*
X1072017D01*
G01X1073058D02*
X1073683Y266500D01*
G01X1075033Y266875D02*
X1075283Y266667D01*
X1075575Y266542D01*
X1075950Y266500D01*
X1076325Y266583D01*
X1076617Y266750D01*
X1076825Y267042D01*
X1076867Y267375D01*
X1076783Y267708D01*
X1076575Y267917D01*
X1076283Y268083D01*
X1075992Y268125D01*
X1075700Y268083D01*
X1075325Y267917D01*
X1075450Y269000D01*
X1076575D01*
G01X1078258Y268583D02*
X1078508Y268833D01*
X1078800Y268958D01*
X1079133Y269000D01*
X1079550Y268917D01*
X1079842Y268708D01*
X1079925Y268458D01*
X1079883Y268208D01*
X1079717Y268000D01*
X1078883Y267583D01*
X1078508Y267292D01*
X1078258Y266875D01*
X1078175Y266500D01*
X1079925D01*
G01X1082150Y269000D02*
X1081817Y268917D01*
X1081567Y268708D01*
X1081400Y268458D01*
X1081275Y268125D01*
X1081233Y267750D01*
X1081275Y267375D01*
X1081400Y267042D01*
X1081567Y266792D01*
X1081817Y266583D01*
X1082150Y266500D01*
X1082483Y266583D01*
X1082733Y266792D01*
X1082900Y267042D01*
X1083025Y267375D01*
X1083067Y267750D01*
X1083025Y268125D01*
X1082900Y268458D01*
X1082733Y268708D01*
X1082483Y268917D01*
X1082150Y269000D01*
G01X1091700Y415000D02*
X1078300D01*
G01D02*
Y430000D01*
G01X1070467Y405500D02*
Y408000D01*
X1071467D01*
X1071800Y407875D01*
X1072050Y407583D01*
X1072133Y407250D01*
X1072050Y406917D01*
X1071842Y406667D01*
X1071467Y406542D01*
X1070467D01*
G01X1075317Y407792D02*
X1075067Y407917D01*
X1074775Y408000D01*
X1074442D01*
X1074067Y407875D01*
X1073775Y407667D01*
X1073567Y407417D01*
X1073400Y407000D01*
X1073358Y406625D01*
X1073442Y406250D01*
X1073567Y406000D01*
X1073817Y405750D01*
X1074108Y405583D01*
X1074400Y405500D01*
X1074692D01*
X1074983Y405583D01*
X1075233Y405708D01*
X1075442Y405875D01*
G01X1077500Y405500D02*
Y408000D01*
X1077000Y407500D01*
G01Y405500D02*
X1078000D01*
G01X1079892Y405792D02*
X1080183Y405583D01*
X1080517Y405500D01*
X1080850Y405583D01*
X1081142Y405833D01*
X1081350Y406208D01*
X1081433Y406583D01*
Y407042D01*
X1081350Y407417D01*
X1081142Y407750D01*
X1080892Y407917D01*
X1080600Y408000D01*
X1080267Y407917D01*
X1080017Y407750D01*
X1079850Y407500D01*
X1079767Y407167D01*
X1079850Y406875D01*
X1080058Y406583D01*
X1080308Y406417D01*
X1080600Y406375D01*
X1080933Y406458D01*
X1081183Y406667D01*
X1081433Y407042D01*
G01X1082908Y407583D02*
X1083158Y407833D01*
X1083450Y407958D01*
X1083783Y408000D01*
X1084200Y407917D01*
X1084492Y407708D01*
X1084575Y407458D01*
X1084533Y407208D01*
X1084367Y407000D01*
X1083533Y406583D01*
X1083158Y406292D01*
X1082908Y405875D01*
X1082825Y405500D01*
X1084575D01*
G01X1078400Y432500D02*
X1078067Y432542D01*
X1077775Y432708D01*
X1077525Y432958D01*
X1077358Y433250D01*
X1077275Y433583D01*
Y433917D01*
X1077358Y434250D01*
X1077525Y434542D01*
X1077775Y434792D01*
X1078067Y434958D01*
X1078400Y435000D01*
X1078733Y434958D01*
X1079025Y434792D01*
X1079275Y434542D01*
X1079442Y434250D01*
X1079525Y433917D01*
Y433583D01*
X1079442Y433250D01*
X1079275Y432958D01*
X1079025Y432708D01*
X1078733Y432542D01*
X1078400Y432500D01*
G01X1078733Y433167D02*
X1079233Y432500D01*
G01X1081417D02*
X1081500Y433042D01*
X1081625Y433500D01*
X1081792Y433917D01*
X1082000Y434375D01*
X1082333Y435000D01*
X1080667D01*
G01X1084600Y432500D02*
X1084892Y432542D01*
X1085225Y432667D01*
X1085433Y432875D01*
X1085517Y433167D01*
X1085433Y433458D01*
X1085183Y433708D01*
X1084808Y433833D01*
X1084392D01*
X1084142Y433917D01*
X1083933Y434125D01*
X1083850Y434417D01*
X1083975Y434708D01*
X1084267Y434917D01*
X1084600Y435000D01*
X1084933Y434917D01*
X1085225Y434708D01*
X1085350Y434417D01*
X1085267Y434125D01*
X1085058Y433917D01*
X1084808Y433833D01*
X1084392D01*
X1084017Y433708D01*
X1083767Y433458D01*
X1083683Y433167D01*
X1083767Y432875D01*
X1083975Y432667D01*
X1084308Y432542D01*
X1084600Y432500D01*
G01X1078300Y430000D02*
X1091700D01*
G01X1086500Y437567D02*
X1084000D01*
Y438567D01*
X1084125Y438900D01*
X1084417Y439150D01*
X1084750Y439233D01*
X1085083Y439150D01*
X1085333Y438942D01*
X1085458Y438567D01*
Y437567D01*
G01X1086500Y441500D02*
X1086458Y441167D01*
X1086292Y440875D01*
X1086042Y440625D01*
X1085750Y440458D01*
X1085417Y440375D01*
X1085083D01*
X1084750Y440458D01*
X1084458Y440625D01*
X1084208Y440875D01*
X1084042Y441167D01*
X1084000Y441500D01*
X1084042Y441833D01*
X1084208Y442125D01*
X1084458Y442375D01*
X1084750Y442542D01*
X1085083Y442625D01*
X1085417D01*
X1085750Y442542D01*
X1086042Y442375D01*
X1086292Y442125D01*
X1086458Y441833D01*
X1086500Y441500D01*
G01X1085833Y441833D02*
X1086500Y442333D01*
G01X1086125Y443683D02*
X1086333Y443933D01*
X1086458Y444225D01*
X1086500Y444600D01*
X1086417Y444975D01*
X1086250Y445267D01*
X1085958Y445475D01*
X1085625Y445517D01*
X1085292Y445433D01*
X1085083Y445225D01*
X1084917Y444933D01*
X1084875Y444642D01*
X1084917Y444350D01*
X1085083Y443975D01*
X1084000Y444100D01*
Y445225D01*
G01X1086000Y464467D02*
X1083500D01*
Y465467D01*
X1083625Y465800D01*
X1083917Y466050D01*
X1084250Y466133D01*
X1084583Y466050D01*
X1084833Y465842D01*
X1084958Y465467D01*
Y464467D01*
G01X1086000Y467567D02*
X1083500D01*
Y468608D01*
X1083625Y468942D01*
X1083792Y469150D01*
X1084125Y469233D01*
X1084458Y469150D01*
X1084667Y468900D01*
X1084792Y468608D01*
Y467567D01*
G01Y468608D02*
X1086000Y469233D01*
G01Y471500D02*
X1083500D01*
X1084000Y471000D01*
G01X1086000D02*
Y472000D01*
G01Y474517D02*
X1085458Y474600D01*
X1085000Y474725D01*
X1084583Y474892D01*
X1084125Y475100D01*
X1083500Y475433D01*
Y473767D01*
G01X1084958Y476908D02*
X1084667Y477200D01*
X1084500Y477450D01*
X1084417Y477783D01*
X1084500Y478075D01*
X1084667Y478283D01*
X1084917Y478450D01*
X1085208Y478492D01*
X1085458Y478450D01*
X1085708Y478283D01*
X1085917Y478033D01*
X1086000Y477742D01*
X1085917Y477408D01*
X1085667Y477117D01*
X1085292Y476950D01*
X1084875Y476908D01*
X1084333Y476992D01*
X1084042Y477117D01*
X1083750Y477325D01*
X1083542Y477617D01*
X1083500Y477908D01*
X1083583Y478200D01*
X1083792Y478408D01*
G01X1096000Y598500D02*
X1116000D01*
Y587500D01*
X1123500D01*
Y569500D01*
X1107000D01*
Y543000D01*
X1090500D01*
Y556000D01*
X1084500D01*
Y570500D01*
X1078500D01*
Y598500D01*
X1096000D01*
G01X1084000Y574017D02*
X1081500D01*
Y575058D01*
X1081625Y575392D01*
X1081792Y575600D01*
X1082125Y575683D01*
X1082458Y575600D01*
X1082667Y575350D01*
X1082792Y575058D01*
Y574017D01*
G01Y575058D02*
X1084000Y575683D01*
G01X1083500Y577033D02*
X1083792Y577283D01*
X1083958Y577617D01*
X1084000Y577992D01*
X1083958Y578325D01*
X1083750Y578658D01*
X1083500Y578867D01*
X1083250Y578908D01*
X1082958Y578825D01*
X1082750Y578533D01*
X1082667Y578242D01*
Y577867D01*
G01Y578242D02*
X1082542Y578492D01*
X1082333Y578700D01*
X1082083Y578783D01*
X1081833Y578700D01*
X1081625Y578492D01*
X1081500Y578117D01*
X1081542Y577742D01*
X1081708Y577367D01*
G01X1081917Y580258D02*
X1081667Y580508D01*
X1081542Y580800D01*
X1081500Y581133D01*
X1081583Y581550D01*
X1081792Y581842D01*
X1082042Y581925D01*
X1082292Y581883D01*
X1082500Y581717D01*
X1082917Y580883D01*
X1083208Y580508D01*
X1083625Y580258D01*
X1084000Y580175D01*
Y581925D01*
G01Y584150D02*
X1083958Y584442D01*
X1083833Y584775D01*
X1083625Y584983D01*
X1083333Y585067D01*
X1083042Y584983D01*
X1082792Y584733D01*
X1082667Y584358D01*
Y583942D01*
X1082583Y583692D01*
X1082375Y583483D01*
X1082083Y583400D01*
X1081792Y583525D01*
X1081583Y583817D01*
X1081500Y584150D01*
X1081583Y584483D01*
X1081792Y584775D01*
X1082083Y584900D01*
X1082375Y584817D01*
X1082583Y584608D01*
X1082667Y584358D01*
Y583942D01*
X1082792Y583567D01*
X1083042Y583317D01*
X1083333Y583233D01*
X1083625Y583317D01*
X1083833Y583525D01*
X1083958Y583858D01*
X1084000Y584150D01*
G01X1074517Y612000D02*
Y614500D01*
X1075558D01*
X1075892Y614375D01*
X1076100Y614208D01*
X1076183Y613875D01*
X1076100Y613542D01*
X1075850Y613333D01*
X1075558Y613208D01*
X1074517D01*
G01X1075558D02*
X1076183Y612000D01*
G01X1077658Y614083D02*
X1077908Y614333D01*
X1078200Y614458D01*
X1078533Y614500D01*
X1078950Y614417D01*
X1079242Y614208D01*
X1079325Y613958D01*
X1079283Y613708D01*
X1079117Y613500D01*
X1078283Y613083D01*
X1077908Y612792D01*
X1077658Y612375D01*
X1077575Y612000D01*
X1079325D01*
G01X1080633Y612500D02*
X1080883Y612208D01*
X1081217Y612042D01*
X1081592Y612000D01*
X1081925Y612042D01*
X1082258Y612250D01*
X1082467Y612500D01*
X1082508Y612750D01*
X1082425Y613042D01*
X1082133Y613250D01*
X1081842Y613333D01*
X1081467D01*
G01X1081842D02*
X1082092Y613458D01*
X1082300Y613667D01*
X1082383Y613917D01*
X1082300Y614167D01*
X1082092Y614375D01*
X1081717Y614500D01*
X1081342Y614458D01*
X1080967Y614292D01*
G01X1083733Y612375D02*
X1083983Y612167D01*
X1084275Y612042D01*
X1084650Y612000D01*
X1085025Y612083D01*
X1085317Y612250D01*
X1085525Y612542D01*
X1085567Y612875D01*
X1085483Y613208D01*
X1085275Y613417D01*
X1084983Y613583D01*
X1084692Y613625D01*
X1084400Y613583D01*
X1084025Y613417D01*
X1084150Y614500D01*
X1085275D01*
G01X1074517Y620000D02*
Y622500D01*
X1075558D01*
X1075892Y622375D01*
X1076100Y622208D01*
X1076183Y621875D01*
X1076100Y621542D01*
X1075850Y621333D01*
X1075558Y621208D01*
X1074517D01*
G01X1075558D02*
X1076183Y620000D01*
G01X1077658Y622083D02*
X1077908Y622333D01*
X1078200Y622458D01*
X1078533Y622500D01*
X1078950Y622417D01*
X1079242Y622208D01*
X1079325Y621958D01*
X1079283Y621708D01*
X1079117Y621500D01*
X1078283Y621083D01*
X1077908Y620792D01*
X1077658Y620375D01*
X1077575Y620000D01*
X1079325D01*
G01X1080842Y620292D02*
X1081133Y620083D01*
X1081467Y620000D01*
X1081800Y620083D01*
X1082092Y620333D01*
X1082300Y620708D01*
X1082383Y621083D01*
Y621542D01*
X1082300Y621917D01*
X1082092Y622250D01*
X1081842Y622417D01*
X1081550Y622500D01*
X1081217Y622417D01*
X1080967Y622250D01*
X1080800Y622000D01*
X1080717Y621667D01*
X1080800Y621375D01*
X1081008Y621083D01*
X1081258Y620917D01*
X1081550Y620875D01*
X1081883Y620958D01*
X1082133Y621167D01*
X1082383Y621542D01*
G01X1083858Y622083D02*
X1084108Y622333D01*
X1084400Y622458D01*
X1084733Y622500D01*
X1085150Y622417D01*
X1085442Y622208D01*
X1085525Y621958D01*
X1085483Y621708D01*
X1085317Y621500D01*
X1084483Y621083D01*
X1084108Y620792D01*
X1083858Y620375D01*
X1083775Y620000D01*
X1085525D01*
G01X1087500Y630517D02*
X1085000D01*
Y631558D01*
X1085125Y631892D01*
X1085292Y632100D01*
X1085625Y632183D01*
X1085958Y632100D01*
X1086167Y631850D01*
X1086292Y631558D01*
Y630517D01*
G01Y631558D02*
X1087500Y632183D01*
G01X1085417Y633658D02*
X1085167Y633908D01*
X1085042Y634200D01*
X1085000Y634533D01*
X1085083Y634950D01*
X1085292Y635242D01*
X1085542Y635325D01*
X1085792Y635283D01*
X1086000Y635117D01*
X1086417Y634283D01*
X1086708Y633908D01*
X1087125Y633658D01*
X1087500Y633575D01*
Y635325D01*
G01X1087000Y636633D02*
X1087292Y636883D01*
X1087458Y637217D01*
X1087500Y637592D01*
X1087458Y637925D01*
X1087250Y638258D01*
X1087000Y638467D01*
X1086750Y638508D01*
X1086458Y638425D01*
X1086250Y638133D01*
X1086167Y637842D01*
Y637467D01*
G01Y637842D02*
X1086042Y638092D01*
X1085833Y638300D01*
X1085583Y638383D01*
X1085333Y638300D01*
X1085125Y638092D01*
X1085000Y637717D01*
X1085042Y637342D01*
X1085208Y636967D01*
G01X1087000Y639733D02*
X1087292Y639983D01*
X1087458Y640317D01*
X1087500Y640692D01*
X1087458Y641025D01*
X1087250Y641358D01*
X1087000Y641567D01*
X1086750Y641608D01*
X1086458Y641525D01*
X1086250Y641233D01*
X1086167Y640942D01*
Y640567D01*
G01Y640942D02*
X1086042Y641192D01*
X1085833Y641400D01*
X1085583Y641483D01*
X1085333Y641400D01*
X1085125Y641192D01*
X1085000Y640817D01*
X1085042Y640442D01*
X1085208Y640067D01*
G01X1074517Y616000D02*
Y618500D01*
X1075558D01*
X1075892Y618375D01*
X1076100Y618208D01*
X1076183Y617875D01*
X1076100Y617542D01*
X1075850Y617333D01*
X1075558Y617208D01*
X1074517D01*
G01X1075558D02*
X1076183Y616000D01*
G01X1077658Y618083D02*
X1077908Y618333D01*
X1078200Y618458D01*
X1078533Y618500D01*
X1078950Y618417D01*
X1079242Y618208D01*
X1079325Y617958D01*
X1079283Y617708D01*
X1079117Y617500D01*
X1078283Y617083D01*
X1077908Y616792D01*
X1077658Y616375D01*
X1077575Y616000D01*
X1079325D01*
G01X1080633Y616500D02*
X1080883Y616208D01*
X1081217Y616042D01*
X1081592Y616000D01*
X1081925Y616042D01*
X1082258Y616250D01*
X1082467Y616500D01*
X1082508Y616750D01*
X1082425Y617042D01*
X1082133Y617250D01*
X1081842Y617333D01*
X1081467D01*
G01X1081842D02*
X1082092Y617458D01*
X1082300Y617667D01*
X1082383Y617917D01*
X1082300Y618167D01*
X1082092Y618375D01*
X1081717Y618500D01*
X1081342Y618458D01*
X1080967Y618292D01*
G01X1085150Y616000D02*
Y618500D01*
X1083608Y616708D01*
X1085692D01*
G01X1075800Y633500D02*
Y629500D01*
X1083200D01*
G01X1075800D02*
Y625500D01*
X1083200D01*
G01X1075800Y646000D02*
Y642000D01*
X1083200D01*
G01X1075800Y637500D02*
Y633500D01*
X1083200D01*
G01X1075800Y650000D02*
Y646000D01*
X1083200D01*
G01X1075800Y658000D02*
Y654000D01*
X1083200D01*
G01X1075800D02*
Y650000D01*
X1083200D01*
G01X1075800Y663500D02*
Y659500D01*
X1083200D01*
G01X1075800Y677500D02*
Y673500D01*
X1083200D01*
G01X1075800D02*
Y669500D01*
X1083200D01*
G01X1075800D02*
Y665500D01*
X1083200D01*
G01X1075800Y681500D02*
Y677500D01*
X1083200D01*
G01X1075800Y693500D02*
Y689500D01*
X1083200D01*
G01X1075800D02*
Y685500D01*
X1083200D01*
G01X1075800Y697500D02*
Y693500D01*
X1083200D01*
G01X1075800Y685500D02*
Y681500D01*
X1083200D01*
G01X1075800Y713500D02*
Y709500D01*
X1083200D01*
G01X1075800Y701500D02*
Y697500D01*
X1083200D01*
G01X1075800Y709500D02*
Y705500D01*
X1083200D01*
G01X1075800D02*
Y701500D01*
X1083200D01*
G01X1086300Y732500D02*
Y730000D01*
G01X1085342Y732500D02*
X1087258D01*
G01X1088567Y730000D02*
Y732500D01*
X1089567D01*
X1089900Y732375D01*
X1090150Y732083D01*
X1090233Y731750D01*
X1090150Y731417D01*
X1089942Y731167D01*
X1089567Y731042D01*
X1088567D01*
G01X1092500Y730000D02*
Y732500D01*
X1092000Y732000D01*
G01Y730000D02*
X1093000D01*
G01X1096100D02*
Y732500D01*
X1094558Y730708D01*
X1096642D01*
G01X1097908Y731042D02*
X1098200Y731333D01*
X1098450Y731500D01*
X1098783Y731583D01*
X1099075Y731500D01*
X1099283Y731333D01*
X1099450Y731083D01*
X1099492Y730792D01*
X1099450Y730542D01*
X1099283Y730292D01*
X1099033Y730083D01*
X1098742Y730000D01*
X1098408Y730083D01*
X1098117Y730333D01*
X1097950Y730708D01*
X1097908Y731125D01*
X1097992Y731667D01*
X1098117Y731958D01*
X1098325Y732250D01*
X1098617Y732458D01*
X1098908Y732500D01*
X1099200Y732417D01*
X1099408Y732208D01*
G01X1075800Y717500D02*
Y713500D01*
X1083200D01*
G01X1075800Y724500D02*
Y720500D01*
X1083200D01*
G01X1075800Y728500D02*
Y724500D01*
X1083200D01*
G01X1075800Y732500D02*
Y728500D01*
X1083200D01*
G01X1084500Y736350D02*
X1084458Y736017D01*
X1084292Y735725D01*
X1084042Y735475D01*
X1083750Y735308D01*
X1083417Y735225D01*
X1083083D01*
X1082750Y735308D01*
X1082458Y735475D01*
X1082208Y735725D01*
X1082042Y736017D01*
X1082000Y736350D01*
X1082042Y736683D01*
X1082208Y736975D01*
X1082458Y737225D01*
X1082750Y737392D01*
X1083083Y737475D01*
X1083417D01*
X1083750Y737392D01*
X1084042Y737225D01*
X1084292Y736975D01*
X1084458Y736683D01*
X1084500Y736350D01*
G01X1084167Y738575D02*
X1084375Y738908D01*
X1084500Y739283D01*
Y739617D01*
X1084375Y739950D01*
X1084167Y740200D01*
X1083875Y740325D01*
X1083583Y740242D01*
X1083333Y740033D01*
X1083167Y739658D01*
X1083083Y739158D01*
X1082917Y738867D01*
X1082625Y738742D01*
X1082333Y738825D01*
X1082125Y739033D01*
X1082000Y739325D01*
Y739617D01*
X1082083Y739908D01*
X1082292Y740158D01*
G01X1082208Y743467D02*
X1082083Y743217D01*
X1082000Y742925D01*
Y742592D01*
X1082125Y742217D01*
X1082333Y741925D01*
X1082583Y741717D01*
X1083000Y741550D01*
X1083375Y741508D01*
X1083750Y741592D01*
X1084000Y741717D01*
X1084250Y741967D01*
X1084417Y742258D01*
X1084500Y742550D01*
Y742842D01*
X1084417Y743133D01*
X1084292Y743383D01*
X1084125Y743592D01*
G01X1084500Y745650D02*
X1082000D01*
X1082500Y745150D01*
G01X1084500D02*
Y746150D01*
G01X1080500Y735517D02*
X1078000D01*
Y736558D01*
X1078125Y736892D01*
X1078292Y737100D01*
X1078625Y737183D01*
X1078958Y737100D01*
X1079167Y736850D01*
X1079292Y736558D01*
Y735517D01*
G01Y736558D02*
X1080500Y737183D01*
G01X1078417Y738658D02*
X1078167Y738908D01*
X1078042Y739200D01*
X1078000Y739533D01*
X1078083Y739950D01*
X1078292Y740242D01*
X1078542Y740325D01*
X1078792Y740283D01*
X1079000Y740117D01*
X1079417Y739283D01*
X1079708Y738908D01*
X1080125Y738658D01*
X1080500Y738575D01*
Y740325D01*
G01X1080208Y741842D02*
X1080417Y742133D01*
X1080500Y742467D01*
X1080417Y742800D01*
X1080167Y743092D01*
X1079792Y743300D01*
X1079417Y743383D01*
X1078958D01*
X1078583Y743300D01*
X1078250Y743092D01*
X1078083Y742842D01*
X1078000Y742550D01*
X1078083Y742217D01*
X1078250Y741967D01*
X1078500Y741800D01*
X1078833Y741717D01*
X1079125Y741800D01*
X1079417Y742008D01*
X1079583Y742258D01*
X1079625Y742550D01*
X1079542Y742883D01*
X1079333Y743133D01*
X1078958Y743383D01*
G01X1080500Y745567D02*
X1079958Y745650D01*
X1079500Y745775D01*
X1079083Y745942D01*
X1078625Y746150D01*
X1078000Y746483D01*
Y744817D01*
G01X1085000Y764200D02*
X1092000D01*
Y750800D01*
X1085000D01*
Y764200D01*
G01X1076968Y755384D02*
X1072968D01*
Y747984D01*
G01X1077688Y748034D02*
X1081688D01*
Y755434D01*
G01X1085117Y768500D02*
Y766000D01*
X1086783D01*
G01X1088258Y767042D02*
X1088550Y767333D01*
X1088800Y767500D01*
X1089133Y767583D01*
X1089425Y767500D01*
X1089633Y767333D01*
X1089800Y767083D01*
X1089842Y766792D01*
X1089800Y766542D01*
X1089633Y766292D01*
X1089383Y766083D01*
X1089092Y766000D01*
X1088758Y766083D01*
X1088467Y766333D01*
X1088300Y766708D01*
X1088258Y767125D01*
X1088342Y767667D01*
X1088467Y767958D01*
X1088675Y768250D01*
X1088967Y768458D01*
X1089258Y768500D01*
X1089550Y768417D01*
X1089758Y768208D01*
G01X1085750Y834940D02*
Y832440D01*
G01X1084792Y834940D02*
X1086708D01*
G01X1088017Y832440D02*
Y834940D01*
X1089017D01*
X1089350Y834815D01*
X1089600Y834523D01*
X1089683Y834190D01*
X1089600Y833857D01*
X1089392Y833607D01*
X1089017Y833482D01*
X1088017D01*
G01X1091950Y832440D02*
Y834940D01*
X1091450Y834440D01*
G01Y832440D02*
X1092450D01*
G01X1095050D02*
X1095342Y832482D01*
X1095675Y832607D01*
X1095883Y832815D01*
X1095967Y833107D01*
X1095883Y833398D01*
X1095633Y833648D01*
X1095258Y833773D01*
X1094842D01*
X1094592Y833857D01*
X1094383Y834065D01*
X1094300Y834357D01*
X1094425Y834648D01*
X1094717Y834857D01*
X1095050Y834940D01*
X1095383Y834857D01*
X1095675Y834648D01*
X1095800Y834357D01*
X1095717Y834065D01*
X1095508Y833857D01*
X1095258Y833773D01*
X1094842D01*
X1094467Y833648D01*
X1094217Y833398D01*
X1094133Y833107D01*
X1094217Y832815D01*
X1094425Y832607D01*
X1094758Y832482D01*
X1095050Y832440D01*
G01X1098150D02*
Y834940D01*
X1097650Y834440D01*
G01Y832440D02*
X1098650D01*
G01X1087608Y843691D02*
X1085108D01*
Y844732D01*
X1085233Y845066D01*
X1085400Y845274D01*
X1085733Y845357D01*
X1086066Y845274D01*
X1086275Y845024D01*
X1086400Y844732D01*
Y843691D01*
G01Y844732D02*
X1087608Y845357D01*
G01Y848124D02*
X1085108D01*
X1086900Y846582D01*
Y848666D01*
G01X1087233Y849807D02*
X1087441Y850057D01*
X1087566Y850349D01*
X1087608Y850724D01*
X1087525Y851099D01*
X1087358Y851391D01*
X1087066Y851599D01*
X1086733Y851641D01*
X1086400Y851557D01*
X1086191Y851349D01*
X1086025Y851057D01*
X1085983Y850766D01*
X1086025Y850474D01*
X1086191Y850099D01*
X1085108Y850224D01*
Y851349D01*
G01X1086566Y853032D02*
X1086275Y853324D01*
X1086108Y853574D01*
X1086025Y853907D01*
X1086108Y854199D01*
X1086275Y854407D01*
X1086525Y854574D01*
X1086816Y854616D01*
X1087066Y854574D01*
X1087316Y854407D01*
X1087525Y854157D01*
X1087608Y853866D01*
X1087525Y853532D01*
X1087275Y853241D01*
X1086900Y853074D01*
X1086483Y853032D01*
X1085941Y853116D01*
X1085650Y853241D01*
X1085358Y853449D01*
X1085150Y853741D01*
X1085108Y854032D01*
X1085191Y854324D01*
X1085400Y854532D01*
G01X1078485Y861784D02*
Y864284D01*
X1079485D01*
X1079818Y864159D01*
X1080068Y863867D01*
X1080151Y863534D01*
X1080068Y863201D01*
X1079860Y862951D01*
X1079485Y862826D01*
X1078485D01*
G01X1083335Y864076D02*
X1083085Y864201D01*
X1082793Y864284D01*
X1082460D01*
X1082085Y864159D01*
X1081793Y863951D01*
X1081585Y863701D01*
X1081418Y863284D01*
X1081376Y862909D01*
X1081460Y862534D01*
X1081585Y862284D01*
X1081835Y862034D01*
X1082126Y861867D01*
X1082418Y861784D01*
X1082710D01*
X1083001Y861867D01*
X1083251Y861992D01*
X1083460Y862159D01*
G01X1085518Y861784D02*
X1085810Y861826D01*
X1086143Y861951D01*
X1086351Y862159D01*
X1086435Y862451D01*
X1086351Y862742D01*
X1086101Y862992D01*
X1085726Y863117D01*
X1085310D01*
X1085060Y863201D01*
X1084851Y863409D01*
X1084768Y863701D01*
X1084893Y863992D01*
X1085185Y864201D01*
X1085518Y864284D01*
X1085851Y864201D01*
X1086143Y863992D01*
X1086268Y863701D01*
X1086185Y863409D01*
X1085976Y863201D01*
X1085726Y863117D01*
X1085310D01*
X1084935Y862992D01*
X1084685Y862742D01*
X1084601Y862451D01*
X1084685Y862159D01*
X1084893Y861951D01*
X1085226Y861826D01*
X1085518Y861784D01*
G01X1088618D02*
X1088910Y861826D01*
X1089243Y861951D01*
X1089451Y862159D01*
X1089535Y862451D01*
X1089451Y862742D01*
X1089201Y862992D01*
X1088826Y863117D01*
X1088410D01*
X1088160Y863201D01*
X1087951Y863409D01*
X1087868Y863701D01*
X1087993Y863992D01*
X1088285Y864201D01*
X1088618Y864284D01*
X1088951Y864201D01*
X1089243Y863992D01*
X1089368Y863701D01*
X1089285Y863409D01*
X1089076Y863201D01*
X1088826Y863117D01*
X1088410D01*
X1088035Y862992D01*
X1087785Y862742D01*
X1087701Y862451D01*
X1087785Y862159D01*
X1087993Y861951D01*
X1088326Y861826D01*
X1088618Y861784D01*
G01X1078485Y866284D02*
Y868784D01*
X1079485D01*
X1079818Y868659D01*
X1080068Y868367D01*
X1080151Y868034D01*
X1080068Y867701D01*
X1079860Y867451D01*
X1079485Y867326D01*
X1078485D01*
G01X1081585Y866284D02*
Y868784D01*
X1082626D01*
X1082960Y868659D01*
X1083168Y868492D01*
X1083251Y868159D01*
X1083168Y867826D01*
X1082918Y867617D01*
X1082626Y867492D01*
X1081585D01*
G01X1082626D02*
X1083251Y866284D01*
G01X1085518D02*
X1085810Y866326D01*
X1086143Y866451D01*
X1086351Y866659D01*
X1086435Y866951D01*
X1086351Y867242D01*
X1086101Y867492D01*
X1085726Y867617D01*
X1085310D01*
X1085060Y867701D01*
X1084851Y867909D01*
X1084768Y868201D01*
X1084893Y868492D01*
X1085185Y868701D01*
X1085518Y868784D01*
X1085851Y868701D01*
X1086143Y868492D01*
X1086268Y868201D01*
X1086185Y867909D01*
X1085976Y867701D01*
X1085726Y867617D01*
X1085310D01*
X1084935Y867492D01*
X1084685Y867242D01*
X1084601Y866951D01*
X1084685Y866659D01*
X1084893Y866451D01*
X1085226Y866326D01*
X1085518Y866284D01*
G01X1088618D02*
Y868784D01*
X1088118Y868284D01*
G01Y866284D02*
X1089118D01*
G01X1078485Y870784D02*
Y873284D01*
X1079485D01*
X1079818Y873159D01*
X1080068Y872867D01*
X1080151Y872534D01*
X1080068Y872201D01*
X1079860Y871951D01*
X1079485Y871826D01*
X1078485D01*
G01X1081585Y870784D02*
Y873284D01*
X1082626D01*
X1082960Y873159D01*
X1083168Y872992D01*
X1083251Y872659D01*
X1083168Y872326D01*
X1082918Y872117D01*
X1082626Y871992D01*
X1081585D01*
G01X1082626D02*
X1083251Y870784D01*
G01X1085518D02*
X1085810Y870826D01*
X1086143Y870951D01*
X1086351Y871159D01*
X1086435Y871451D01*
X1086351Y871742D01*
X1086101Y871992D01*
X1085726Y872117D01*
X1085310D01*
X1085060Y872201D01*
X1084851Y872409D01*
X1084768Y872701D01*
X1084893Y872992D01*
X1085185Y873201D01*
X1085518Y873284D01*
X1085851Y873201D01*
X1086143Y872992D01*
X1086268Y872701D01*
X1086185Y872409D01*
X1085976Y872201D01*
X1085726Y872117D01*
X1085310D01*
X1084935Y871992D01*
X1084685Y871742D01*
X1084601Y871451D01*
X1084685Y871159D01*
X1084893Y870951D01*
X1085226Y870826D01*
X1085518Y870784D01*
G01X1087826Y872867D02*
X1088076Y873117D01*
X1088368Y873242D01*
X1088701Y873284D01*
X1089118Y873201D01*
X1089410Y872992D01*
X1089493Y872742D01*
X1089451Y872492D01*
X1089285Y872284D01*
X1088451Y871867D01*
X1088076Y871576D01*
X1087826Y871159D01*
X1087743Y870784D01*
X1089493D01*
G01X1071500Y896800D02*
X1079500D01*
Y879200D01*
X1071500D01*
Y896800D01*
G01X1077000Y901017D02*
X1074500D01*
Y902017D01*
X1074625Y902350D01*
X1074917Y902600D01*
X1075250Y902683D01*
X1075583Y902600D01*
X1075833Y902392D01*
X1075958Y902017D01*
Y901017D01*
G01X1077000Y904117D02*
X1074500D01*
Y905158D01*
X1074625Y905492D01*
X1074792Y905700D01*
X1075125Y905783D01*
X1075458Y905700D01*
X1075667Y905450D01*
X1075792Y905158D01*
Y904117D01*
G01Y905158D02*
X1077000Y905783D01*
G01Y907967D02*
X1076458Y908050D01*
X1076000Y908175D01*
X1075583Y908342D01*
X1075125Y908550D01*
X1074500Y908883D01*
Y907217D01*
G01X1077000Y911067D02*
X1076458Y911150D01*
X1076000Y911275D01*
X1075583Y911442D01*
X1075125Y911650D01*
X1074500Y911983D01*
Y910317D01*
G01X1085968Y896301D02*
X1083468D01*
Y897301D01*
X1083593Y897634D01*
X1083885Y897884D01*
X1084218Y897967D01*
X1084551Y897884D01*
X1084801Y897676D01*
X1084926Y897301D01*
Y896301D01*
G01X1083676Y901151D02*
X1083551Y900901D01*
X1083468Y900609D01*
Y900276D01*
X1083593Y899901D01*
X1083801Y899609D01*
X1084051Y899401D01*
X1084468Y899234D01*
X1084843Y899192D01*
X1085218Y899276D01*
X1085468Y899401D01*
X1085718Y899651D01*
X1085885Y899942D01*
X1085968Y900234D01*
Y900526D01*
X1085885Y900817D01*
X1085760Y901067D01*
X1085593Y901276D01*
G01X1085968Y903334D02*
X1085926Y903626D01*
X1085801Y903959D01*
X1085593Y904167D01*
X1085301Y904251D01*
X1085010Y904167D01*
X1084760Y903917D01*
X1084635Y903542D01*
Y903126D01*
X1084551Y902876D01*
X1084343Y902667D01*
X1084051Y902584D01*
X1083760Y902709D01*
X1083551Y903001D01*
X1083468Y903334D01*
X1083551Y903667D01*
X1083760Y903959D01*
X1084051Y904084D01*
X1084343Y904001D01*
X1084551Y903792D01*
X1084635Y903542D01*
Y903126D01*
X1084760Y902751D01*
X1085010Y902501D01*
X1085301Y902417D01*
X1085593Y902501D01*
X1085801Y902709D01*
X1085926Y903042D01*
X1085968Y903334D01*
G01X1083468Y906434D02*
X1083551Y906101D01*
X1083760Y905851D01*
X1084010Y905684D01*
X1084343Y905559D01*
X1084718Y905517D01*
X1085093Y905559D01*
X1085426Y905684D01*
X1085676Y905851D01*
X1085885Y906101D01*
X1085968Y906434D01*
X1085885Y906767D01*
X1085676Y907017D01*
X1085426Y907184D01*
X1085093Y907309D01*
X1084718Y907351D01*
X1084343Y907309D01*
X1084010Y907184D01*
X1083760Y907017D01*
X1083551Y906767D01*
X1083468Y906434D01*
G01X1096017Y55000D02*
Y57500D01*
X1097058D01*
X1097392Y57375D01*
X1097600Y57208D01*
X1097683Y56875D01*
X1097600Y56542D01*
X1097350Y56333D01*
X1097058Y56208D01*
X1096017D01*
G01X1097058D02*
X1097683Y55000D01*
G01X1099033Y55375D02*
X1099283Y55167D01*
X1099575Y55042D01*
X1099950Y55000D01*
X1100325Y55083D01*
X1100617Y55250D01*
X1100825Y55542D01*
X1100867Y55875D01*
X1100783Y56208D01*
X1100575Y56417D01*
X1100283Y56583D01*
X1099992Y56625D01*
X1099700Y56583D01*
X1099325Y56417D01*
X1099450Y57500D01*
X1100575D01*
G01X1103550Y55000D02*
Y57500D01*
X1102008Y55708D01*
X1104092D01*
G01X1105233Y55375D02*
X1105483Y55167D01*
X1105775Y55042D01*
X1106150Y55000D01*
X1106525Y55083D01*
X1106817Y55250D01*
X1107025Y55542D01*
X1107067Y55875D01*
X1106983Y56208D01*
X1106775Y56417D01*
X1106483Y56583D01*
X1106192Y56625D01*
X1105900Y56583D01*
X1105525Y56417D01*
X1105650Y57500D01*
X1106775D01*
G01X1096517Y71000D02*
Y73500D01*
X1097558D01*
X1097892Y73375D01*
X1098100Y73208D01*
X1098183Y72875D01*
X1098100Y72542D01*
X1097850Y72333D01*
X1097558Y72208D01*
X1096517D01*
G01X1097558D02*
X1098183Y71000D01*
G01X1100950D02*
Y73500D01*
X1099408Y71708D01*
X1101492D01*
G01X1104050Y71000D02*
Y73500D01*
X1102508Y71708D01*
X1104592D01*
G01X1105858Y72042D02*
X1106150Y72333D01*
X1106400Y72500D01*
X1106733Y72583D01*
X1107025Y72500D01*
X1107233Y72333D01*
X1107400Y72083D01*
X1107442Y71792D01*
X1107400Y71542D01*
X1107233Y71292D01*
X1106983Y71083D01*
X1106692Y71000D01*
X1106358Y71083D01*
X1106067Y71333D01*
X1105900Y71708D01*
X1105858Y72125D01*
X1105942Y72667D01*
X1106067Y72958D01*
X1106275Y73250D01*
X1106567Y73458D01*
X1106858Y73500D01*
X1107150Y73417D01*
X1107358Y73208D01*
G01X1096650Y85000D02*
X1098250Y86600D01*
G01Y83400D02*
X1096650Y85000D01*
G01X1098250Y82700D02*
Y87300D01*
G01X1096161Y95442D02*
X1087761D01*
Y107642D01*
X1096161D01*
Y95442D01*
G01X1095961Y105242D02*
X1091961D01*
Y97842D01*
G01X1103961Y97059D02*
X1101461D01*
Y98100D01*
X1101586Y98434D01*
X1101753Y98642D01*
X1102086Y98725D01*
X1102419Y98642D01*
X1102628Y98392D01*
X1102753Y98100D01*
Y97059D01*
G01Y98100D02*
X1103961Y98725D01*
G01Y101492D02*
X1101461D01*
X1103253Y99950D01*
Y102034D01*
G01X1103961Y104092D02*
X1101461D01*
X1101961Y103592D01*
G01X1103961D02*
Y104592D01*
G01X1101461Y107192D02*
X1101544Y106859D01*
X1101753Y106609D01*
X1102003Y106442D01*
X1102336Y106317D01*
X1102711Y106275D01*
X1103086Y106317D01*
X1103419Y106442D01*
X1103669Y106609D01*
X1103878Y106859D01*
X1103961Y107192D01*
X1103878Y107525D01*
X1103669Y107775D01*
X1103419Y107942D01*
X1103086Y108067D01*
X1102711Y108109D01*
X1102336Y108067D01*
X1102003Y107942D01*
X1101753Y107775D01*
X1101544Y107525D01*
X1101461Y107192D01*
G01X1091961Y105242D02*
X1087961D01*
Y97842D01*
G01X1090046Y113258D02*
Y110758D01*
X1091712D01*
G01X1093979D02*
X1094271Y110800D01*
X1094604Y110925D01*
X1094812Y111133D01*
X1094896Y111425D01*
X1094812Y111716D01*
X1094562Y111966D01*
X1094187Y112091D01*
X1093771D01*
X1093521Y112175D01*
X1093312Y112383D01*
X1093229Y112675D01*
X1093354Y112966D01*
X1093646Y113175D01*
X1093979Y113258D01*
X1094312Y113175D01*
X1094604Y112966D01*
X1094729Y112675D01*
X1094646Y112383D01*
X1094437Y112175D01*
X1094187Y112091D01*
X1093771D01*
X1093396Y111966D01*
X1093146Y111716D01*
X1093062Y111425D01*
X1093146Y111133D01*
X1093354Y110925D01*
X1093687Y110800D01*
X1093979Y110758D01*
G01X1093000Y139017D02*
X1090500D01*
Y140017D01*
X1090625Y140350D01*
X1090917Y140600D01*
X1091250Y140683D01*
X1091583Y140600D01*
X1091833Y140392D01*
X1091958Y140017D01*
Y139017D01*
G01X1093000Y142117D02*
X1090500D01*
Y143158D01*
X1090625Y143492D01*
X1090792Y143700D01*
X1091125Y143783D01*
X1091458Y143700D01*
X1091667Y143450D01*
X1091792Y143158D01*
Y142117D01*
G01Y143158D02*
X1093000Y143783D01*
G01Y146550D02*
X1090500D01*
X1092292Y145008D01*
Y147092D01*
G01X1092708Y148442D02*
X1092917Y148733D01*
X1093000Y149067D01*
X1092917Y149400D01*
X1092667Y149692D01*
X1092292Y149900D01*
X1091917Y149983D01*
X1091458D01*
X1091083Y149900D01*
X1090750Y149692D01*
X1090583Y149442D01*
X1090500Y149150D01*
X1090583Y148817D01*
X1090750Y148567D01*
X1091000Y148400D01*
X1091333Y148317D01*
X1091625Y148400D01*
X1091917Y148608D01*
X1092083Y148858D01*
X1092125Y149150D01*
X1092042Y149483D01*
X1091833Y149733D01*
X1091458Y149983D01*
G01X1087500Y138300D02*
Y146100D01*
G01Y145300D02*
Y151700D01*
G01X1086600Y170300D02*
Y183700D01*
G01X1097000Y157017D02*
X1094500D01*
Y158017D01*
X1094625Y158350D01*
X1094917Y158600D01*
X1095250Y158683D01*
X1095583Y158600D01*
X1095833Y158392D01*
X1095958Y158017D01*
Y157017D01*
G01X1094708Y161867D02*
X1094583Y161617D01*
X1094500Y161325D01*
Y160992D01*
X1094625Y160617D01*
X1094833Y160325D01*
X1095083Y160117D01*
X1095500Y159950D01*
X1095875Y159908D01*
X1096250Y159992D01*
X1096500Y160117D01*
X1096750Y160367D01*
X1096917Y160658D01*
X1097000Y160950D01*
Y161242D01*
X1096917Y161533D01*
X1096792Y161783D01*
X1096625Y161992D01*
G01X1097000Y164550D02*
X1094500D01*
X1096292Y163008D01*
Y165092D01*
G01X1097000Y167150D02*
X1094500D01*
X1095000Y166650D01*
G01X1097000D02*
Y167650D01*
G01X1101500Y157017D02*
X1099000D01*
Y158017D01*
X1099125Y158350D01*
X1099417Y158600D01*
X1099750Y158683D01*
X1100083Y158600D01*
X1100333Y158392D01*
X1100458Y158017D01*
Y157017D01*
G01X1099208Y161867D02*
X1099083Y161617D01*
X1099000Y161325D01*
Y160992D01*
X1099125Y160617D01*
X1099333Y160325D01*
X1099583Y160117D01*
X1100000Y159950D01*
X1100375Y159908D01*
X1100750Y159992D01*
X1101000Y160117D01*
X1101250Y160367D01*
X1101417Y160658D01*
X1101500Y160950D01*
Y161242D01*
X1101417Y161533D01*
X1101292Y161783D01*
X1101125Y161992D01*
G01X1101500Y164550D02*
X1099000D01*
X1100792Y163008D01*
Y165092D01*
G01X1099417Y166358D02*
X1099167Y166608D01*
X1099042Y166900D01*
X1099000Y167233D01*
X1099083Y167650D01*
X1099292Y167942D01*
X1099542Y168025D01*
X1099792Y167983D01*
X1100000Y167817D01*
X1100417Y166983D01*
X1100708Y166608D01*
X1101125Y166358D01*
X1101500Y166275D01*
Y168025D01*
G01X1092500Y157017D02*
X1090000D01*
Y158017D01*
X1090125Y158350D01*
X1090417Y158600D01*
X1090750Y158683D01*
X1091083Y158600D01*
X1091333Y158392D01*
X1091458Y158017D01*
Y157017D01*
G01X1090208Y161867D02*
X1090083Y161617D01*
X1090000Y161325D01*
Y160992D01*
X1090125Y160617D01*
X1090333Y160325D01*
X1090583Y160117D01*
X1091000Y159950D01*
X1091375Y159908D01*
X1091750Y159992D01*
X1092000Y160117D01*
X1092250Y160367D01*
X1092417Y160658D01*
X1092500Y160950D01*
Y161242D01*
X1092417Y161533D01*
X1092292Y161783D01*
X1092125Y161992D01*
G01X1092500Y164550D02*
X1090000D01*
X1091792Y163008D01*
Y165092D01*
G01X1092125Y166233D02*
X1092333Y166483D01*
X1092458Y166775D01*
X1092500Y167150D01*
X1092417Y167525D01*
X1092250Y167817D01*
X1091958Y168025D01*
X1091625Y168067D01*
X1091292Y167983D01*
X1091083Y167775D01*
X1090917Y167483D01*
X1090875Y167192D01*
X1090917Y166900D01*
X1091083Y166525D01*
X1090000Y166650D01*
Y167775D01*
G01X1099500Y172567D02*
X1097000D01*
Y173567D01*
X1097125Y173900D01*
X1097417Y174150D01*
X1097750Y174233D01*
X1098083Y174150D01*
X1098333Y173942D01*
X1098458Y173567D01*
Y172567D01*
G01X1097000Y175667D02*
X1099500D01*
Y177333D01*
G01Y180100D02*
X1097000D01*
X1098792Y178558D01*
Y180642D01*
G01X1091500Y172517D02*
X1089000D01*
Y173517D01*
X1089125Y173850D01*
X1089417Y174100D01*
X1089750Y174183D01*
X1090083Y174100D01*
X1090333Y173892D01*
X1090458Y173517D01*
Y172517D01*
G01X1089208Y177367D02*
X1089083Y177117D01*
X1089000Y176825D01*
Y176492D01*
X1089125Y176117D01*
X1089333Y175825D01*
X1089583Y175617D01*
X1090000Y175450D01*
X1090375Y175408D01*
X1090750Y175492D01*
X1091000Y175617D01*
X1091250Y175867D01*
X1091417Y176158D01*
X1091500Y176450D01*
Y176742D01*
X1091417Y177033D01*
X1091292Y177283D01*
X1091125Y177492D01*
G01X1091500Y180050D02*
X1089000D01*
X1090792Y178508D01*
Y180592D01*
G01X1091000Y181733D02*
X1091292Y181983D01*
X1091458Y182317D01*
X1091500Y182692D01*
X1091458Y183025D01*
X1091250Y183358D01*
X1091000Y183567D01*
X1090750Y183608D01*
X1090458Y183525D01*
X1090250Y183233D01*
X1090167Y182942D01*
Y182567D01*
G01Y182942D02*
X1090042Y183192D01*
X1089833Y183400D01*
X1089583Y183483D01*
X1089333Y183400D01*
X1089125Y183192D01*
X1089000Y182817D01*
X1089042Y182442D01*
X1089208Y182067D01*
G01X1095500Y172517D02*
X1093000D01*
Y173517D01*
X1093125Y173850D01*
X1093417Y174100D01*
X1093750Y174183D01*
X1094083Y174100D01*
X1094333Y173892D01*
X1094458Y173517D01*
Y172517D01*
G01X1093208Y177367D02*
X1093083Y177117D01*
X1093000Y176825D01*
Y176492D01*
X1093125Y176117D01*
X1093333Y175825D01*
X1093583Y175617D01*
X1094000Y175450D01*
X1094375Y175408D01*
X1094750Y175492D01*
X1095000Y175617D01*
X1095250Y175867D01*
X1095417Y176158D01*
X1095500Y176450D01*
Y176742D01*
X1095417Y177033D01*
X1095292Y177283D01*
X1095125Y177492D01*
G01X1095500Y180050D02*
X1093000D01*
X1094792Y178508D01*
Y180592D01*
G01X1095500Y183150D02*
X1093000D01*
X1094792Y181608D01*
Y183692D01*
G01X1089000Y202467D02*
X1086500D01*
Y203467D01*
X1086625Y203800D01*
X1086917Y204050D01*
X1087250Y204133D01*
X1087583Y204050D01*
X1087833Y203842D01*
X1087958Y203467D01*
Y202467D01*
G01X1089000Y205567D02*
X1086500D01*
Y206608D01*
X1086625Y206942D01*
X1086792Y207150D01*
X1087125Y207233D01*
X1087458Y207150D01*
X1087667Y206900D01*
X1087792Y206608D01*
Y205567D01*
G01Y206608D02*
X1089000Y207233D01*
G01Y209500D02*
X1086500D01*
X1087000Y209000D01*
G01X1089000D02*
Y210000D01*
G01Y212600D02*
X1086500D01*
X1087000Y212100D01*
G01X1089000D02*
Y213100D01*
G01X1087958Y214908D02*
X1087667Y215200D01*
X1087500Y215450D01*
X1087417Y215783D01*
X1087500Y216075D01*
X1087667Y216283D01*
X1087917Y216450D01*
X1088208Y216492D01*
X1088458Y216450D01*
X1088708Y216283D01*
X1088917Y216033D01*
X1089000Y215742D01*
X1088917Y215408D01*
X1088667Y215117D01*
X1088292Y214950D01*
X1087875Y214908D01*
X1087333Y214992D01*
X1087042Y215117D01*
X1086750Y215325D01*
X1086542Y215617D01*
X1086500Y215908D01*
X1086583Y216200D01*
X1086792Y216408D01*
G01X1093767Y266292D02*
X1093517Y266417D01*
X1093225Y266500D01*
X1092892D01*
X1092517Y266375D01*
X1092225Y266167D01*
X1092017Y265917D01*
X1091850Y265500D01*
X1091808Y265125D01*
X1091892Y264750D01*
X1092017Y264500D01*
X1092267Y264250D01*
X1092558Y264083D01*
X1092850Y264000D01*
X1093142D01*
X1093433Y264083D01*
X1093683Y264208D01*
X1093892Y264375D01*
G01X1095158Y266083D02*
X1095408Y266333D01*
X1095700Y266458D01*
X1096033Y266500D01*
X1096450Y266417D01*
X1096742Y266208D01*
X1096825Y265958D01*
X1096783Y265708D01*
X1096617Y265500D01*
X1095783Y265083D01*
X1095408Y264792D01*
X1095158Y264375D01*
X1095075Y264000D01*
X1096825D01*
G01X1098258Y265042D02*
X1098550Y265333D01*
X1098800Y265500D01*
X1099133Y265583D01*
X1099425Y265500D01*
X1099633Y265333D01*
X1099800Y265083D01*
X1099842Y264792D01*
X1099800Y264542D01*
X1099633Y264292D01*
X1099383Y264083D01*
X1099092Y264000D01*
X1098758Y264083D01*
X1098467Y264333D01*
X1098300Y264708D01*
X1098258Y265125D01*
X1098342Y265667D01*
X1098467Y265958D01*
X1098675Y266250D01*
X1098967Y266458D01*
X1099258Y266500D01*
X1099550Y266417D01*
X1099758Y266208D01*
G01X1101233Y264375D02*
X1101483Y264167D01*
X1101775Y264042D01*
X1102150Y264000D01*
X1102525Y264083D01*
X1102817Y264250D01*
X1103025Y264542D01*
X1103067Y264875D01*
X1102983Y265208D01*
X1102775Y265417D01*
X1102483Y265583D01*
X1102192Y265625D01*
X1101900Y265583D01*
X1101525Y265417D01*
X1101650Y266500D01*
X1102775D01*
G01X1097983Y280000D02*
Y278208D01*
X1098150Y277833D01*
X1098483Y277583D01*
X1098900Y277500D01*
X1099317Y277583D01*
X1099650Y277833D01*
X1099817Y278208D01*
Y280000D01*
G01X1101083Y278000D02*
X1101333Y277708D01*
X1101667Y277542D01*
X1102042Y277500D01*
X1102375Y277542D01*
X1102708Y277750D01*
X1102917Y278000D01*
X1102958Y278250D01*
X1102875Y278542D01*
X1102583Y278750D01*
X1102292Y278833D01*
X1101917D01*
G01X1102292D02*
X1102542Y278958D01*
X1102750Y279167D01*
X1102833Y279417D01*
X1102750Y279667D01*
X1102542Y279875D01*
X1102167Y280000D01*
X1101792Y279958D01*
X1101417Y279792D01*
G01X1105600Y277500D02*
Y280000D01*
X1104058Y278208D01*
X1106142D01*
G01X1095000Y397467D02*
X1092500D01*
Y398467D01*
X1092625Y398800D01*
X1092917Y399050D01*
X1093250Y399133D01*
X1093583Y399050D01*
X1093833Y398842D01*
X1093958Y398467D01*
Y397467D01*
G01X1095000Y400567D02*
X1092500D01*
Y401608D01*
X1092625Y401942D01*
X1092792Y402150D01*
X1093125Y402233D01*
X1093458Y402150D01*
X1093667Y401900D01*
X1093792Y401608D01*
Y400567D01*
G01Y401608D02*
X1095000Y402233D01*
G01Y404500D02*
X1092500D01*
X1093000Y404000D01*
G01X1095000D02*
Y405000D01*
G01Y407517D02*
X1094458Y407600D01*
X1094000Y407725D01*
X1093583Y407892D01*
X1093125Y408100D01*
X1092500Y408433D01*
Y406767D01*
G01X1095000Y410617D02*
X1094458Y410700D01*
X1094000Y410825D01*
X1093583Y410992D01*
X1093125Y411200D01*
X1092500Y411533D01*
Y409867D01*
G01X1091700Y430000D02*
Y415000D01*
G01X1099500Y405467D02*
X1097000D01*
Y406467D01*
X1097125Y406800D01*
X1097417Y407050D01*
X1097750Y407133D01*
X1098083Y407050D01*
X1098333Y406842D01*
X1098458Y406467D01*
Y405467D01*
G01X1099500Y408567D02*
X1097000D01*
Y409608D01*
X1097125Y409942D01*
X1097292Y410150D01*
X1097625Y410233D01*
X1097958Y410150D01*
X1098167Y409900D01*
X1098292Y409608D01*
Y408567D01*
G01Y409608D02*
X1099500Y410233D01*
G01Y412500D02*
X1097000D01*
X1097500Y412000D01*
G01X1099500D02*
Y413000D01*
G01Y415517D02*
X1098958Y415600D01*
X1098500Y415725D01*
X1098083Y415892D01*
X1097625Y416100D01*
X1097000Y416433D01*
Y414767D01*
G01X1099125Y417783D02*
X1099333Y418033D01*
X1099458Y418325D01*
X1099500Y418700D01*
X1099417Y419075D01*
X1099250Y419367D01*
X1098958Y419575D01*
X1098625Y419617D01*
X1098292Y419533D01*
X1098083Y419325D01*
X1097917Y419033D01*
X1097875Y418742D01*
X1097917Y418450D01*
X1098083Y418075D01*
X1097000Y418200D01*
Y419325D01*
G01X1091500Y414200D02*
X1087500D01*
Y406800D01*
G01X1089000Y433500D02*
X1102000D01*
G01X1089000Y447500D02*
Y433500D01*
G01X1104700Y426000D02*
Y430000D01*
X1097300D01*
G01X1102000Y447500D02*
X1089000D01*
G01X1090000Y459700D02*
X1086000D01*
Y452300D01*
G01X1090500Y464467D02*
X1088000D01*
Y465467D01*
X1088125Y465800D01*
X1088417Y466050D01*
X1088750Y466133D01*
X1089083Y466050D01*
X1089333Y465842D01*
X1089458Y465467D01*
Y464467D01*
G01X1090500Y467567D02*
X1088000D01*
Y468608D01*
X1088125Y468942D01*
X1088292Y469150D01*
X1088625Y469233D01*
X1088958Y469150D01*
X1089167Y468900D01*
X1089292Y468608D01*
Y467567D01*
G01Y468608D02*
X1090500Y469233D01*
G01Y471500D02*
X1088000D01*
X1088500Y471000D01*
G01X1090500D02*
Y472000D01*
G01Y474600D02*
X1090458Y474892D01*
X1090333Y475225D01*
X1090125Y475433D01*
X1089833Y475517D01*
X1089542Y475433D01*
X1089292Y475183D01*
X1089167Y474808D01*
Y474392D01*
X1089083Y474142D01*
X1088875Y473933D01*
X1088583Y473850D01*
X1088292Y473975D01*
X1088083Y474267D01*
X1088000Y474600D01*
X1088083Y474933D01*
X1088292Y475225D01*
X1088583Y475350D01*
X1088875Y475267D01*
X1089083Y475058D01*
X1089167Y474808D01*
Y474392D01*
X1089292Y474017D01*
X1089542Y473767D01*
X1089833Y473683D01*
X1090125Y473767D01*
X1090333Y473975D01*
X1090458Y474308D01*
X1090500Y474600D01*
G01X1088000Y477700D02*
X1088083Y477367D01*
X1088292Y477117D01*
X1088542Y476950D01*
X1088875Y476825D01*
X1089250Y476783D01*
X1089625Y476825D01*
X1089958Y476950D01*
X1090208Y477117D01*
X1090417Y477367D01*
X1090500Y477700D01*
X1090417Y478033D01*
X1090208Y478283D01*
X1089958Y478450D01*
X1089625Y478575D01*
X1089250Y478617D01*
X1088875Y478575D01*
X1088542Y478450D01*
X1088292Y478283D01*
X1088083Y478033D01*
X1088000Y477700D01*
G01X1094500Y459700D02*
X1090500D01*
Y452300D01*
G01X1099500Y464467D02*
X1097000D01*
Y465467D01*
X1097125Y465800D01*
X1097417Y466050D01*
X1097750Y466133D01*
X1098083Y466050D01*
X1098333Y465842D01*
X1098458Y465467D01*
Y464467D01*
G01X1099500Y467567D02*
X1097000D01*
Y468608D01*
X1097125Y468942D01*
X1097292Y469150D01*
X1097625Y469233D01*
X1097958Y469150D01*
X1098167Y468900D01*
X1098292Y468608D01*
Y467567D01*
G01Y468608D02*
X1099500Y469233D01*
G01Y471500D02*
X1097000D01*
X1097500Y471000D01*
G01X1099500D02*
Y472000D01*
G01Y474517D02*
X1098958Y474600D01*
X1098500Y474725D01*
X1098083Y474892D01*
X1097625Y475100D01*
X1097000Y475433D01*
Y473767D01*
G01X1099000Y476783D02*
X1099292Y477033D01*
X1099458Y477367D01*
X1099500Y477742D01*
X1099458Y478075D01*
X1099250Y478408D01*
X1099000Y478617D01*
X1098750Y478658D01*
X1098458Y478575D01*
X1098250Y478283D01*
X1098167Y477992D01*
Y477617D01*
G01Y477992D02*
X1098042Y478242D01*
X1097833Y478450D01*
X1097583Y478533D01*
X1097333Y478450D01*
X1097125Y478242D01*
X1097000Y477867D01*
X1097042Y477492D01*
X1097208Y477117D01*
G01X1099500Y452300D02*
X1103500D01*
Y459700D01*
G01X1095000Y464467D02*
X1092500D01*
Y465467D01*
X1092625Y465800D01*
X1092917Y466050D01*
X1093250Y466133D01*
X1093583Y466050D01*
X1093833Y465842D01*
X1093958Y465467D01*
Y464467D01*
G01X1095000Y467567D02*
X1092500D01*
Y468608D01*
X1092625Y468942D01*
X1092792Y469150D01*
X1093125Y469233D01*
X1093458Y469150D01*
X1093667Y468900D01*
X1093792Y468608D01*
Y467567D01*
G01Y468608D02*
X1095000Y469233D01*
G01Y471500D02*
X1092500D01*
X1093000Y471000D01*
G01X1095000D02*
Y472000D01*
G01Y474517D02*
X1094458Y474600D01*
X1094000Y474725D01*
X1093583Y474892D01*
X1093125Y475100D01*
X1092500Y475433D01*
Y473767D01*
G01X1095000Y478200D02*
X1092500D01*
X1094292Y476658D01*
Y478742D01*
G01X1095000Y452300D02*
X1099000D01*
Y459700D01*
G01X1099500Y545517D02*
X1097000D01*
Y546558D01*
X1097125Y546892D01*
X1097292Y547100D01*
X1097625Y547183D01*
X1097958Y547100D01*
X1098167Y546850D01*
X1098292Y546558D01*
Y545517D01*
G01Y546558D02*
X1099500Y547183D01*
G01Y549950D02*
X1097000D01*
X1098792Y548408D01*
Y550492D01*
G01X1097417Y551758D02*
X1097167Y552008D01*
X1097042Y552300D01*
X1097000Y552633D01*
X1097083Y553050D01*
X1097292Y553342D01*
X1097542Y553425D01*
X1097792Y553383D01*
X1098000Y553217D01*
X1098417Y552383D01*
X1098708Y552008D01*
X1099125Y551758D01*
X1099500Y551675D01*
Y553425D01*
G01Y555650D02*
X1097000D01*
X1097500Y555150D01*
G01X1099500D02*
Y556150D01*
G01X1095000Y545517D02*
X1092500D01*
Y546558D01*
X1092625Y546892D01*
X1092792Y547100D01*
X1093125Y547183D01*
X1093458Y547100D01*
X1093667Y546850D01*
X1093792Y546558D01*
Y545517D01*
G01Y546558D02*
X1095000Y547183D01*
G01X1093958Y548658D02*
X1093667Y548950D01*
X1093500Y549200D01*
X1093417Y549533D01*
X1093500Y549825D01*
X1093667Y550033D01*
X1093917Y550200D01*
X1094208Y550242D01*
X1094458Y550200D01*
X1094708Y550033D01*
X1094917Y549783D01*
X1095000Y549492D01*
X1094917Y549158D01*
X1094667Y548867D01*
X1094292Y548700D01*
X1093875Y548658D01*
X1093333Y548742D01*
X1093042Y548867D01*
X1092750Y549075D01*
X1092542Y549367D01*
X1092500Y549658D01*
X1092583Y549950D01*
X1092792Y550158D01*
G01X1095000Y552550D02*
X1092500D01*
X1093000Y552050D01*
G01X1095000D02*
Y553050D01*
G01X1093958Y554858D02*
X1093667Y555150D01*
X1093500Y555400D01*
X1093417Y555733D01*
X1093500Y556025D01*
X1093667Y556233D01*
X1093917Y556400D01*
X1094208Y556442D01*
X1094458Y556400D01*
X1094708Y556233D01*
X1094917Y555983D01*
X1095000Y555692D01*
X1094917Y555358D01*
X1094667Y555067D01*
X1094292Y554900D01*
X1093875Y554858D01*
X1093333Y554942D01*
X1093042Y555067D01*
X1092750Y555275D01*
X1092542Y555567D01*
X1092500Y555858D01*
X1092583Y556150D01*
X1092792Y556358D01*
G01X1089500Y559517D02*
X1087000D01*
Y560558D01*
X1087125Y560892D01*
X1087292Y561100D01*
X1087625Y561183D01*
X1087958Y561100D01*
X1088167Y560850D01*
X1088292Y560558D01*
Y559517D01*
G01Y560558D02*
X1089500Y561183D01*
G01Y563950D02*
X1087000D01*
X1088792Y562408D01*
Y564492D01*
G01X1089500Y566467D02*
X1088958Y566550D01*
X1088500Y566675D01*
X1088083Y566842D01*
X1087625Y567050D01*
X1087000Y567383D01*
Y565717D01*
G01X1088458Y568858D02*
X1088167Y569150D01*
X1088000Y569400D01*
X1087917Y569733D01*
X1088000Y570025D01*
X1088167Y570233D01*
X1088417Y570400D01*
X1088708Y570442D01*
X1088958Y570400D01*
X1089208Y570233D01*
X1089417Y569983D01*
X1089500Y569692D01*
X1089417Y569358D01*
X1089167Y569067D01*
X1088792Y568900D01*
X1088375Y568858D01*
X1087833Y568942D01*
X1087542Y569067D01*
X1087250Y569275D01*
X1087042Y569567D01*
X1087000Y569858D01*
X1087083Y570150D01*
X1087292Y570358D01*
G01X1103000Y559517D02*
X1100500D01*
Y560558D01*
X1100625Y560892D01*
X1100792Y561100D01*
X1101125Y561183D01*
X1101458Y561100D01*
X1101667Y560850D01*
X1101792Y560558D01*
Y559517D01*
G01Y560558D02*
X1103000Y561183D01*
G01X1101958Y562658D02*
X1101667Y562950D01*
X1101500Y563200D01*
X1101417Y563533D01*
X1101500Y563825D01*
X1101667Y564033D01*
X1101917Y564200D01*
X1102208Y564242D01*
X1102458Y564200D01*
X1102708Y564033D01*
X1102917Y563783D01*
X1103000Y563492D01*
X1102917Y563158D01*
X1102667Y562867D01*
X1102292Y562700D01*
X1101875Y562658D01*
X1101333Y562742D01*
X1101042Y562867D01*
X1100750Y563075D01*
X1100542Y563367D01*
X1100500Y563658D01*
X1100583Y563950D01*
X1100792Y564158D01*
G01X1103000Y566550D02*
X1100500D01*
X1101000Y566050D01*
G01X1103000D02*
Y567050D01*
G01Y569567D02*
X1102458Y569650D01*
X1102000Y569775D01*
X1101583Y569942D01*
X1101125Y570150D01*
X1100500Y570483D01*
Y568817D01*
G01X1094000Y559517D02*
X1091500D01*
Y560558D01*
X1091625Y560892D01*
X1091792Y561100D01*
X1092125Y561183D01*
X1092458Y561100D01*
X1092667Y560850D01*
X1092792Y560558D01*
Y559517D01*
G01Y560558D02*
X1094000Y561183D01*
G01Y563950D02*
X1091500D01*
X1093292Y562408D01*
Y564492D01*
G01X1091917Y565758D02*
X1091667Y566008D01*
X1091542Y566300D01*
X1091500Y566633D01*
X1091583Y567050D01*
X1091792Y567342D01*
X1092042Y567425D01*
X1092292Y567383D01*
X1092500Y567217D01*
X1092917Y566383D01*
X1093208Y566008D01*
X1093625Y565758D01*
X1094000Y565675D01*
Y567425D01*
G01X1091917Y568858D02*
X1091667Y569108D01*
X1091542Y569400D01*
X1091500Y569733D01*
X1091583Y570150D01*
X1091792Y570442D01*
X1092042Y570525D01*
X1092292Y570483D01*
X1092500Y570317D01*
X1092917Y569483D01*
X1093208Y569108D01*
X1093625Y568858D01*
X1094000Y568775D01*
Y570525D01*
G01X1098500Y559517D02*
X1096000D01*
Y560558D01*
X1096125Y560892D01*
X1096292Y561100D01*
X1096625Y561183D01*
X1096958Y561100D01*
X1097167Y560850D01*
X1097292Y560558D01*
Y559517D01*
G01Y560558D02*
X1098500Y561183D01*
G01X1097458Y562658D02*
X1097167Y562950D01*
X1097000Y563200D01*
X1096917Y563533D01*
X1097000Y563825D01*
X1097167Y564033D01*
X1097417Y564200D01*
X1097708Y564242D01*
X1097958Y564200D01*
X1098208Y564033D01*
X1098417Y563783D01*
X1098500Y563492D01*
X1098417Y563158D01*
X1098167Y562867D01*
X1097792Y562700D01*
X1097375Y562658D01*
X1096833Y562742D01*
X1096542Y562867D01*
X1096250Y563075D01*
X1096042Y563367D01*
X1096000Y563658D01*
X1096083Y563950D01*
X1096292Y564158D01*
G01X1098500Y566550D02*
X1096000D01*
X1096500Y566050D01*
G01X1098500D02*
Y567050D01*
G01X1098125Y568733D02*
X1098333Y568983D01*
X1098458Y569275D01*
X1098500Y569650D01*
X1098417Y570025D01*
X1098250Y570317D01*
X1097958Y570525D01*
X1097625Y570567D01*
X1097292Y570483D01*
X1097083Y570275D01*
X1096917Y569983D01*
X1096875Y569692D01*
X1096917Y569400D01*
X1097083Y569025D01*
X1096000Y569150D01*
Y570275D01*
G01X1088000Y574017D02*
X1085500D01*
Y575058D01*
X1085625Y575392D01*
X1085792Y575600D01*
X1086125Y575683D01*
X1086458Y575600D01*
X1086667Y575350D01*
X1086792Y575058D01*
Y574017D01*
G01Y575058D02*
X1088000Y575683D01*
G01X1085917Y577158D02*
X1085667Y577408D01*
X1085542Y577700D01*
X1085500Y578033D01*
X1085583Y578450D01*
X1085792Y578742D01*
X1086042Y578825D01*
X1086292Y578783D01*
X1086500Y578617D01*
X1086917Y577783D01*
X1087208Y577408D01*
X1087625Y577158D01*
X1088000Y577075D01*
Y578825D01*
G01X1087625Y580133D02*
X1087833Y580383D01*
X1087958Y580675D01*
X1088000Y581050D01*
X1087917Y581425D01*
X1087750Y581717D01*
X1087458Y581925D01*
X1087125Y581967D01*
X1086792Y581883D01*
X1086583Y581675D01*
X1086417Y581383D01*
X1086375Y581092D01*
X1086417Y580800D01*
X1086583Y580425D01*
X1085500Y580550D01*
Y581675D01*
G01Y584150D02*
X1085583Y583817D01*
X1085792Y583567D01*
X1086042Y583400D01*
X1086375Y583275D01*
X1086750Y583233D01*
X1087125Y583275D01*
X1087458Y583400D01*
X1087708Y583567D01*
X1087917Y583817D01*
X1088000Y584150D01*
X1087917Y584483D01*
X1087708Y584733D01*
X1087458Y584900D01*
X1087125Y585025D01*
X1086750Y585067D01*
X1086375Y585025D01*
X1086042Y584900D01*
X1085792Y584733D01*
X1085583Y584483D01*
X1085500Y584150D01*
G01X1092000Y574017D02*
X1089500D01*
Y575058D01*
X1089625Y575392D01*
X1089792Y575600D01*
X1090125Y575683D01*
X1090458Y575600D01*
X1090667Y575350D01*
X1090792Y575058D01*
Y574017D01*
G01Y575058D02*
X1092000Y575683D01*
G01X1089917Y577158D02*
X1089667Y577408D01*
X1089542Y577700D01*
X1089500Y578033D01*
X1089583Y578450D01*
X1089792Y578742D01*
X1090042Y578825D01*
X1090292Y578783D01*
X1090500Y578617D01*
X1090917Y577783D01*
X1091208Y577408D01*
X1091625Y577158D01*
X1092000Y577075D01*
Y578825D01*
G01X1091625Y580133D02*
X1091833Y580383D01*
X1091958Y580675D01*
X1092000Y581050D01*
X1091917Y581425D01*
X1091750Y581717D01*
X1091458Y581925D01*
X1091125Y581967D01*
X1090792Y581883D01*
X1090583Y581675D01*
X1090417Y581383D01*
X1090375Y581092D01*
X1090417Y580800D01*
X1090583Y580425D01*
X1089500Y580550D01*
Y581675D01*
G01X1089917Y583358D02*
X1089667Y583608D01*
X1089542Y583900D01*
X1089500Y584233D01*
X1089583Y584650D01*
X1089792Y584942D01*
X1090042Y585025D01*
X1090292Y584983D01*
X1090500Y584817D01*
X1090917Y583983D01*
X1091208Y583608D01*
X1091625Y583358D01*
X1092000Y583275D01*
Y585025D01*
G01X1101000Y574017D02*
X1098500D01*
Y575058D01*
X1098625Y575392D01*
X1098792Y575600D01*
X1099125Y575683D01*
X1099458Y575600D01*
X1099667Y575350D01*
X1099792Y575058D01*
Y574017D01*
G01Y575058D02*
X1101000Y575683D01*
G01Y578450D02*
X1098500D01*
X1100292Y576908D01*
Y578992D01*
G01X1101000Y580967D02*
X1100458Y581050D01*
X1100000Y581175D01*
X1099583Y581342D01*
X1099125Y581550D01*
X1098500Y581883D01*
Y580217D01*
G01X1101000Y584650D02*
X1098500D01*
X1100292Y583108D01*
Y585192D01*
G01X1096500Y574017D02*
X1094000D01*
Y575058D01*
X1094125Y575392D01*
X1094292Y575600D01*
X1094625Y575683D01*
X1094958Y575600D01*
X1095167Y575350D01*
X1095292Y575058D01*
Y574017D01*
G01Y575058D02*
X1096500Y575683D01*
G01X1096125Y577033D02*
X1096333Y577283D01*
X1096458Y577575D01*
X1096500Y577950D01*
X1096417Y578325D01*
X1096250Y578617D01*
X1095958Y578825D01*
X1095625Y578867D01*
X1095292Y578783D01*
X1095083Y578575D01*
X1094917Y578283D01*
X1094875Y577992D01*
X1094917Y577700D01*
X1095083Y577325D01*
X1094000Y577450D01*
Y578575D01*
G01X1096000Y580133D02*
X1096292Y580383D01*
X1096458Y580717D01*
X1096500Y581092D01*
X1096458Y581425D01*
X1096250Y581758D01*
X1096000Y581967D01*
X1095750Y582008D01*
X1095458Y581925D01*
X1095250Y581633D01*
X1095167Y581342D01*
Y580967D01*
G01Y581342D02*
X1095042Y581592D01*
X1094833Y581800D01*
X1094583Y581883D01*
X1094333Y581800D01*
X1094125Y581592D01*
X1094000Y581217D01*
X1094042Y580842D01*
X1094208Y580467D01*
G01X1094000Y584150D02*
X1094083Y583817D01*
X1094292Y583567D01*
X1094542Y583400D01*
X1094875Y583275D01*
X1095250Y583233D01*
X1095625Y583275D01*
X1095958Y583400D01*
X1096208Y583567D01*
X1096417Y583817D01*
X1096500Y584150D01*
X1096417Y584483D01*
X1096208Y584733D01*
X1095958Y584900D01*
X1095625Y585025D01*
X1095250Y585067D01*
X1094875Y585025D01*
X1094542Y584900D01*
X1094292Y584733D01*
X1094083Y584483D01*
X1094000Y584150D01*
G01X1097800Y594500D02*
Y592000D01*
G01X1096842Y594500D02*
X1098758D01*
G01X1100067Y592000D02*
Y594500D01*
X1101067D01*
X1101400Y594375D01*
X1101650Y594083D01*
X1101733Y593750D01*
X1101650Y593417D01*
X1101442Y593167D01*
X1101067Y593042D01*
X1100067D01*
G01X1104000Y592000D02*
Y594500D01*
X1103500Y594000D01*
G01Y592000D02*
X1104500D01*
G01X1106183Y592500D02*
X1106433Y592208D01*
X1106767Y592042D01*
X1107142Y592000D01*
X1107475Y592042D01*
X1107808Y592250D01*
X1108017Y592500D01*
X1108058Y592750D01*
X1107975Y593042D01*
X1107683Y593250D01*
X1107392Y593333D01*
X1107017D01*
G01X1107392D02*
X1107642Y593458D01*
X1107850Y593667D01*
X1107933Y593917D01*
X1107850Y594167D01*
X1107642Y594375D01*
X1107267Y594500D01*
X1106892Y594458D01*
X1106517Y594292D01*
G01X1109492Y592292D02*
X1109783Y592083D01*
X1110117Y592000D01*
X1110450Y592083D01*
X1110742Y592333D01*
X1110950Y592708D01*
X1111033Y593083D01*
Y593542D01*
X1110950Y593917D01*
X1110742Y594250D01*
X1110492Y594417D01*
X1110200Y594500D01*
X1109867Y594417D01*
X1109617Y594250D01*
X1109450Y594000D01*
X1109367Y593667D01*
X1109450Y593375D01*
X1109658Y593083D01*
X1109908Y592917D01*
X1110200Y592875D01*
X1110533Y592958D01*
X1110783Y593167D01*
X1111033Y593542D01*
G01X1097800Y590500D02*
Y588000D01*
G01X1096842Y590500D02*
X1098758D01*
G01X1100067Y588000D02*
Y590500D01*
X1101067D01*
X1101400Y590375D01*
X1101650Y590083D01*
X1101733Y589750D01*
X1101650Y589417D01*
X1101442Y589167D01*
X1101067Y589042D01*
X1100067D01*
G01X1104000Y588000D02*
Y590500D01*
X1103500Y590000D01*
G01Y588000D02*
X1104500D01*
G01X1107600D02*
Y590500D01*
X1106058Y588708D01*
X1108142D01*
G01X1110200Y590500D02*
X1109867Y590417D01*
X1109617Y590208D01*
X1109450Y589958D01*
X1109325Y589625D01*
X1109283Y589250D01*
X1109325Y588875D01*
X1109450Y588542D01*
X1109617Y588292D01*
X1109867Y588083D01*
X1110200Y588000D01*
X1110533Y588083D01*
X1110783Y588292D01*
X1110950Y588542D01*
X1111075Y588875D01*
X1111117Y589250D01*
X1111075Y589625D01*
X1110950Y589958D01*
X1110783Y590208D01*
X1110533Y590417D01*
X1110200Y590500D01*
G01X1097300Y620500D02*
Y618000D01*
G01X1096342Y620500D02*
X1098258D01*
G01X1099567Y618000D02*
Y620500D01*
X1100567D01*
X1100900Y620375D01*
X1101150Y620083D01*
X1101233Y619750D01*
X1101150Y619417D01*
X1100942Y619167D01*
X1100567Y619042D01*
X1099567D01*
G01X1103500Y618000D02*
Y620500D01*
X1103000Y620000D01*
G01Y618000D02*
X1104000D01*
G01X1106600D02*
Y620500D01*
X1106100Y620000D01*
G01Y618000D02*
X1107100D01*
G01X1108783Y618375D02*
X1109033Y618167D01*
X1109325Y618042D01*
X1109700Y618000D01*
X1110075Y618083D01*
X1110367Y618250D01*
X1110575Y618542D01*
X1110617Y618875D01*
X1110533Y619208D01*
X1110325Y619417D01*
X1110033Y619583D01*
X1109742Y619625D01*
X1109450Y619583D01*
X1109075Y619417D01*
X1109200Y620500D01*
X1110325D01*
G01X1097300Y624500D02*
Y622000D01*
G01X1096342Y624500D02*
X1098258D01*
G01X1099567Y622000D02*
Y624500D01*
X1100567D01*
X1100900Y624375D01*
X1101150Y624083D01*
X1101233Y623750D01*
X1101150Y623417D01*
X1100942Y623167D01*
X1100567Y623042D01*
X1099567D01*
G01X1103500Y622000D02*
Y624500D01*
X1103000Y624000D01*
G01Y622000D02*
X1104000D01*
G01X1105683Y622500D02*
X1105933Y622208D01*
X1106267Y622042D01*
X1106642Y622000D01*
X1106975Y622042D01*
X1107308Y622250D01*
X1107517Y622500D01*
X1107558Y622750D01*
X1107475Y623042D01*
X1107183Y623250D01*
X1106892Y623333D01*
X1106517D01*
G01X1106892D02*
X1107142Y623458D01*
X1107350Y623667D01*
X1107433Y623917D01*
X1107350Y624167D01*
X1107142Y624375D01*
X1106767Y624500D01*
X1106392Y624458D01*
X1106017Y624292D01*
G01X1108783Y622375D02*
X1109033Y622167D01*
X1109325Y622042D01*
X1109700Y622000D01*
X1110075Y622083D01*
X1110367Y622250D01*
X1110575Y622542D01*
X1110617Y622875D01*
X1110533Y623208D01*
X1110325Y623417D01*
X1110033Y623583D01*
X1109742Y623625D01*
X1109450Y623583D01*
X1109075Y623417D01*
X1109200Y624500D01*
X1110325D01*
G01X1097300Y628500D02*
Y626000D01*
G01X1096342Y628500D02*
X1098258D01*
G01X1099567Y626000D02*
Y628500D01*
X1100567D01*
X1100900Y628375D01*
X1101150Y628083D01*
X1101233Y627750D01*
X1101150Y627417D01*
X1100942Y627167D01*
X1100567Y627042D01*
X1099567D01*
G01X1103500Y626000D02*
Y628500D01*
X1103000Y628000D01*
G01Y626000D02*
X1104000D01*
G01X1105683Y626500D02*
X1105933Y626208D01*
X1106267Y626042D01*
X1106642Y626000D01*
X1106975Y626042D01*
X1107308Y626250D01*
X1107517Y626500D01*
X1107558Y626750D01*
X1107475Y627042D01*
X1107183Y627250D01*
X1106892Y627333D01*
X1106517D01*
G01X1106892D02*
X1107142Y627458D01*
X1107350Y627667D01*
X1107433Y627917D01*
X1107350Y628167D01*
X1107142Y628375D01*
X1106767Y628500D01*
X1106392Y628458D01*
X1106017Y628292D01*
G01X1108908Y627042D02*
X1109200Y627333D01*
X1109450Y627500D01*
X1109783Y627583D01*
X1110075Y627500D01*
X1110283Y627333D01*
X1110450Y627083D01*
X1110492Y626792D01*
X1110450Y626542D01*
X1110283Y626292D01*
X1110033Y626083D01*
X1109742Y626000D01*
X1109408Y626083D01*
X1109117Y626333D01*
X1108950Y626708D01*
X1108908Y627125D01*
X1108992Y627667D01*
X1109117Y627958D01*
X1109325Y628250D01*
X1109617Y628458D01*
X1109908Y628500D01*
X1110200Y628417D01*
X1110408Y628208D01*
G01X1095500Y630517D02*
X1093000D01*
Y631558D01*
X1093125Y631892D01*
X1093292Y632100D01*
X1093625Y632183D01*
X1093958Y632100D01*
X1094167Y631850D01*
X1094292Y631558D01*
Y630517D01*
G01Y631558D02*
X1095500Y632183D01*
G01X1093417Y633658D02*
X1093167Y633908D01*
X1093042Y634200D01*
X1093000Y634533D01*
X1093083Y634950D01*
X1093292Y635242D01*
X1093542Y635325D01*
X1093792Y635283D01*
X1094000Y635117D01*
X1094417Y634283D01*
X1094708Y633908D01*
X1095125Y633658D01*
X1095500Y633575D01*
Y635325D01*
G01X1095000Y636633D02*
X1095292Y636883D01*
X1095458Y637217D01*
X1095500Y637592D01*
X1095458Y637925D01*
X1095250Y638258D01*
X1095000Y638467D01*
X1094750Y638508D01*
X1094458Y638425D01*
X1094250Y638133D01*
X1094167Y637842D01*
Y637467D01*
G01Y637842D02*
X1094042Y638092D01*
X1093833Y638300D01*
X1093583Y638383D01*
X1093333Y638300D01*
X1093125Y638092D01*
X1093000Y637717D01*
X1093042Y637342D01*
X1093208Y636967D01*
G01X1095500Y640567D02*
X1094958Y640650D01*
X1094500Y640775D01*
X1094083Y640942D01*
X1093625Y641150D01*
X1093000Y641483D01*
Y639817D01*
G01X1091500Y630517D02*
X1089000D01*
Y631558D01*
X1089125Y631892D01*
X1089292Y632100D01*
X1089625Y632183D01*
X1089958Y632100D01*
X1090167Y631850D01*
X1090292Y631558D01*
Y630517D01*
G01Y631558D02*
X1091500Y632183D01*
G01X1089417Y633658D02*
X1089167Y633908D01*
X1089042Y634200D01*
X1089000Y634533D01*
X1089083Y634950D01*
X1089292Y635242D01*
X1089542Y635325D01*
X1089792Y635283D01*
X1090000Y635117D01*
X1090417Y634283D01*
X1090708Y633908D01*
X1091125Y633658D01*
X1091500Y633575D01*
Y635325D01*
G01X1091125Y636633D02*
X1091333Y636883D01*
X1091458Y637175D01*
X1091500Y637550D01*
X1091417Y637925D01*
X1091250Y638217D01*
X1090958Y638425D01*
X1090625Y638467D01*
X1090292Y638383D01*
X1090083Y638175D01*
X1089917Y637883D01*
X1089875Y637592D01*
X1089917Y637300D01*
X1090083Y636925D01*
X1089000Y637050D01*
Y638175D01*
G01X1091500Y640650D02*
X1091458Y640942D01*
X1091333Y641275D01*
X1091125Y641483D01*
X1090833Y641567D01*
X1090542Y641483D01*
X1090292Y641233D01*
X1090167Y640858D01*
Y640442D01*
X1090083Y640192D01*
X1089875Y639983D01*
X1089583Y639900D01*
X1089292Y640025D01*
X1089083Y640317D01*
X1089000Y640650D01*
X1089083Y640983D01*
X1089292Y641275D01*
X1089583Y641400D01*
X1089875Y641317D01*
X1090083Y641108D01*
X1090167Y640858D01*
Y640442D01*
X1090292Y640067D01*
X1090542Y639817D01*
X1090833Y639733D01*
X1091125Y639817D01*
X1091333Y640025D01*
X1091458Y640358D01*
X1091500Y640650D01*
G01X1099500Y630517D02*
X1097000D01*
Y631558D01*
X1097125Y631892D01*
X1097292Y632100D01*
X1097625Y632183D01*
X1097958Y632100D01*
X1098167Y631850D01*
X1098292Y631558D01*
Y630517D01*
G01Y631558D02*
X1099500Y632183D01*
G01X1097417Y633658D02*
X1097167Y633908D01*
X1097042Y634200D01*
X1097000Y634533D01*
X1097083Y634950D01*
X1097292Y635242D01*
X1097542Y635325D01*
X1097792Y635283D01*
X1098000Y635117D01*
X1098417Y634283D01*
X1098708Y633908D01*
X1099125Y633658D01*
X1099500Y633575D01*
Y635325D01*
G01X1099125Y636633D02*
X1099333Y636883D01*
X1099458Y637175D01*
X1099500Y637550D01*
X1099417Y637925D01*
X1099250Y638217D01*
X1098958Y638425D01*
X1098625Y638467D01*
X1098292Y638383D01*
X1098083Y638175D01*
X1097917Y637883D01*
X1097875Y637592D01*
X1097917Y637300D01*
X1098083Y636925D01*
X1097000Y637050D01*
Y638175D01*
G01X1099208Y639942D02*
X1099417Y640233D01*
X1099500Y640567D01*
X1099417Y640900D01*
X1099167Y641192D01*
X1098792Y641400D01*
X1098417Y641483D01*
X1097958D01*
X1097583Y641400D01*
X1097250Y641192D01*
X1097083Y640942D01*
X1097000Y640650D01*
X1097083Y640317D01*
X1097250Y640067D01*
X1097500Y639900D01*
X1097833Y639817D01*
X1098125Y639900D01*
X1098417Y640108D01*
X1098583Y640358D01*
X1098625Y640650D01*
X1098542Y640983D01*
X1098333Y641233D01*
X1097958Y641483D01*
G01X1105000Y639700D02*
X1101000D01*
Y632300D01*
G01X1097800Y658000D02*
Y655500D01*
G01X1096842Y658000D02*
X1098758D01*
G01X1100067Y655500D02*
Y658000D01*
X1101067D01*
X1101400Y657875D01*
X1101650Y657583D01*
X1101733Y657250D01*
X1101650Y656917D01*
X1101442Y656667D01*
X1101067Y656542D01*
X1100067D01*
G01X1104000Y655500D02*
Y658000D01*
X1103500Y657500D01*
G01Y655500D02*
X1104500D01*
G01X1106183Y656000D02*
X1106433Y655708D01*
X1106767Y655542D01*
X1107142Y655500D01*
X1107475Y655542D01*
X1107808Y655750D01*
X1108017Y656000D01*
X1108058Y656250D01*
X1107975Y656542D01*
X1107683Y656750D01*
X1107392Y656833D01*
X1107017D01*
G01X1107392D02*
X1107642Y656958D01*
X1107850Y657167D01*
X1107933Y657417D01*
X1107850Y657667D01*
X1107642Y657875D01*
X1107267Y658000D01*
X1106892Y657958D01*
X1106517Y657792D01*
G01X1109283Y656000D02*
X1109533Y655708D01*
X1109867Y655542D01*
X1110242Y655500D01*
X1110575Y655542D01*
X1110908Y655750D01*
X1111117Y656000D01*
X1111158Y656250D01*
X1111075Y656542D01*
X1110783Y656750D01*
X1110492Y656833D01*
X1110117D01*
G01X1110492D02*
X1110742Y656958D01*
X1110950Y657167D01*
X1111033Y657417D01*
X1110950Y657667D01*
X1110742Y657875D01*
X1110367Y658000D01*
X1109992Y657958D01*
X1109617Y657792D01*
G01X1092000Y656350D02*
X1094500D01*
G01X1092000Y655392D02*
Y657308D01*
G01X1094500Y658617D02*
X1092000D01*
Y659617D01*
X1092125Y659950D01*
X1092417Y660200D01*
X1092750Y660283D01*
X1093083Y660200D01*
X1093333Y659992D01*
X1093458Y659617D01*
Y658617D01*
G01X1094500Y662550D02*
X1094458Y662842D01*
X1094333Y663175D01*
X1094125Y663383D01*
X1093833Y663467D01*
X1093542Y663383D01*
X1093292Y663133D01*
X1093167Y662758D01*
Y662342D01*
X1093083Y662092D01*
X1092875Y661883D01*
X1092583Y661800D01*
X1092292Y661925D01*
X1092083Y662217D01*
X1092000Y662550D01*
X1092083Y662883D01*
X1092292Y663175D01*
X1092583Y663300D01*
X1092875Y663217D01*
X1093083Y663008D01*
X1093167Y662758D01*
Y662342D01*
X1093292Y661967D01*
X1093542Y661717D01*
X1093833Y661633D01*
X1094125Y661717D01*
X1094333Y661925D01*
X1094458Y662258D01*
X1094500Y662550D01*
G01Y665650D02*
X1094458Y665942D01*
X1094333Y666275D01*
X1094125Y666483D01*
X1093833Y666567D01*
X1093542Y666483D01*
X1093292Y666233D01*
X1093167Y665858D01*
Y665442D01*
X1093083Y665192D01*
X1092875Y664983D01*
X1092583Y664900D01*
X1092292Y665025D01*
X1092083Y665317D01*
X1092000Y665650D01*
X1092083Y665983D01*
X1092292Y666275D01*
X1092583Y666400D01*
X1092875Y666317D01*
X1093083Y666108D01*
X1093167Y665858D01*
Y665442D01*
X1093292Y665067D01*
X1093542Y664817D01*
X1093833Y664733D01*
X1094125Y664817D01*
X1094333Y665025D01*
X1094458Y665358D01*
X1094500Y665650D01*
G01X1098000Y699850D02*
X1100500D01*
G01X1098000Y698892D02*
Y700808D01*
G01X1100500Y702117D02*
X1098000D01*
Y703117D01*
X1098125Y703450D01*
X1098417Y703700D01*
X1098750Y703783D01*
X1099083Y703700D01*
X1099333Y703492D01*
X1099458Y703117D01*
Y702117D01*
G01X1100208Y705342D02*
X1100417Y705633D01*
X1100500Y705967D01*
X1100417Y706300D01*
X1100167Y706592D01*
X1099792Y706800D01*
X1099417Y706883D01*
X1098958D01*
X1098583Y706800D01*
X1098250Y706592D01*
X1098083Y706342D01*
X1098000Y706050D01*
X1098083Y705717D01*
X1098250Y705467D01*
X1098500Y705300D01*
X1098833Y705217D01*
X1099125Y705300D01*
X1099417Y705508D01*
X1099583Y705758D01*
X1099625Y706050D01*
X1099542Y706383D01*
X1099333Y706633D01*
X1098958Y706883D01*
G01X1099458Y708358D02*
X1099167Y708650D01*
X1099000Y708900D01*
X1098917Y709233D01*
X1099000Y709525D01*
X1099167Y709733D01*
X1099417Y709900D01*
X1099708Y709942D01*
X1099958Y709900D01*
X1100208Y709733D01*
X1100417Y709483D01*
X1100500Y709192D01*
X1100417Y708858D01*
X1100167Y708567D01*
X1099792Y708400D01*
X1099375Y708358D01*
X1098833Y708442D01*
X1098542Y708567D01*
X1098250Y708775D01*
X1098042Y709067D01*
X1098000Y709358D01*
X1098083Y709650D01*
X1098292Y709858D01*
G01X1091300Y728500D02*
Y726000D01*
G01X1090342Y728500D02*
X1092258D01*
G01X1093567Y726000D02*
Y728500D01*
X1094567D01*
X1094900Y728375D01*
X1095150Y728083D01*
X1095233Y727750D01*
X1095150Y727417D01*
X1094942Y727167D01*
X1094567Y727042D01*
X1093567D01*
G01X1097500Y726000D02*
Y728500D01*
X1097000Y728000D01*
G01Y726000D02*
X1098000D01*
G01X1099683Y726375D02*
X1099933Y726167D01*
X1100225Y726042D01*
X1100600Y726000D01*
X1100975Y726083D01*
X1101267Y726250D01*
X1101475Y726542D01*
X1101517Y726875D01*
X1101433Y727208D01*
X1101225Y727417D01*
X1100933Y727583D01*
X1100642Y727625D01*
X1100350Y727583D01*
X1099975Y727417D01*
X1100100Y728500D01*
X1101225D01*
G01X1103700D02*
X1103367Y728417D01*
X1103117Y728208D01*
X1102950Y727958D01*
X1102825Y727625D01*
X1102783Y727250D01*
X1102825Y726875D01*
X1102950Y726542D01*
X1103117Y726292D01*
X1103367Y726083D01*
X1103700Y726000D01*
X1104033Y726083D01*
X1104283Y726292D01*
X1104450Y726542D01*
X1104575Y726875D01*
X1104617Y727250D01*
X1104575Y727625D01*
X1104450Y727958D01*
X1104283Y728208D01*
X1104033Y728417D01*
X1103700Y728500D01*
G01X1091268Y748204D02*
X1107968D01*
Y736104D01*
X1091268D01*
Y748204D01*
G01X1089988Y747324D02*
X1085988D01*
Y739924D01*
G01X1095767Y764792D02*
X1095517Y764917D01*
X1095225Y765000D01*
X1094892D01*
X1094517Y764875D01*
X1094225Y764667D01*
X1094017Y764417D01*
X1093850Y764000D01*
X1093808Y763625D01*
X1093892Y763250D01*
X1094017Y763000D01*
X1094267Y762750D01*
X1094558Y762583D01*
X1094850Y762500D01*
X1095142D01*
X1095433Y762583D01*
X1095683Y762708D01*
X1095892Y762875D01*
G01X1097158Y764583D02*
X1097408Y764833D01*
X1097700Y764958D01*
X1098033Y765000D01*
X1098450Y764917D01*
X1098742Y764708D01*
X1098825Y764458D01*
X1098783Y764208D01*
X1098617Y764000D01*
X1097783Y763583D01*
X1097408Y763292D01*
X1097158Y762875D01*
X1097075Y762500D01*
X1098825D01*
G01X1101050Y765000D02*
X1100717Y764917D01*
X1100467Y764708D01*
X1100300Y764458D01*
X1100175Y764125D01*
X1100133Y763750D01*
X1100175Y763375D01*
X1100300Y763042D01*
X1100467Y762792D01*
X1100717Y762583D01*
X1101050Y762500D01*
X1101383Y762583D01*
X1101633Y762792D01*
X1101800Y763042D01*
X1101925Y763375D01*
X1101967Y763750D01*
X1101925Y764125D01*
X1101800Y764458D01*
X1101633Y764708D01*
X1101383Y764917D01*
X1101050Y765000D01*
G01X1103358Y764583D02*
X1103608Y764833D01*
X1103900Y764958D01*
X1104233Y765000D01*
X1104650Y764917D01*
X1104942Y764708D01*
X1105025Y764458D01*
X1104983Y764208D01*
X1104817Y764000D01*
X1103983Y763583D01*
X1103608Y763292D01*
X1103358Y762875D01*
X1103275Y762500D01*
X1105025D01*
G01X1093767Y769792D02*
X1093517Y769917D01*
X1093225Y770000D01*
X1092892D01*
X1092517Y769875D01*
X1092225Y769667D01*
X1092017Y769417D01*
X1091850Y769000D01*
X1091808Y768625D01*
X1091892Y768250D01*
X1092017Y768000D01*
X1092267Y767750D01*
X1092558Y767583D01*
X1092850Y767500D01*
X1093142D01*
X1093433Y767583D01*
X1093683Y767708D01*
X1093892Y767875D01*
G01X1095158Y769583D02*
X1095408Y769833D01*
X1095700Y769958D01*
X1096033Y770000D01*
X1096450Y769917D01*
X1096742Y769708D01*
X1096825Y769458D01*
X1096783Y769208D01*
X1096617Y769000D01*
X1095783Y768583D01*
X1095408Y768292D01*
X1095158Y767875D01*
X1095075Y767500D01*
X1096825D01*
G01X1099050Y770000D02*
X1098717Y769917D01*
X1098467Y769708D01*
X1098300Y769458D01*
X1098175Y769125D01*
X1098133Y768750D01*
X1098175Y768375D01*
X1098300Y768042D01*
X1098467Y767792D01*
X1098717Y767583D01*
X1099050Y767500D01*
X1099383Y767583D01*
X1099633Y767792D01*
X1099800Y768042D01*
X1099925Y768375D01*
X1099967Y768750D01*
X1099925Y769125D01*
X1099800Y769458D01*
X1099633Y769708D01*
X1099383Y769917D01*
X1099050Y770000D01*
G01X1102150Y767500D02*
Y770000D01*
X1101650Y769500D01*
G01Y767500D02*
X1102650D01*
G01X1088267Y778792D02*
X1088017Y778917D01*
X1087725Y779000D01*
X1087392D01*
X1087017Y778875D01*
X1086725Y778667D01*
X1086517Y778417D01*
X1086350Y778000D01*
X1086308Y777625D01*
X1086392Y777250D01*
X1086517Y777000D01*
X1086767Y776750D01*
X1087058Y776583D01*
X1087350Y776500D01*
X1087642D01*
X1087933Y776583D01*
X1088183Y776708D01*
X1088392Y776875D01*
G01X1090450Y776500D02*
Y779000D01*
X1089950Y778500D01*
G01Y776500D02*
X1090950D01*
G01X1092842Y776792D02*
X1093133Y776583D01*
X1093467Y776500D01*
X1093800Y776583D01*
X1094092Y776833D01*
X1094300Y777208D01*
X1094383Y777583D01*
Y778042D01*
X1094300Y778417D01*
X1094092Y778750D01*
X1093842Y778917D01*
X1093550Y779000D01*
X1093217Y778917D01*
X1092967Y778750D01*
X1092800Y778500D01*
X1092717Y778167D01*
X1092800Y777875D01*
X1093008Y777583D01*
X1093258Y777417D01*
X1093550Y777375D01*
X1093883Y777458D01*
X1094133Y777667D01*
X1094383Y778042D01*
G01X1095733Y776875D02*
X1095983Y776667D01*
X1096275Y776542D01*
X1096650Y776500D01*
X1097025Y776583D01*
X1097317Y776750D01*
X1097525Y777042D01*
X1097567Y777375D01*
X1097483Y777708D01*
X1097275Y777917D01*
X1096983Y778083D01*
X1096692Y778125D01*
X1096400Y778083D01*
X1096025Y777917D01*
X1096150Y779000D01*
X1097275D01*
G01X1088267Y774792D02*
X1088017Y774917D01*
X1087725Y775000D01*
X1087392D01*
X1087017Y774875D01*
X1086725Y774667D01*
X1086517Y774417D01*
X1086350Y774000D01*
X1086308Y773625D01*
X1086392Y773250D01*
X1086517Y773000D01*
X1086767Y772750D01*
X1087058Y772583D01*
X1087350Y772500D01*
X1087642D01*
X1087933Y772583D01*
X1088183Y772708D01*
X1088392Y772875D01*
G01X1090450Y772500D02*
Y775000D01*
X1089950Y774500D01*
G01Y772500D02*
X1090950D01*
G01X1092842Y772792D02*
X1093133Y772583D01*
X1093467Y772500D01*
X1093800Y772583D01*
X1094092Y772833D01*
X1094300Y773208D01*
X1094383Y773583D01*
Y774042D01*
X1094300Y774417D01*
X1094092Y774750D01*
X1093842Y774917D01*
X1093550Y775000D01*
X1093217Y774917D01*
X1092967Y774750D01*
X1092800Y774500D01*
X1092717Y774167D01*
X1092800Y773875D01*
X1093008Y773583D01*
X1093258Y773417D01*
X1093550Y773375D01*
X1093883Y773458D01*
X1094133Y773667D01*
X1094383Y774042D01*
G01X1095858Y773542D02*
X1096150Y773833D01*
X1096400Y774000D01*
X1096733Y774083D01*
X1097025Y774000D01*
X1097233Y773833D01*
X1097400Y773583D01*
X1097442Y773292D01*
X1097400Y773042D01*
X1097233Y772792D01*
X1096983Y772583D01*
X1096692Y772500D01*
X1096358Y772583D01*
X1096067Y772833D01*
X1095900Y773208D01*
X1095858Y773625D01*
X1095942Y774167D01*
X1096067Y774458D01*
X1096275Y774750D01*
X1096567Y774958D01*
X1096858Y775000D01*
X1097150Y774917D01*
X1097358Y774708D01*
G01X1100000Y797700D02*
X1107000D01*
Y784300D01*
X1100000D01*
Y797700D01*
G01X1088267Y782792D02*
X1088017Y782917D01*
X1087725Y783000D01*
X1087392D01*
X1087017Y782875D01*
X1086725Y782667D01*
X1086517Y782417D01*
X1086350Y782000D01*
X1086308Y781625D01*
X1086392Y781250D01*
X1086517Y781000D01*
X1086767Y780750D01*
X1087058Y780583D01*
X1087350Y780500D01*
X1087642D01*
X1087933Y780583D01*
X1088183Y780708D01*
X1088392Y780875D01*
G01X1090450Y780500D02*
Y783000D01*
X1089950Y782500D01*
G01Y780500D02*
X1090950D01*
G01X1092842Y780792D02*
X1093133Y780583D01*
X1093467Y780500D01*
X1093800Y780583D01*
X1094092Y780833D01*
X1094300Y781208D01*
X1094383Y781583D01*
Y782042D01*
X1094300Y782417D01*
X1094092Y782750D01*
X1093842Y782917D01*
X1093550Y783000D01*
X1093217Y782917D01*
X1092967Y782750D01*
X1092800Y782500D01*
X1092717Y782167D01*
X1092800Y781875D01*
X1093008Y781583D01*
X1093258Y781417D01*
X1093550Y781375D01*
X1093883Y781458D01*
X1094133Y781667D01*
X1094383Y782042D01*
G01X1097150Y780500D02*
Y783000D01*
X1095608Y781208D01*
X1097692D01*
G01X1086708Y788767D02*
X1086583Y788517D01*
X1086500Y788225D01*
Y787892D01*
X1086625Y787517D01*
X1086833Y787225D01*
X1087083Y787017D01*
X1087500Y786850D01*
X1087875Y786808D01*
X1088250Y786892D01*
X1088500Y787017D01*
X1088750Y787267D01*
X1088917Y787558D01*
X1089000Y787850D01*
Y788142D01*
X1088917Y788433D01*
X1088792Y788683D01*
X1088625Y788892D01*
G01X1089000Y790950D02*
X1086500D01*
X1087000Y790450D01*
G01X1089000D02*
Y791450D01*
G01Y794050D02*
X1088958Y794342D01*
X1088833Y794675D01*
X1088625Y794883D01*
X1088333Y794967D01*
X1088042Y794883D01*
X1087792Y794633D01*
X1087667Y794258D01*
Y793842D01*
X1087583Y793592D01*
X1087375Y793383D01*
X1087083Y793300D01*
X1086792Y793425D01*
X1086583Y793717D01*
X1086500Y794050D01*
X1086583Y794383D01*
X1086792Y794675D01*
X1087083Y794800D01*
X1087375Y794717D01*
X1087583Y794508D01*
X1087667Y794258D01*
Y793842D01*
X1087792Y793467D01*
X1088042Y793217D01*
X1088333Y793133D01*
X1088625Y793217D01*
X1088833Y793425D01*
X1088958Y793758D01*
X1089000Y794050D01*
G01Y797067D02*
X1088458Y797150D01*
X1088000Y797275D01*
X1087583Y797442D01*
X1087125Y797650D01*
X1086500Y797983D01*
Y796317D01*
G01X1098117Y802500D02*
Y800000D01*
X1099783D01*
G01X1101133Y800375D02*
X1101383Y800167D01*
X1101675Y800042D01*
X1102050Y800000D01*
X1102425Y800083D01*
X1102717Y800250D01*
X1102925Y800542D01*
X1102967Y800875D01*
X1102883Y801208D01*
X1102675Y801417D01*
X1102383Y801583D01*
X1102092Y801625D01*
X1101800Y801583D01*
X1101425Y801417D01*
X1101550Y802500D01*
X1102675D01*
G01X1088000Y801517D02*
X1085500D01*
Y802558D01*
X1085625Y802892D01*
X1085792Y803100D01*
X1086125Y803183D01*
X1086458Y803100D01*
X1086667Y802850D01*
X1086792Y802558D01*
Y801517D01*
G01Y802558D02*
X1088000Y803183D01*
G01Y805950D02*
X1085500D01*
X1087292Y804408D01*
Y806492D01*
G01X1087708Y807842D02*
X1087917Y808133D01*
X1088000Y808467D01*
X1087917Y808800D01*
X1087667Y809092D01*
X1087292Y809300D01*
X1086917Y809383D01*
X1086458D01*
X1086083Y809300D01*
X1085750Y809092D01*
X1085583Y808842D01*
X1085500Y808550D01*
X1085583Y808217D01*
X1085750Y807967D01*
X1086000Y807800D01*
X1086333Y807717D01*
X1086625Y807800D01*
X1086917Y808008D01*
X1087083Y808258D01*
X1087125Y808550D01*
X1087042Y808883D01*
X1086833Y809133D01*
X1086458Y809383D01*
G01X1088000Y811650D02*
X1085500D01*
X1086000Y811150D01*
G01X1088000D02*
Y812150D01*
G01X1103968Y811984D02*
X1099968D01*
Y804584D01*
G01X1092500Y801517D02*
X1090000D01*
Y802558D01*
X1090125Y802892D01*
X1090292Y803100D01*
X1090625Y803183D01*
X1090958Y803100D01*
X1091167Y802850D01*
X1091292Y802558D01*
Y801517D01*
G01Y802558D02*
X1092500Y803183D01*
G01Y805950D02*
X1090000D01*
X1091792Y804408D01*
Y806492D01*
G01X1092500Y808550D02*
X1092458Y808842D01*
X1092333Y809175D01*
X1092125Y809383D01*
X1091833Y809467D01*
X1091542Y809383D01*
X1091292Y809133D01*
X1091167Y808758D01*
Y808342D01*
X1091083Y808092D01*
X1090875Y807883D01*
X1090583Y807800D01*
X1090292Y807925D01*
X1090083Y808217D01*
X1090000Y808550D01*
X1090083Y808883D01*
X1090292Y809175D01*
X1090583Y809300D01*
X1090875Y809217D01*
X1091083Y809008D01*
X1091167Y808758D01*
Y808342D01*
X1091292Y807967D01*
X1091542Y807717D01*
X1091833Y807633D01*
X1092125Y807717D01*
X1092333Y807925D01*
X1092458Y808258D01*
X1092500Y808550D01*
G01X1092208Y810942D02*
X1092417Y811233D01*
X1092500Y811567D01*
X1092417Y811900D01*
X1092167Y812192D01*
X1091792Y812400D01*
X1091417Y812483D01*
X1090958D01*
X1090583Y812400D01*
X1090250Y812192D01*
X1090083Y811942D01*
X1090000Y811650D01*
X1090083Y811317D01*
X1090250Y811067D01*
X1090500Y810900D01*
X1090833Y810817D01*
X1091125Y810900D01*
X1091417Y811108D01*
X1091583Y811358D01*
X1091625Y811650D01*
X1091542Y811983D01*
X1091333Y812233D01*
X1090958Y812483D01*
G01X1090500Y817483D02*
X1092292D01*
X1092667Y817650D01*
X1092917Y817983D01*
X1093000Y818400D01*
X1092917Y818817D01*
X1092667Y819150D01*
X1092292Y819317D01*
X1090500D01*
G01X1090917Y820708D02*
X1090667Y820958D01*
X1090542Y821250D01*
X1090500Y821583D01*
X1090583Y822000D01*
X1090792Y822292D01*
X1091042Y822375D01*
X1091292Y822333D01*
X1091500Y822167D01*
X1091917Y821333D01*
X1092208Y820958D01*
X1092625Y820708D01*
X1093000Y820625D01*
Y822375D01*
G01X1092625Y823683D02*
X1092833Y823933D01*
X1092958Y824225D01*
X1093000Y824600D01*
X1092917Y824975D01*
X1092750Y825267D01*
X1092458Y825475D01*
X1092125Y825517D01*
X1091792Y825433D01*
X1091583Y825225D01*
X1091417Y824933D01*
X1091375Y824642D01*
X1091417Y824350D01*
X1091583Y823975D01*
X1090500Y824100D01*
Y825225D01*
G01X1099546Y813394D02*
Y826794D01*
G01X1109546Y813394D02*
X1099546D01*
G01Y826794D02*
X1109546D01*
G01X1085708Y817267D02*
X1085583Y817017D01*
X1085500Y816725D01*
Y816392D01*
X1085625Y816017D01*
X1085833Y815725D01*
X1086083Y815517D01*
X1086500Y815350D01*
X1086875Y815308D01*
X1087250Y815392D01*
X1087500Y815517D01*
X1087750Y815767D01*
X1087917Y816058D01*
X1088000Y816350D01*
Y816642D01*
X1087917Y816933D01*
X1087792Y817183D01*
X1087625Y817392D01*
G01X1087500Y818533D02*
X1087792Y818783D01*
X1087958Y819117D01*
X1088000Y819492D01*
X1087958Y819825D01*
X1087750Y820158D01*
X1087500Y820367D01*
X1087250Y820408D01*
X1086958Y820325D01*
X1086750Y820033D01*
X1086667Y819742D01*
Y819367D01*
G01Y819742D02*
X1086542Y819992D01*
X1086333Y820200D01*
X1086083Y820283D01*
X1085833Y820200D01*
X1085625Y819992D01*
X1085500Y819617D01*
X1085542Y819242D01*
X1085708Y818867D01*
G01X1087500Y821633D02*
X1087792Y821883D01*
X1087958Y822217D01*
X1088000Y822592D01*
X1087958Y822925D01*
X1087750Y823258D01*
X1087500Y823467D01*
X1087250Y823508D01*
X1086958Y823425D01*
X1086750Y823133D01*
X1086667Y822842D01*
Y822467D01*
G01Y822842D02*
X1086542Y823092D01*
X1086333Y823300D01*
X1086083Y823383D01*
X1085833Y823300D01*
X1085625Y823092D01*
X1085500Y822717D01*
X1085542Y822342D01*
X1085708Y821967D01*
G01X1085500Y825650D02*
X1085583Y825317D01*
X1085792Y825067D01*
X1086042Y824900D01*
X1086375Y824775D01*
X1086750Y824733D01*
X1087125Y824775D01*
X1087458Y824900D01*
X1087708Y825067D01*
X1087917Y825317D01*
X1088000Y825650D01*
X1087917Y825983D01*
X1087708Y826233D01*
X1087458Y826400D01*
X1087125Y826525D01*
X1086750Y826567D01*
X1086375Y826525D01*
X1086042Y826400D01*
X1085792Y826233D01*
X1085583Y825983D01*
X1085500Y825650D01*
G01X1092108Y843691D02*
X1089608D01*
Y844691D01*
X1089733Y845024D01*
X1090025Y845274D01*
X1090358Y845357D01*
X1090691Y845274D01*
X1090941Y845066D01*
X1091066Y844691D01*
Y843691D01*
G01X1092108Y846791D02*
X1089608D01*
Y847832D01*
X1089733Y848166D01*
X1089900Y848374D01*
X1090233Y848457D01*
X1090566Y848374D01*
X1090775Y848124D01*
X1090900Y847832D01*
Y846791D01*
G01Y847832D02*
X1092108Y848457D01*
G01Y850724D02*
X1092066Y851016D01*
X1091941Y851349D01*
X1091733Y851557D01*
X1091441Y851641D01*
X1091150Y851557D01*
X1090900Y851307D01*
X1090775Y850932D01*
Y850516D01*
X1090691Y850266D01*
X1090483Y850057D01*
X1090191Y849974D01*
X1089900Y850099D01*
X1089691Y850391D01*
X1089608Y850724D01*
X1089691Y851057D01*
X1089900Y851349D01*
X1090191Y851474D01*
X1090483Y851391D01*
X1090691Y851182D01*
X1090775Y850932D01*
Y850516D01*
X1090900Y850141D01*
X1091150Y849891D01*
X1091441Y849807D01*
X1091733Y849891D01*
X1091941Y850099D01*
X1092066Y850432D01*
X1092108Y850724D01*
G01X1091608Y852907D02*
X1091900Y853157D01*
X1092066Y853491D01*
X1092108Y853866D01*
X1092066Y854199D01*
X1091858Y854532D01*
X1091608Y854741D01*
X1091358Y854782D01*
X1091066Y854699D01*
X1090858Y854407D01*
X1090775Y854116D01*
Y853741D01*
G01Y854116D02*
X1090650Y854366D01*
X1090441Y854574D01*
X1090191Y854657D01*
X1089941Y854574D01*
X1089733Y854366D01*
X1089608Y853991D01*
X1089650Y853616D01*
X1089816Y853241D01*
G01X1096608Y843691D02*
X1094108D01*
Y844691D01*
X1094233Y845024D01*
X1094525Y845274D01*
X1094858Y845357D01*
X1095191Y845274D01*
X1095441Y845066D01*
X1095566Y844691D01*
Y843691D01*
G01X1094316Y848541D02*
X1094191Y848291D01*
X1094108Y847999D01*
Y847666D01*
X1094233Y847291D01*
X1094441Y846999D01*
X1094691Y846791D01*
X1095108Y846624D01*
X1095483Y846582D01*
X1095858Y846666D01*
X1096108Y846791D01*
X1096358Y847041D01*
X1096525Y847332D01*
X1096608Y847624D01*
Y847916D01*
X1096525Y848207D01*
X1096400Y848457D01*
X1096233Y848666D01*
G01X1096608Y850724D02*
X1096566Y851016D01*
X1096441Y851349D01*
X1096233Y851557D01*
X1095941Y851641D01*
X1095650Y851557D01*
X1095400Y851307D01*
X1095275Y850932D01*
Y850516D01*
X1095191Y850266D01*
X1094983Y850057D01*
X1094691Y849974D01*
X1094400Y850099D01*
X1094191Y850391D01*
X1094108Y850724D01*
X1094191Y851057D01*
X1094400Y851349D01*
X1094691Y851474D01*
X1094983Y851391D01*
X1095191Y851182D01*
X1095275Y850932D01*
Y850516D01*
X1095400Y850141D01*
X1095650Y849891D01*
X1095941Y849807D01*
X1096233Y849891D01*
X1096441Y850099D01*
X1096566Y850432D01*
X1096608Y850724D01*
G01X1096316Y853116D02*
X1096525Y853407D01*
X1096608Y853741D01*
X1096525Y854074D01*
X1096275Y854366D01*
X1095900Y854574D01*
X1095525Y854657D01*
X1095066D01*
X1094691Y854574D01*
X1094358Y854366D01*
X1094191Y854116D01*
X1094108Y853824D01*
X1094191Y853491D01*
X1094358Y853241D01*
X1094608Y853074D01*
X1094941Y852991D01*
X1095233Y853074D01*
X1095525Y853282D01*
X1095691Y853532D01*
X1095733Y853824D01*
X1095650Y854157D01*
X1095441Y854407D01*
X1095066Y854657D01*
G01X1099468Y845084D02*
X1103468D01*
Y852484D01*
G01X1104025Y865166D02*
X1101025D01*
G01X1090768Y869284D02*
Y865284D01*
X1098168D01*
G01X1090768Y873784D02*
Y869784D01*
X1098168D01*
G01X1093968Y896301D02*
X1091468D01*
Y897301D01*
X1091593Y897634D01*
X1091885Y897884D01*
X1092218Y897967D01*
X1092551Y897884D01*
X1092801Y897676D01*
X1092926Y897301D01*
Y896301D01*
G01X1091676Y901151D02*
X1091551Y900901D01*
X1091468Y900609D01*
Y900276D01*
X1091593Y899901D01*
X1091801Y899609D01*
X1092051Y899401D01*
X1092468Y899234D01*
X1092843Y899192D01*
X1093218Y899276D01*
X1093468Y899401D01*
X1093718Y899651D01*
X1093885Y899942D01*
X1093968Y900234D01*
Y900526D01*
X1093885Y900817D01*
X1093760Y901067D01*
X1093593Y901276D01*
G01X1093968Y903251D02*
X1093426Y903334D01*
X1092968Y903459D01*
X1092551Y903626D01*
X1092093Y903834D01*
X1091468Y904167D01*
Y902501D01*
G01X1093676Y905726D02*
X1093885Y906017D01*
X1093968Y906351D01*
X1093885Y906684D01*
X1093635Y906976D01*
X1093260Y907184D01*
X1092885Y907267D01*
X1092426D01*
X1092051Y907184D01*
X1091718Y906976D01*
X1091551Y906726D01*
X1091468Y906434D01*
X1091551Y906101D01*
X1091718Y905851D01*
X1091968Y905684D01*
X1092301Y905601D01*
X1092593Y905684D01*
X1092885Y905892D01*
X1093051Y906142D01*
X1093093Y906434D01*
X1093010Y906767D01*
X1092801Y907017D01*
X1092426Y907267D01*
G01X1099968Y896301D02*
X1097468D01*
Y897301D01*
X1097593Y897634D01*
X1097885Y897884D01*
X1098218Y897967D01*
X1098551Y897884D01*
X1098801Y897676D01*
X1098926Y897301D01*
Y896301D01*
G01X1097676Y901151D02*
X1097551Y900901D01*
X1097468Y900609D01*
Y900276D01*
X1097593Y899901D01*
X1097801Y899609D01*
X1098051Y899401D01*
X1098468Y899234D01*
X1098843Y899192D01*
X1099218Y899276D01*
X1099468Y899401D01*
X1099718Y899651D01*
X1099885Y899942D01*
X1099968Y900234D01*
Y900526D01*
X1099885Y900817D01*
X1099760Y901067D01*
X1099593Y901276D01*
G01X1099968Y903251D02*
X1099426Y903334D01*
X1098968Y903459D01*
X1098551Y903626D01*
X1098093Y903834D01*
X1097468Y904167D01*
Y902501D01*
G01X1099968Y906434D02*
X1099926Y906726D01*
X1099801Y907059D01*
X1099593Y907267D01*
X1099301Y907351D01*
X1099010Y907267D01*
X1098760Y907017D01*
X1098635Y906642D01*
Y906226D01*
X1098551Y905976D01*
X1098343Y905767D01*
X1098051Y905684D01*
X1097760Y905809D01*
X1097551Y906101D01*
X1097468Y906434D01*
X1097551Y906767D01*
X1097760Y907059D01*
X1098051Y907184D01*
X1098343Y907101D01*
X1098551Y906892D01*
X1098635Y906642D01*
Y906226D01*
X1098760Y905851D01*
X1099010Y905601D01*
X1099301Y905517D01*
X1099593Y905601D01*
X1099801Y905809D01*
X1099926Y906142D01*
X1099968Y906434D01*
G01X1107961Y97059D02*
X1105461D01*
Y98100D01*
X1105586Y98434D01*
X1105753Y98642D01*
X1106086Y98725D01*
X1106419Y98642D01*
X1106628Y98392D01*
X1106753Y98100D01*
Y97059D01*
G01Y98100D02*
X1107961Y98725D01*
G01Y101492D02*
X1105461D01*
X1107253Y99950D01*
Y102034D01*
G01X1105461Y104092D02*
X1105544Y103759D01*
X1105753Y103509D01*
X1106003Y103342D01*
X1106336Y103217D01*
X1106711Y103175D01*
X1107086Y103217D01*
X1107419Y103342D01*
X1107669Y103509D01*
X1107878Y103759D01*
X1107961Y104092D01*
X1107878Y104425D01*
X1107669Y104675D01*
X1107419Y104842D01*
X1107086Y104967D01*
X1106711Y105009D01*
X1106336Y104967D01*
X1106003Y104842D01*
X1105753Y104675D01*
X1105544Y104425D01*
X1105461Y104092D01*
G01X1107669Y106484D02*
X1107878Y106775D01*
X1107961Y107109D01*
X1107878Y107442D01*
X1107628Y107734D01*
X1107253Y107942D01*
X1106878Y108025D01*
X1106419D01*
X1106044Y107942D01*
X1105711Y107734D01*
X1105544Y107484D01*
X1105461Y107192D01*
X1105544Y106859D01*
X1105711Y106609D01*
X1105961Y106442D01*
X1106294Y106359D01*
X1106586Y106442D01*
X1106878Y106650D01*
X1107044Y106900D01*
X1107086Y107192D01*
X1107003Y107525D01*
X1106794Y107775D01*
X1106419Y108025D01*
G01X1110500Y232517D02*
X1108000D01*
Y233558D01*
X1108125Y233892D01*
X1108292Y234100D01*
X1108625Y234183D01*
X1108958Y234100D01*
X1109167Y233850D01*
X1109292Y233558D01*
Y232517D01*
G01Y233558D02*
X1110500Y234183D01*
G01X1110125Y235533D02*
X1110333Y235783D01*
X1110458Y236075D01*
X1110500Y236450D01*
X1110417Y236825D01*
X1110250Y237117D01*
X1109958Y237325D01*
X1109625Y237367D01*
X1109292Y237283D01*
X1109083Y237075D01*
X1108917Y236783D01*
X1108875Y236492D01*
X1108917Y236200D01*
X1109083Y235825D01*
X1108000Y235950D01*
Y237075D01*
G01X1108417Y238758D02*
X1108167Y239008D01*
X1108042Y239300D01*
X1108000Y239633D01*
X1108083Y240050D01*
X1108292Y240342D01*
X1108542Y240425D01*
X1108792Y240383D01*
X1109000Y240217D01*
X1109417Y239383D01*
X1109708Y239008D01*
X1110125Y238758D01*
X1110500Y238675D01*
Y240425D01*
G01Y242567D02*
X1109958Y242650D01*
X1109500Y242775D01*
X1109083Y242942D01*
X1108625Y243150D01*
X1108000Y243483D01*
Y241817D01*
G01X1112708Y234267D02*
X1112583Y234017D01*
X1112500Y233725D01*
Y233392D01*
X1112625Y233017D01*
X1112833Y232725D01*
X1113083Y232517D01*
X1113500Y232350D01*
X1113875Y232308D01*
X1114250Y232392D01*
X1114500Y232517D01*
X1114750Y232767D01*
X1114917Y233058D01*
X1115000Y233350D01*
Y233642D01*
X1114917Y233933D01*
X1114792Y234183D01*
X1114625Y234392D01*
G01X1112917Y235658D02*
X1112667Y235908D01*
X1112542Y236200D01*
X1112500Y236533D01*
X1112583Y236950D01*
X1112792Y237242D01*
X1113042Y237325D01*
X1113292Y237283D01*
X1113500Y237117D01*
X1113917Y236283D01*
X1114208Y235908D01*
X1114625Y235658D01*
X1115000Y235575D01*
Y237325D01*
G01X1113958Y238758D02*
X1113667Y239050D01*
X1113500Y239300D01*
X1113417Y239633D01*
X1113500Y239925D01*
X1113667Y240133D01*
X1113917Y240300D01*
X1114208Y240342D01*
X1114458Y240300D01*
X1114708Y240133D01*
X1114917Y239883D01*
X1115000Y239592D01*
X1114917Y239258D01*
X1114667Y238967D01*
X1114292Y238800D01*
X1113875Y238758D01*
X1113333Y238842D01*
X1113042Y238967D01*
X1112750Y239175D01*
X1112542Y239467D01*
X1112500Y239758D01*
X1112583Y240050D01*
X1112792Y240258D01*
G01X1115000Y242650D02*
X1114958Y242942D01*
X1114833Y243275D01*
X1114625Y243483D01*
X1114333Y243567D01*
X1114042Y243483D01*
X1113792Y243233D01*
X1113667Y242858D01*
Y242442D01*
X1113583Y242192D01*
X1113375Y241983D01*
X1113083Y241900D01*
X1112792Y242025D01*
X1112583Y242317D01*
X1112500Y242650D01*
X1112583Y242983D01*
X1112792Y243275D01*
X1113083Y243400D01*
X1113375Y243317D01*
X1113583Y243108D01*
X1113667Y242858D01*
Y242442D01*
X1113792Y242067D01*
X1114042Y241817D01*
X1114333Y241733D01*
X1114625Y241817D01*
X1114833Y242025D01*
X1114958Y242358D01*
X1115000Y242650D01*
G01X1114468Y275684D02*
X1122468D01*
Y263284D01*
X1114468D01*
Y275684D01*
G01X1118468Y273984D02*
X1116968Y275484D01*
G01X1108767Y286292D02*
X1108517Y286417D01*
X1108225Y286500D01*
X1107892D01*
X1107517Y286375D01*
X1107225Y286167D01*
X1107017Y285917D01*
X1106850Y285500D01*
X1106808Y285125D01*
X1106892Y284750D01*
X1107017Y284500D01*
X1107267Y284250D01*
X1107558Y284083D01*
X1107850Y284000D01*
X1108142D01*
X1108433Y284083D01*
X1108683Y284208D01*
X1108892Y284375D01*
G01X1110158Y286083D02*
X1110408Y286333D01*
X1110700Y286458D01*
X1111033Y286500D01*
X1111450Y286417D01*
X1111742Y286208D01*
X1111825Y285958D01*
X1111783Y285708D01*
X1111617Y285500D01*
X1110783Y285083D01*
X1110408Y284792D01*
X1110158Y284375D01*
X1110075Y284000D01*
X1111825D01*
G01X1113258Y285042D02*
X1113550Y285333D01*
X1113800Y285500D01*
X1114133Y285583D01*
X1114425Y285500D01*
X1114633Y285333D01*
X1114800Y285083D01*
X1114842Y284792D01*
X1114800Y284542D01*
X1114633Y284292D01*
X1114383Y284083D01*
X1114092Y284000D01*
X1113758Y284083D01*
X1113467Y284333D01*
X1113300Y284708D01*
X1113258Y285125D01*
X1113342Y285667D01*
X1113467Y285958D01*
X1113675Y286250D01*
X1113967Y286458D01*
X1114258Y286500D01*
X1114550Y286417D01*
X1114758Y286208D01*
G01X1117067Y284000D02*
X1117150Y284542D01*
X1117275Y285000D01*
X1117442Y285417D01*
X1117650Y285875D01*
X1117983Y286500D01*
X1116317D01*
G01X1102000Y433500D02*
Y447500D01*
G01X1104500Y545517D02*
X1102000D01*
Y546558D01*
X1102125Y546892D01*
X1102292Y547100D01*
X1102625Y547183D01*
X1102958Y547100D01*
X1103167Y546850D01*
X1103292Y546558D01*
Y545517D01*
G01Y546558D02*
X1104500Y547183D01*
G01X1103458Y548658D02*
X1103167Y548950D01*
X1103000Y549200D01*
X1102917Y549533D01*
X1103000Y549825D01*
X1103167Y550033D01*
X1103417Y550200D01*
X1103708Y550242D01*
X1103958Y550200D01*
X1104208Y550033D01*
X1104417Y549783D01*
X1104500Y549492D01*
X1104417Y549158D01*
X1104167Y548867D01*
X1103792Y548700D01*
X1103375Y548658D01*
X1102833Y548742D01*
X1102542Y548867D01*
X1102250Y549075D01*
X1102042Y549367D01*
X1102000Y549658D01*
X1102083Y549950D01*
X1102292Y550158D01*
G01X1104500Y552550D02*
X1102000D01*
X1102500Y552050D01*
G01X1104500D02*
Y553050D01*
G01Y555650D02*
X1104458Y555942D01*
X1104333Y556275D01*
X1104125Y556483D01*
X1103833Y556567D01*
X1103542Y556483D01*
X1103292Y556233D01*
X1103167Y555858D01*
Y555442D01*
X1103083Y555192D01*
X1102875Y554983D01*
X1102583Y554900D01*
X1102292Y555025D01*
X1102083Y555317D01*
X1102000Y555650D01*
X1102083Y555983D01*
X1102292Y556275D01*
X1102583Y556400D01*
X1102875Y556317D01*
X1103083Y556108D01*
X1103167Y555858D01*
Y555442D01*
X1103292Y555067D01*
X1103542Y554817D01*
X1103833Y554733D01*
X1104125Y554817D01*
X1104333Y555025D01*
X1104458Y555358D01*
X1104500Y555650D01*
G01X1109500Y574017D02*
X1107000D01*
Y575058D01*
X1107125Y575392D01*
X1107292Y575600D01*
X1107625Y575683D01*
X1107958Y575600D01*
X1108167Y575350D01*
X1108292Y575058D01*
Y574017D01*
G01Y575058D02*
X1109500Y575683D01*
G01X1107417Y577158D02*
X1107167Y577408D01*
X1107042Y577700D01*
X1107000Y578033D01*
X1107083Y578450D01*
X1107292Y578742D01*
X1107542Y578825D01*
X1107792Y578783D01*
X1108000Y578617D01*
X1108417Y577783D01*
X1108708Y577408D01*
X1109125Y577158D01*
X1109500Y577075D01*
Y578825D01*
G01Y581050D02*
X1109458Y581342D01*
X1109333Y581675D01*
X1109125Y581883D01*
X1108833Y581967D01*
X1108542Y581883D01*
X1108292Y581633D01*
X1108167Y581258D01*
Y580842D01*
X1108083Y580592D01*
X1107875Y580383D01*
X1107583Y580300D01*
X1107292Y580425D01*
X1107083Y580717D01*
X1107000Y581050D01*
X1107083Y581383D01*
X1107292Y581675D01*
X1107583Y581800D01*
X1107875Y581717D01*
X1108083Y581508D01*
X1108167Y581258D01*
Y580842D01*
X1108292Y580467D01*
X1108542Y580217D01*
X1108833Y580133D01*
X1109125Y580217D01*
X1109333Y580425D01*
X1109458Y580758D01*
X1109500Y581050D01*
G01Y584150D02*
X1107000D01*
X1107500Y583650D01*
G01X1109500D02*
Y584650D01*
G01X1113500Y574017D02*
X1111000D01*
Y575058D01*
X1111125Y575392D01*
X1111292Y575600D01*
X1111625Y575683D01*
X1111958Y575600D01*
X1112167Y575350D01*
X1112292Y575058D01*
Y574017D01*
G01Y575058D02*
X1113500Y575683D01*
G01X1111417Y577158D02*
X1111167Y577408D01*
X1111042Y577700D01*
X1111000Y578033D01*
X1111083Y578450D01*
X1111292Y578742D01*
X1111542Y578825D01*
X1111792Y578783D01*
X1112000Y578617D01*
X1112417Y577783D01*
X1112708Y577408D01*
X1113125Y577158D01*
X1113500Y577075D01*
Y578825D01*
G01Y581050D02*
X1113458Y581342D01*
X1113333Y581675D01*
X1113125Y581883D01*
X1112833Y581967D01*
X1112542Y581883D01*
X1112292Y581633D01*
X1112167Y581258D01*
Y580842D01*
X1112083Y580592D01*
X1111875Y580383D01*
X1111583Y580300D01*
X1111292Y580425D01*
X1111083Y580717D01*
X1111000Y581050D01*
X1111083Y581383D01*
X1111292Y581675D01*
X1111583Y581800D01*
X1111875Y581717D01*
X1112083Y581508D01*
X1112167Y581258D01*
Y580842D01*
X1112292Y580467D01*
X1112542Y580217D01*
X1112833Y580133D01*
X1113125Y580217D01*
X1113333Y580425D01*
X1113458Y580758D01*
X1113500Y581050D01*
G01X1113000Y583233D02*
X1113292Y583483D01*
X1113458Y583817D01*
X1113500Y584192D01*
X1113458Y584525D01*
X1113250Y584858D01*
X1113000Y585067D01*
X1112750Y585108D01*
X1112458Y585025D01*
X1112250Y584733D01*
X1112167Y584442D01*
Y584067D01*
G01Y584442D02*
X1112042Y584692D01*
X1111833Y584900D01*
X1111583Y584983D01*
X1111333Y584900D01*
X1111125Y584692D01*
X1111000Y584317D01*
X1111042Y583942D01*
X1111208Y583567D01*
G01X1117500Y574017D02*
X1115000D01*
Y575058D01*
X1115125Y575392D01*
X1115292Y575600D01*
X1115625Y575683D01*
X1115958Y575600D01*
X1116167Y575350D01*
X1116292Y575058D01*
Y574017D01*
G01Y575058D02*
X1117500Y575683D01*
G01X1115417Y577158D02*
X1115167Y577408D01*
X1115042Y577700D01*
X1115000Y578033D01*
X1115083Y578450D01*
X1115292Y578742D01*
X1115542Y578825D01*
X1115792Y578783D01*
X1116000Y578617D01*
X1116417Y577783D01*
X1116708Y577408D01*
X1117125Y577158D01*
X1117500Y577075D01*
Y578825D01*
G01Y581050D02*
X1117458Y581342D01*
X1117333Y581675D01*
X1117125Y581883D01*
X1116833Y581967D01*
X1116542Y581883D01*
X1116292Y581633D01*
X1116167Y581258D01*
Y580842D01*
X1116083Y580592D01*
X1115875Y580383D01*
X1115583Y580300D01*
X1115292Y580425D01*
X1115083Y580717D01*
X1115000Y581050D01*
X1115083Y581383D01*
X1115292Y581675D01*
X1115583Y581800D01*
X1115875Y581717D01*
X1116083Y581508D01*
X1116167Y581258D01*
Y580842D01*
X1116292Y580467D01*
X1116542Y580217D01*
X1116833Y580133D01*
X1117125Y580217D01*
X1117333Y580425D01*
X1117458Y580758D01*
X1117500Y581050D01*
G01X1116458Y583358D02*
X1116167Y583650D01*
X1116000Y583900D01*
X1115917Y584233D01*
X1116000Y584525D01*
X1116167Y584733D01*
X1116417Y584900D01*
X1116708Y584942D01*
X1116958Y584900D01*
X1117208Y584733D01*
X1117417Y584483D01*
X1117500Y584192D01*
X1117417Y583858D01*
X1117167Y583567D01*
X1116792Y583400D01*
X1116375Y583358D01*
X1115833Y583442D01*
X1115542Y583567D01*
X1115250Y583775D01*
X1115042Y584067D01*
X1115000Y584358D01*
X1115083Y584650D01*
X1115292Y584858D01*
G01X1105500Y574017D02*
X1103000D01*
Y575058D01*
X1103125Y575392D01*
X1103292Y575600D01*
X1103625Y575683D01*
X1103958Y575600D01*
X1104167Y575350D01*
X1104292Y575058D01*
Y574017D01*
G01Y575058D02*
X1105500Y575683D01*
G01X1104458Y577158D02*
X1104167Y577450D01*
X1104000Y577700D01*
X1103917Y578033D01*
X1104000Y578325D01*
X1104167Y578533D01*
X1104417Y578700D01*
X1104708Y578742D01*
X1104958Y578700D01*
X1105208Y578533D01*
X1105417Y578283D01*
X1105500Y577992D01*
X1105417Y577658D01*
X1105167Y577367D01*
X1104792Y577200D01*
X1104375Y577158D01*
X1103833Y577242D01*
X1103542Y577367D01*
X1103250Y577575D01*
X1103042Y577867D01*
X1103000Y578158D01*
X1103083Y578450D01*
X1103292Y578658D01*
G01X1105500Y581050D02*
X1103000D01*
X1103500Y580550D01*
G01X1105500D02*
Y581550D01*
G01X1103417Y583358D02*
X1103167Y583608D01*
X1103042Y583900D01*
X1103000Y584233D01*
X1103083Y584650D01*
X1103292Y584942D01*
X1103542Y585025D01*
X1103792Y584983D01*
X1104000Y584817D01*
X1104417Y583983D01*
X1104708Y583608D01*
X1105125Y583358D01*
X1105500Y583275D01*
Y585025D01*
G01X1126000Y613000D02*
Y593000D01*
X1117000D01*
X1121000Y597000D01*
Y589000D01*
X1117000Y593000D01*
G01X1118000Y602567D02*
X1115500D01*
Y603608D01*
X1115625Y603942D01*
X1115792Y604150D01*
X1116125Y604233D01*
X1116458Y604150D01*
X1116667Y603900D01*
X1116792Y603608D01*
Y602567D01*
G01Y603608D02*
X1118000Y604233D01*
G01X1115917Y605708D02*
X1115667Y605958D01*
X1115542Y606250D01*
X1115500Y606583D01*
X1115583Y607000D01*
X1115792Y607292D01*
X1116042Y607375D01*
X1116292Y607333D01*
X1116500Y607167D01*
X1116917Y606333D01*
X1117208Y605958D01*
X1117625Y605708D01*
X1118000Y605625D01*
Y607375D01*
G01X1115500Y609600D02*
X1115583Y609267D01*
X1115792Y609017D01*
X1116042Y608850D01*
X1116375Y608725D01*
X1116750Y608683D01*
X1117125Y608725D01*
X1117458Y608850D01*
X1117708Y609017D01*
X1117917Y609267D01*
X1118000Y609600D01*
X1117917Y609933D01*
X1117708Y610183D01*
X1117458Y610350D01*
X1117125Y610475D01*
X1116750Y610517D01*
X1116375Y610475D01*
X1116042Y610350D01*
X1115792Y610183D01*
X1115583Y609933D01*
X1115500Y609600D01*
G01X1119500Y619700D02*
X1115500D01*
Y612300D01*
G01X1109000Y632300D02*
X1113000D01*
Y639700D01*
G01X1109000D02*
X1105000D01*
Y632300D01*
G01X1117000Y639700D02*
X1113000D01*
Y632300D01*
G01X1191870Y729686D02*
X1117066D01*
Y654882D01*
X1191870D01*
Y729686D01*
G01X1102000Y699850D02*
X1104500D01*
G01X1102000Y698892D02*
Y700808D01*
G01X1104500Y702117D02*
X1102000D01*
Y703117D01*
X1102125Y703450D01*
X1102417Y703700D01*
X1102750Y703783D01*
X1103083Y703700D01*
X1103333Y703492D01*
X1103458Y703117D01*
Y702117D01*
G01X1104208Y705342D02*
X1104417Y705633D01*
X1104500Y705967D01*
X1104417Y706300D01*
X1104167Y706592D01*
X1103792Y706800D01*
X1103417Y706883D01*
X1102958D01*
X1102583Y706800D01*
X1102250Y706592D01*
X1102083Y706342D01*
X1102000Y706050D01*
X1102083Y705717D01*
X1102250Y705467D01*
X1102500Y705300D01*
X1102833Y705217D01*
X1103125Y705300D01*
X1103417Y705508D01*
X1103583Y705758D01*
X1103625Y706050D01*
X1103542Y706383D01*
X1103333Y706633D01*
X1102958Y706883D01*
G01X1104500Y709150D02*
X1104458Y709442D01*
X1104333Y709775D01*
X1104125Y709983D01*
X1103833Y710067D01*
X1103542Y709983D01*
X1103292Y709733D01*
X1103167Y709358D01*
Y708942D01*
X1103083Y708692D01*
X1102875Y708483D01*
X1102583Y708400D01*
X1102292Y708525D01*
X1102083Y708817D01*
X1102000Y709150D01*
X1102083Y709483D01*
X1102292Y709775D01*
X1102583Y709900D01*
X1102875Y709817D01*
X1103083Y709608D01*
X1103167Y709358D01*
Y708942D01*
X1103292Y708567D01*
X1103542Y708317D01*
X1103833Y708233D01*
X1104125Y708317D01*
X1104333Y708525D01*
X1104458Y708858D01*
X1104500Y709150D01*
G01X1106000Y699900D02*
X1108500D01*
G01X1106000Y698942D02*
Y700858D01*
G01X1108500Y702167D02*
X1106000D01*
Y703167D01*
X1106125Y703500D01*
X1106417Y703750D01*
X1106750Y703833D01*
X1107083Y703750D01*
X1107333Y703542D01*
X1107458Y703167D01*
Y702167D01*
G01X1108500Y706100D02*
X1106000D01*
X1106500Y705600D01*
G01X1108500D02*
Y706600D01*
G01Y709700D02*
X1106000D01*
X1107792Y708158D01*
Y710242D01*
G01X1108000Y711383D02*
X1108292Y711633D01*
X1108458Y711967D01*
X1108500Y712342D01*
X1108458Y712675D01*
X1108250Y713008D01*
X1108000Y713217D01*
X1107750Y713258D01*
X1107458Y713175D01*
X1107250Y712883D01*
X1107167Y712592D01*
Y712217D01*
G01Y712592D02*
X1107042Y712842D01*
X1106833Y713050D01*
X1106583Y713133D01*
X1106333Y713050D01*
X1106125Y712842D01*
X1106000Y712467D01*
X1106042Y712092D01*
X1106208Y711717D01*
G01X1110000Y719300D02*
X1112500D01*
G01X1110000Y718342D02*
Y720258D01*
G01X1112500Y721567D02*
X1110000D01*
Y722567D01*
X1110125Y722900D01*
X1110417Y723150D01*
X1110750Y723233D01*
X1111083Y723150D01*
X1111333Y722942D01*
X1111458Y722567D01*
Y721567D01*
G01X1112500Y725500D02*
X1110000D01*
X1110500Y725000D01*
G01X1112500D02*
Y726000D01*
G01Y729100D02*
X1110000D01*
X1111792Y727558D01*
Y729642D01*
G01X1112500Y732200D02*
X1110000D01*
X1111792Y730658D01*
Y732742D01*
G01X1113000Y747700D02*
X1109000D01*
Y740300D01*
G01X1114208Y762267D02*
X1114083Y762017D01*
X1114000Y761725D01*
Y761392D01*
X1114125Y761017D01*
X1114333Y760725D01*
X1114583Y760517D01*
X1115000Y760350D01*
X1115375Y760308D01*
X1115750Y760392D01*
X1116000Y760517D01*
X1116250Y760767D01*
X1116417Y761058D01*
X1116500Y761350D01*
Y761642D01*
X1116417Y761933D01*
X1116292Y762183D01*
X1116125Y762392D01*
G01X1116500Y764450D02*
X1114000D01*
X1114500Y763950D01*
G01X1116500D02*
Y764950D01*
G01Y767467D02*
X1115958Y767550D01*
X1115500Y767675D01*
X1115083Y767842D01*
X1114625Y768050D01*
X1114000Y768383D01*
Y766717D01*
G01X1115458Y769858D02*
X1115167Y770150D01*
X1115000Y770400D01*
X1114917Y770733D01*
X1115000Y771025D01*
X1115167Y771233D01*
X1115417Y771400D01*
X1115708Y771442D01*
X1115958Y771400D01*
X1116208Y771233D01*
X1116417Y770983D01*
X1116500Y770692D01*
X1116417Y770358D01*
X1116167Y770067D01*
X1115792Y769900D01*
X1115375Y769858D01*
X1114833Y769942D01*
X1114542Y770067D01*
X1114250Y770275D01*
X1114042Y770567D01*
X1114000Y770858D01*
X1114083Y771150D01*
X1114292Y771358D01*
G01X1109708Y762267D02*
X1109583Y762017D01*
X1109500Y761725D01*
Y761392D01*
X1109625Y761017D01*
X1109833Y760725D01*
X1110083Y760517D01*
X1110500Y760350D01*
X1110875Y760308D01*
X1111250Y760392D01*
X1111500Y760517D01*
X1111750Y760767D01*
X1111917Y761058D01*
X1112000Y761350D01*
Y761642D01*
X1111917Y761933D01*
X1111792Y762183D01*
X1111625Y762392D01*
G01X1112000Y764450D02*
X1109500D01*
X1110000Y763950D01*
G01X1112000D02*
Y764950D01*
G01Y767550D02*
X1111958Y767842D01*
X1111833Y768175D01*
X1111625Y768383D01*
X1111333Y768467D01*
X1111042Y768383D01*
X1110792Y768133D01*
X1110667Y767758D01*
Y767342D01*
X1110583Y767092D01*
X1110375Y766883D01*
X1110083Y766800D01*
X1109792Y766925D01*
X1109583Y767217D01*
X1109500Y767550D01*
X1109583Y767883D01*
X1109792Y768175D01*
X1110083Y768300D01*
X1110375Y768217D01*
X1110583Y768008D01*
X1110667Y767758D01*
Y767342D01*
X1110792Y766967D01*
X1111042Y766717D01*
X1111333Y766633D01*
X1111625Y766717D01*
X1111833Y766925D01*
X1111958Y767258D01*
X1112000Y767550D01*
G01X1111500Y769733D02*
X1111792Y769983D01*
X1111958Y770317D01*
X1112000Y770692D01*
X1111958Y771025D01*
X1111750Y771358D01*
X1111500Y771567D01*
X1111250Y771608D01*
X1110958Y771525D01*
X1110750Y771233D01*
X1110667Y770942D01*
Y770567D01*
G01Y770942D02*
X1110542Y771192D01*
X1110333Y771400D01*
X1110083Y771483D01*
X1109833Y771400D01*
X1109625Y771192D01*
X1109500Y770817D01*
X1109542Y770442D01*
X1109708Y770067D01*
G01X1105708Y752267D02*
X1105583Y752017D01*
X1105500Y751725D01*
Y751392D01*
X1105625Y751017D01*
X1105833Y750725D01*
X1106083Y750517D01*
X1106500Y750350D01*
X1106875Y750308D01*
X1107250Y750392D01*
X1107500Y750517D01*
X1107750Y750767D01*
X1107917Y751058D01*
X1108000Y751350D01*
Y751642D01*
X1107917Y751933D01*
X1107792Y752183D01*
X1107625Y752392D01*
G01X1105917Y753658D02*
X1105667Y753908D01*
X1105542Y754200D01*
X1105500Y754533D01*
X1105583Y754950D01*
X1105792Y755242D01*
X1106042Y755325D01*
X1106292Y755283D01*
X1106500Y755117D01*
X1106917Y754283D01*
X1107208Y753908D01*
X1107625Y753658D01*
X1108000Y753575D01*
Y755325D01*
G01X1105500Y757550D02*
X1105583Y757217D01*
X1105792Y756967D01*
X1106042Y756800D01*
X1106375Y756675D01*
X1106750Y756633D01*
X1107125Y756675D01*
X1107458Y756800D01*
X1107708Y756967D01*
X1107917Y757217D01*
X1108000Y757550D01*
X1107917Y757883D01*
X1107708Y758133D01*
X1107458Y758300D01*
X1107125Y758425D01*
X1106750Y758467D01*
X1106375Y758425D01*
X1106042Y758300D01*
X1105792Y758133D01*
X1105583Y757883D01*
X1105500Y757550D01*
G01X1107500Y759733D02*
X1107792Y759983D01*
X1107958Y760317D01*
X1108000Y760692D01*
X1107958Y761025D01*
X1107750Y761358D01*
X1107500Y761567D01*
X1107250Y761608D01*
X1106958Y761525D01*
X1106750Y761233D01*
X1106667Y760942D01*
Y760567D01*
G01Y760942D02*
X1106542Y761192D01*
X1106333Y761400D01*
X1106083Y761483D01*
X1105833Y761400D01*
X1105625Y761192D01*
X1105500Y760817D01*
X1105542Y760442D01*
X1105708Y760067D01*
G01X1109468Y811784D02*
X1105468D01*
Y804384D01*
G01X1109546Y826794D02*
Y813394D01*
G01X1113767Y822292D02*
X1113517Y822417D01*
X1113225Y822500D01*
X1112892D01*
X1112517Y822375D01*
X1112225Y822167D01*
X1112017Y821917D01*
X1111850Y821500D01*
X1111808Y821125D01*
X1111892Y820750D01*
X1112017Y820500D01*
X1112267Y820250D01*
X1112558Y820083D01*
X1112850Y820000D01*
X1113142D01*
X1113433Y820083D01*
X1113683Y820208D01*
X1113892Y820375D01*
G01X1115158Y822083D02*
X1115408Y822333D01*
X1115700Y822458D01*
X1116033Y822500D01*
X1116450Y822417D01*
X1116742Y822208D01*
X1116825Y821958D01*
X1116783Y821708D01*
X1116617Y821500D01*
X1115783Y821083D01*
X1115408Y820792D01*
X1115158Y820375D01*
X1115075Y820000D01*
X1116825D01*
G01X1118967D02*
X1119050Y820542D01*
X1119175Y821000D01*
X1119342Y821417D01*
X1119550Y821875D01*
X1119883Y822500D01*
X1118217D01*
G01X1121358Y822083D02*
X1121608Y822333D01*
X1121900Y822458D01*
X1122233Y822500D01*
X1122650Y822417D01*
X1122942Y822208D01*
X1123025Y821958D01*
X1122983Y821708D01*
X1122817Y821500D01*
X1121983Y821083D01*
X1121608Y820792D01*
X1121358Y820375D01*
X1121275Y820000D01*
X1123025D01*
G01X1113000Y830017D02*
X1110500D01*
Y831058D01*
X1110625Y831392D01*
X1110792Y831600D01*
X1111125Y831683D01*
X1111458Y831600D01*
X1111667Y831350D01*
X1111792Y831058D01*
Y830017D01*
G01Y831058D02*
X1113000Y831683D01*
G01Y833950D02*
X1110500D01*
X1111000Y833450D01*
G01X1113000D02*
Y834450D01*
G01X1110917Y836258D02*
X1110667Y836508D01*
X1110542Y836800D01*
X1110500Y837133D01*
X1110583Y837550D01*
X1110792Y837842D01*
X1111042Y837925D01*
X1111292Y837883D01*
X1111500Y837717D01*
X1111917Y836883D01*
X1112208Y836508D01*
X1112625Y836258D01*
X1113000Y836175D01*
Y837925D01*
G01X1112625Y839233D02*
X1112833Y839483D01*
X1112958Y839775D01*
X1113000Y840150D01*
X1112917Y840525D01*
X1112750Y840817D01*
X1112458Y841025D01*
X1112125Y841067D01*
X1111792Y840983D01*
X1111583Y840775D01*
X1111417Y840483D01*
X1111375Y840192D01*
X1111417Y839900D01*
X1111583Y839525D01*
X1110500Y839650D01*
Y840775D01*
G01X1108500Y839200D02*
X1104500D01*
Y831800D01*
G01X1118000Y842517D02*
X1115500D01*
Y843517D01*
X1115625Y843850D01*
X1115917Y844100D01*
X1116250Y844183D01*
X1116583Y844100D01*
X1116833Y843892D01*
X1116958Y843517D01*
Y842517D01*
G01X1115708Y847367D02*
X1115583Y847117D01*
X1115500Y846825D01*
Y846492D01*
X1115625Y846117D01*
X1115833Y845825D01*
X1116083Y845617D01*
X1116500Y845450D01*
X1116875Y845408D01*
X1117250Y845492D01*
X1117500Y845617D01*
X1117750Y845867D01*
X1117917Y846158D01*
X1118000Y846450D01*
Y846742D01*
X1117917Y847033D01*
X1117792Y847283D01*
X1117625Y847492D01*
G01X1118000Y849550D02*
X1117958Y849842D01*
X1117833Y850175D01*
X1117625Y850383D01*
X1117333Y850467D01*
X1117042Y850383D01*
X1116792Y850133D01*
X1116667Y849758D01*
Y849342D01*
X1116583Y849092D01*
X1116375Y848883D01*
X1116083Y848800D01*
X1115792Y848925D01*
X1115583Y849217D01*
X1115500Y849550D01*
X1115583Y849883D01*
X1115792Y850175D01*
X1116083Y850300D01*
X1116375Y850217D01*
X1116583Y850008D01*
X1116667Y849758D01*
Y849342D01*
X1116792Y848967D01*
X1117042Y848717D01*
X1117333Y848633D01*
X1117625Y848717D01*
X1117833Y848925D01*
X1117958Y849258D01*
X1118000Y849550D01*
G01Y852567D02*
X1117458Y852650D01*
X1117000Y852775D01*
X1116583Y852942D01*
X1116125Y853150D01*
X1115500Y853483D01*
Y851817D01*
G01X1102618Y861434D02*
Y856434D01*
X1107618D01*
G01X1103968Y845084D02*
X1107968D01*
Y852484D01*
G01X1114067Y889000D02*
Y891500D01*
X1115067D01*
X1115400Y891375D01*
X1115650Y891083D01*
X1115733Y890750D01*
X1115650Y890417D01*
X1115442Y890167D01*
X1115067Y890042D01*
X1114067D01*
G01X1117083Y891500D02*
Y889708D01*
X1117250Y889333D01*
X1117583Y889083D01*
X1118000Y889000D01*
X1118417Y889083D01*
X1118750Y889333D01*
X1118917Y889708D01*
Y891500D01*
G01X1120183Y889375D02*
X1120433Y889167D01*
X1120725Y889042D01*
X1121100Y889000D01*
X1121475Y889083D01*
X1121767Y889250D01*
X1121975Y889542D01*
X1122017Y889875D01*
X1121933Y890208D01*
X1121725Y890417D01*
X1121433Y890583D01*
X1121142Y890625D01*
X1120850Y890583D01*
X1120475Y890417D01*
X1120600Y891500D01*
X1121725D01*
G01X1107618Y884134D02*
X1102618D01*
Y879134D01*
G01X1111350Y882727D02*
Y884727D01*
G01X1129067Y234500D02*
Y237000D01*
X1130067D01*
X1130400Y236875D01*
X1130650Y236583D01*
X1130733Y236250D01*
X1130650Y235917D01*
X1130442Y235667D01*
X1130067Y235542D01*
X1129067D01*
G01X1133000Y234500D02*
X1132667Y234542D01*
X1132375Y234708D01*
X1132125Y234958D01*
X1131958Y235250D01*
X1131875Y235583D01*
Y235917D01*
X1131958Y236250D01*
X1132125Y236542D01*
X1132375Y236792D01*
X1132667Y236958D01*
X1133000Y237000D01*
X1133333Y236958D01*
X1133625Y236792D01*
X1133875Y236542D01*
X1134042Y236250D01*
X1134125Y235917D01*
Y235583D01*
X1134042Y235250D01*
X1133875Y234958D01*
X1133625Y234708D01*
X1133333Y234542D01*
X1133000Y234500D01*
G01X1133333Y235167D02*
X1133833Y234500D01*
G01X1136100D02*
Y237000D01*
X1135600Y236500D01*
G01Y234500D02*
X1136600D01*
G01X1135500Y241967D02*
X1133000D01*
Y242967D01*
X1133125Y243300D01*
X1133417Y243550D01*
X1133750Y243633D01*
X1134083Y243550D01*
X1134333Y243342D01*
X1134458Y242967D01*
Y241967D01*
G01X1133208Y246817D02*
X1133083Y246567D01*
X1133000Y246275D01*
Y245942D01*
X1133125Y245567D01*
X1133333Y245275D01*
X1133583Y245067D01*
X1134000Y244900D01*
X1134375Y244858D01*
X1134750Y244942D01*
X1135000Y245067D01*
X1135250Y245317D01*
X1135417Y245608D01*
X1135500Y245900D01*
Y246192D01*
X1135417Y246483D01*
X1135292Y246733D01*
X1135125Y246942D01*
G01X1135500Y249000D02*
X1133000D01*
X1133500Y248500D01*
G01X1135500D02*
Y249500D01*
G01X1135000Y251183D02*
X1135292Y251433D01*
X1135458Y251767D01*
X1135500Y252142D01*
X1135458Y252475D01*
X1135250Y252808D01*
X1135000Y253017D01*
X1134750Y253058D01*
X1134458Y252975D01*
X1134250Y252683D01*
X1134167Y252392D01*
Y252017D01*
G01Y252392D02*
X1134042Y252642D01*
X1133833Y252850D01*
X1133583Y252933D01*
X1133333Y252850D01*
X1133125Y252642D01*
X1133000Y252267D01*
X1133042Y251892D01*
X1133208Y251517D01*
G01X1135500Y255117D02*
X1134958Y255200D01*
X1134500Y255325D01*
X1134083Y255492D01*
X1133625Y255700D01*
X1133000Y256033D01*
Y254367D01*
G01X1118468Y273984D02*
X1119968Y275484D01*
G01X1126500Y283517D02*
X1124000D01*
Y284558D01*
X1124125Y284892D01*
X1124292Y285100D01*
X1124625Y285183D01*
X1124958Y285100D01*
X1125167Y284850D01*
X1125292Y284558D01*
Y283517D01*
G01Y284558D02*
X1126500Y285183D01*
G01Y287950D02*
X1124000D01*
X1125792Y286408D01*
Y288492D01*
G01X1126500Y290550D02*
X1126458Y290842D01*
X1126333Y291175D01*
X1126125Y291383D01*
X1125833Y291467D01*
X1125542Y291383D01*
X1125292Y291133D01*
X1125167Y290758D01*
Y290342D01*
X1125083Y290092D01*
X1124875Y289883D01*
X1124583Y289800D01*
X1124292Y289925D01*
X1124083Y290217D01*
X1124000Y290550D01*
X1124083Y290883D01*
X1124292Y291175D01*
X1124583Y291300D01*
X1124875Y291217D01*
X1125083Y291008D01*
X1125167Y290758D01*
Y290342D01*
X1125292Y289967D01*
X1125542Y289717D01*
X1125833Y289633D01*
X1126125Y289717D01*
X1126333Y289925D01*
X1126458Y290258D01*
X1126500Y290550D01*
G01Y293650D02*
X1126458Y293942D01*
X1126333Y294275D01*
X1126125Y294483D01*
X1125833Y294567D01*
X1125542Y294483D01*
X1125292Y294233D01*
X1125167Y293858D01*
Y293442D01*
X1125083Y293192D01*
X1124875Y292983D01*
X1124583Y292900D01*
X1124292Y293025D01*
X1124083Y293317D01*
X1124000Y293650D01*
X1124083Y293983D01*
X1124292Y294275D01*
X1124583Y294400D01*
X1124875Y294317D01*
X1125083Y294108D01*
X1125167Y293858D01*
Y293442D01*
X1125292Y293067D01*
X1125542Y292817D01*
X1125833Y292733D01*
X1126125Y292817D01*
X1126333Y293025D01*
X1126458Y293358D01*
X1126500Y293650D01*
G01X1131200Y276000D02*
Y280000D01*
X1123800D01*
G01X1121500Y574017D02*
X1119000D01*
Y575058D01*
X1119125Y575392D01*
X1119292Y575600D01*
X1119625Y575683D01*
X1119958Y575600D01*
X1120167Y575350D01*
X1120292Y575058D01*
Y574017D01*
G01Y575058D02*
X1121500Y575683D01*
G01X1119417Y577158D02*
X1119167Y577408D01*
X1119042Y577700D01*
X1119000Y578033D01*
X1119083Y578450D01*
X1119292Y578742D01*
X1119542Y578825D01*
X1119792Y578783D01*
X1120000Y578617D01*
X1120417Y577783D01*
X1120708Y577408D01*
X1121125Y577158D01*
X1121500Y577075D01*
Y578825D01*
G01Y581050D02*
X1121458Y581342D01*
X1121333Y581675D01*
X1121125Y581883D01*
X1120833Y581967D01*
X1120542Y581883D01*
X1120292Y581633D01*
X1120167Y581258D01*
Y580842D01*
X1120083Y580592D01*
X1119875Y580383D01*
X1119583Y580300D01*
X1119292Y580425D01*
X1119083Y580717D01*
X1119000Y581050D01*
X1119083Y581383D01*
X1119292Y581675D01*
X1119583Y581800D01*
X1119875Y581717D01*
X1120083Y581508D01*
X1120167Y581258D01*
Y580842D01*
X1120292Y580467D01*
X1120542Y580217D01*
X1120833Y580133D01*
X1121125Y580217D01*
X1121333Y580425D01*
X1121458Y580758D01*
X1121500Y581050D01*
G01Y584650D02*
X1119000D01*
X1120792Y583108D01*
Y585192D01*
G01X1131017Y596000D02*
Y598500D01*
X1132058D01*
X1132392Y598375D01*
X1132600Y598208D01*
X1132683Y597875D01*
X1132600Y597542D01*
X1132350Y597333D01*
X1132058Y597208D01*
X1131017D01*
G01X1132058D02*
X1132683Y596000D01*
G01X1135450D02*
Y598500D01*
X1133908Y596708D01*
X1135992D01*
G01X1138050Y598500D02*
X1137717Y598417D01*
X1137467Y598208D01*
X1137300Y597958D01*
X1137175Y597625D01*
X1137133Y597250D01*
X1137175Y596875D01*
X1137300Y596542D01*
X1137467Y596292D01*
X1137717Y596083D01*
X1138050Y596000D01*
X1138383Y596083D01*
X1138633Y596292D01*
X1138800Y596542D01*
X1138925Y596875D01*
X1138967Y597250D01*
X1138925Y597625D01*
X1138800Y597958D01*
X1138633Y598208D01*
X1138383Y598417D01*
X1138050Y598500D01*
G01X1141150D02*
X1140817Y598417D01*
X1140567Y598208D01*
X1140400Y597958D01*
X1140275Y597625D01*
X1140233Y597250D01*
X1140275Y596875D01*
X1140400Y596542D01*
X1140567Y596292D01*
X1140817Y596083D01*
X1141150Y596000D01*
X1141483Y596083D01*
X1141733Y596292D01*
X1141900Y596542D01*
X1142025Y596875D01*
X1142067Y597250D01*
X1142025Y597625D01*
X1141900Y597958D01*
X1141733Y598208D01*
X1141483Y598417D01*
X1141150Y598500D01*
G01X1154500Y620000D02*
Y613000D01*
X1126000D01*
Y630000D01*
X1122500D01*
Y631000D01*
G01Y602567D02*
X1120000D01*
Y603608D01*
X1120125Y603942D01*
X1120292Y604150D01*
X1120625Y604233D01*
X1120958Y604150D01*
X1121167Y603900D01*
X1121292Y603608D01*
Y602567D01*
G01Y603608D02*
X1122500Y604233D01*
G01X1120417Y605708D02*
X1120167Y605958D01*
X1120042Y606250D01*
X1120000Y606583D01*
X1120083Y607000D01*
X1120292Y607292D01*
X1120542Y607375D01*
X1120792Y607333D01*
X1121000Y607167D01*
X1121417Y606333D01*
X1121708Y605958D01*
X1122125Y605708D01*
X1122500Y605625D01*
Y607375D01*
G01X1122000Y608683D02*
X1122292Y608933D01*
X1122458Y609267D01*
X1122500Y609642D01*
X1122458Y609975D01*
X1122250Y610308D01*
X1122000Y610517D01*
X1121750Y610558D01*
X1121458Y610475D01*
X1121250Y610183D01*
X1121167Y609892D01*
Y609517D01*
G01Y609892D02*
X1121042Y610142D01*
X1120833Y610350D01*
X1120583Y610433D01*
X1120333Y610350D01*
X1120125Y610142D01*
X1120000Y609767D01*
X1120042Y609392D01*
X1120208Y609017D01*
G01X1124000Y619700D02*
X1120000D01*
Y612300D01*
G01X1133267Y605792D02*
X1133017Y605917D01*
X1132725Y606000D01*
X1132392D01*
X1132017Y605875D01*
X1131725Y605667D01*
X1131517Y605417D01*
X1131350Y605000D01*
X1131308Y604625D01*
X1131392Y604250D01*
X1131517Y604000D01*
X1131767Y603750D01*
X1132058Y603583D01*
X1132350Y603500D01*
X1132642D01*
X1132933Y603583D01*
X1133183Y603708D01*
X1133392Y603875D01*
G01X1134658Y605583D02*
X1134908Y605833D01*
X1135200Y605958D01*
X1135533Y606000D01*
X1135950Y605917D01*
X1136242Y605708D01*
X1136325Y605458D01*
X1136283Y605208D01*
X1136117Y605000D01*
X1135283Y604583D01*
X1134908Y604292D01*
X1134658Y603875D01*
X1134575Y603500D01*
X1136325D01*
G01X1137633Y604000D02*
X1137883Y603708D01*
X1138217Y603542D01*
X1138592Y603500D01*
X1138925Y603542D01*
X1139258Y603750D01*
X1139467Y604000D01*
X1139508Y604250D01*
X1139425Y604542D01*
X1139133Y604750D01*
X1138842Y604833D01*
X1138467D01*
G01X1138842D02*
X1139092Y604958D01*
X1139300Y605167D01*
X1139383Y605417D01*
X1139300Y605667D01*
X1139092Y605875D01*
X1138717Y606000D01*
X1138342Y605958D01*
X1137967Y605792D01*
G01X1140858Y605583D02*
X1141108Y605833D01*
X1141400Y605958D01*
X1141733Y606000D01*
X1142150Y605917D01*
X1142442Y605708D01*
X1142525Y605458D01*
X1142483Y605208D01*
X1142317Y605000D01*
X1141483Y604583D01*
X1141108Y604292D01*
X1140858Y603875D01*
X1140775Y603500D01*
X1142525D01*
G01X1135200Y616000D02*
Y620000D01*
X1127800D01*
G01X1123500Y641000D02*
X1126500D01*
G01X1132000Y640500D02*
X1136000D01*
Y647000D01*
X1149500D01*
G01X1127000Y632300D02*
X1131000D01*
Y639700D01*
G01Y632300D02*
X1135000D01*
Y639700D01*
G01X1123000Y632300D02*
X1127000D01*
Y639700D01*
G01X1124500Y737017D02*
X1122000D01*
Y738058D01*
X1122125Y738392D01*
X1122292Y738600D01*
X1122625Y738683D01*
X1122958Y738600D01*
X1123167Y738350D01*
X1123292Y738058D01*
Y737017D01*
G01Y738058D02*
X1124500Y738683D01*
G01X1122417Y740158D02*
X1122167Y740408D01*
X1122042Y740700D01*
X1122000Y741033D01*
X1122083Y741450D01*
X1122292Y741742D01*
X1122542Y741825D01*
X1122792Y741783D01*
X1123000Y741617D01*
X1123417Y740783D01*
X1123708Y740408D01*
X1124125Y740158D01*
X1124500Y740075D01*
Y741825D01*
G01X1124208Y743342D02*
X1124417Y743633D01*
X1124500Y743967D01*
X1124417Y744300D01*
X1124167Y744592D01*
X1123792Y744800D01*
X1123417Y744883D01*
X1122958D01*
X1122583Y744800D01*
X1122250Y744592D01*
X1122083Y744342D01*
X1122000Y744050D01*
X1122083Y743717D01*
X1122250Y743467D01*
X1122500Y743300D01*
X1122833Y743217D01*
X1123125Y743300D01*
X1123417Y743508D01*
X1123583Y743758D01*
X1123625Y744050D01*
X1123542Y744383D01*
X1123333Y744633D01*
X1122958Y744883D01*
G01X1124500Y747150D02*
X1124458Y747442D01*
X1124333Y747775D01*
X1124125Y747983D01*
X1123833Y748067D01*
X1123542Y747983D01*
X1123292Y747733D01*
X1123167Y747358D01*
Y746942D01*
X1123083Y746692D01*
X1122875Y746483D01*
X1122583Y746400D01*
X1122292Y746525D01*
X1122083Y746817D01*
X1122000Y747150D01*
X1122083Y747483D01*
X1122292Y747775D01*
X1122583Y747900D01*
X1122875Y747817D01*
X1123083Y747608D01*
X1123167Y747358D01*
Y746942D01*
X1123292Y746567D01*
X1123542Y746317D01*
X1123833Y746233D01*
X1124125Y746317D01*
X1124333Y746525D01*
X1124458Y746858D01*
X1124500Y747150D01*
G01X1119677Y802501D02*
Y767067D01*
X1170859D01*
Y802501D01*
X1119677D01*
G01X1133767Y811792D02*
X1133517Y811917D01*
X1133225Y812000D01*
X1132892D01*
X1132517Y811875D01*
X1132225Y811667D01*
X1132017Y811417D01*
X1131850Y811000D01*
X1131808Y810625D01*
X1131892Y810250D01*
X1132017Y810000D01*
X1132267Y809750D01*
X1132558Y809583D01*
X1132850Y809500D01*
X1133142D01*
X1133433Y809583D01*
X1133683Y809708D01*
X1133892Y809875D01*
G01X1135950Y809500D02*
Y812000D01*
X1135450Y811500D01*
G01Y809500D02*
X1136450D01*
G01X1138967D02*
X1139050Y810042D01*
X1139175Y810500D01*
X1139342Y810917D01*
X1139550Y811375D01*
X1139883Y812000D01*
X1138217D01*
G01X1142650Y809500D02*
Y812000D01*
X1141108Y810208D01*
X1143192D01*
G01X1132017Y814500D02*
Y817000D01*
X1133058D01*
X1133392Y816875D01*
X1133600Y816708D01*
X1133683Y816375D01*
X1133600Y816042D01*
X1133350Y815833D01*
X1133058Y815708D01*
X1132017D01*
G01X1133058D02*
X1133683Y814500D01*
G01X1135158Y816583D02*
X1135408Y816833D01*
X1135700Y816958D01*
X1136033Y817000D01*
X1136450Y816917D01*
X1136742Y816708D01*
X1136825Y816458D01*
X1136783Y816208D01*
X1136617Y816000D01*
X1135783Y815583D01*
X1135408Y815292D01*
X1135158Y814875D01*
X1135075Y814500D01*
X1136825D01*
G01X1138133Y815000D02*
X1138383Y814708D01*
X1138717Y814542D01*
X1139092Y814500D01*
X1139425Y814542D01*
X1139758Y814750D01*
X1139967Y815000D01*
X1140008Y815250D01*
X1139925Y815542D01*
X1139633Y815750D01*
X1139342Y815833D01*
X1138967D01*
G01X1139342D02*
X1139592Y815958D01*
X1139800Y816167D01*
X1139883Y816417D01*
X1139800Y816667D01*
X1139592Y816875D01*
X1139217Y817000D01*
X1138842Y816958D01*
X1138467Y816792D01*
G01X1141358Y816583D02*
X1141608Y816833D01*
X1141900Y816958D01*
X1142233Y817000D01*
X1142650Y816917D01*
X1142942Y816708D01*
X1143025Y816458D01*
X1142983Y816208D01*
X1142817Y816000D01*
X1141983Y815583D01*
X1141608Y815292D01*
X1141358Y814875D01*
X1141275Y814500D01*
X1143025D01*
G01X1128708Y839267D02*
X1128583Y839017D01*
X1128500Y838725D01*
Y838392D01*
X1128625Y838017D01*
X1128833Y837725D01*
X1129083Y837517D01*
X1129500Y837350D01*
X1129875Y837308D01*
X1130250Y837392D01*
X1130500Y837517D01*
X1130750Y837767D01*
X1130917Y838058D01*
X1131000Y838350D01*
Y838642D01*
X1130917Y838933D01*
X1130792Y839183D01*
X1130625Y839392D01*
G01X1131000Y841450D02*
X1128500D01*
X1129000Y840950D01*
G01X1131000D02*
Y841950D01*
G01Y844467D02*
X1130458Y844550D01*
X1130000Y844675D01*
X1129583Y844842D01*
X1129125Y845050D01*
X1128500Y845383D01*
Y843717D01*
G01Y847650D02*
X1128583Y847317D01*
X1128792Y847067D01*
X1129042Y846900D01*
X1129375Y846775D01*
X1129750Y846733D01*
X1130125Y846775D01*
X1130458Y846900D01*
X1130708Y847067D01*
X1130917Y847317D01*
X1131000Y847650D01*
X1130917Y847983D01*
X1130708Y848233D01*
X1130458Y848400D01*
X1130125Y848525D01*
X1129750Y848567D01*
X1129375Y848525D01*
X1129042Y848400D01*
X1128792Y848233D01*
X1128583Y847983D01*
X1128500Y847650D01*
G01X1133708Y837267D02*
X1133583Y837017D01*
X1133500Y836725D01*
Y836392D01*
X1133625Y836017D01*
X1133833Y835725D01*
X1134083Y835517D01*
X1134500Y835350D01*
X1134875Y835308D01*
X1135250Y835392D01*
X1135500Y835517D01*
X1135750Y835767D01*
X1135917Y836058D01*
X1136000Y836350D01*
Y836642D01*
X1135917Y836933D01*
X1135792Y837183D01*
X1135625Y837392D01*
G01X1136000Y839450D02*
X1133500D01*
X1134000Y838950D01*
G01X1136000D02*
Y839950D01*
G01Y842467D02*
X1135458Y842550D01*
X1135000Y842675D01*
X1134583Y842842D01*
X1134125Y843050D01*
X1133500Y843383D01*
Y841717D01*
G01X1133917Y844858D02*
X1133667Y845108D01*
X1133542Y845400D01*
X1133500Y845733D01*
X1133583Y846150D01*
X1133792Y846442D01*
X1134042Y846525D01*
X1134292Y846483D01*
X1134500Y846317D01*
X1134917Y845483D01*
X1135208Y845108D01*
X1135625Y844858D01*
X1136000Y844775D01*
Y846525D01*
G01X1125318Y856434D02*
X1130318D01*
Y861434D01*
G01X1121586Y857841D02*
Y855841D01*
G01X1137468Y863984D02*
X1133468D01*
Y856584D01*
G01X1128911Y875402D02*
X1131911D01*
G01X1134517Y866000D02*
Y868500D01*
X1135517D01*
X1135850Y868375D01*
X1136100Y868083D01*
X1136183Y867750D01*
X1136100Y867417D01*
X1135892Y867167D01*
X1135517Y867042D01*
X1134517D01*
G01X1137617Y866000D02*
Y868500D01*
X1138658D01*
X1138992Y868375D01*
X1139200Y868208D01*
X1139283Y867875D01*
X1139200Y867542D01*
X1138950Y867333D01*
X1138658Y867208D01*
X1137617D01*
G01X1138658D02*
X1139283Y866000D01*
G01X1141550D02*
X1141842Y866042D01*
X1142175Y866167D01*
X1142383Y866375D01*
X1142467Y866667D01*
X1142383Y866958D01*
X1142133Y867208D01*
X1141758Y867333D01*
X1141342D01*
X1141092Y867417D01*
X1140883Y867625D01*
X1140800Y867917D01*
X1140925Y868208D01*
X1141217Y868417D01*
X1141550Y868500D01*
X1141883Y868417D01*
X1142175Y868208D01*
X1142300Y867917D01*
X1142217Y867625D01*
X1142008Y867417D01*
X1141758Y867333D01*
X1141342D01*
X1140967Y867208D01*
X1140717Y866958D01*
X1140633Y866667D01*
X1140717Y866375D01*
X1140925Y866167D01*
X1141258Y866042D01*
X1141550Y866000D01*
G01X1144650Y868500D02*
X1144317Y868417D01*
X1144067Y868208D01*
X1143900Y867958D01*
X1143775Y867625D01*
X1143733Y867250D01*
X1143775Y866875D01*
X1143900Y866542D01*
X1144067Y866292D01*
X1144317Y866083D01*
X1144650Y866000D01*
X1144983Y866083D01*
X1145233Y866292D01*
X1145400Y866542D01*
X1145525Y866875D01*
X1145567Y867250D01*
X1145525Y867625D01*
X1145400Y867958D01*
X1145233Y868208D01*
X1144983Y868417D01*
X1144650Y868500D01*
G01X1136000Y886517D02*
X1133500D01*
Y887517D01*
X1133625Y887850D01*
X1133917Y888100D01*
X1134250Y888183D01*
X1134583Y888100D01*
X1134833Y887892D01*
X1134958Y887517D01*
Y886517D01*
G01X1133708Y891367D02*
X1133583Y891117D01*
X1133500Y890825D01*
Y890492D01*
X1133625Y890117D01*
X1133833Y889825D01*
X1134083Y889617D01*
X1134500Y889450D01*
X1134875Y889408D01*
X1135250Y889492D01*
X1135500Y889617D01*
X1135750Y889867D01*
X1135917Y890158D01*
X1136000Y890450D01*
Y890742D01*
X1135917Y891033D01*
X1135792Y891283D01*
X1135625Y891492D01*
G01X1136000Y893550D02*
X1135958Y893842D01*
X1135833Y894175D01*
X1135625Y894383D01*
X1135333Y894467D01*
X1135042Y894383D01*
X1134792Y894133D01*
X1134667Y893758D01*
Y893342D01*
X1134583Y893092D01*
X1134375Y892883D01*
X1134083Y892800D01*
X1133792Y892925D01*
X1133583Y893217D01*
X1133500Y893550D01*
X1133583Y893883D01*
X1133792Y894175D01*
X1134083Y894300D01*
X1134375Y894217D01*
X1134583Y894008D01*
X1134667Y893758D01*
Y893342D01*
X1134792Y892967D01*
X1135042Y892717D01*
X1135333Y892633D01*
X1135625Y892717D01*
X1135833Y892925D01*
X1135958Y893258D01*
X1136000Y893550D01*
G01X1134958Y895858D02*
X1134667Y896150D01*
X1134500Y896400D01*
X1134417Y896733D01*
X1134500Y897025D01*
X1134667Y897233D01*
X1134917Y897400D01*
X1135208Y897442D01*
X1135458Y897400D01*
X1135708Y897233D01*
X1135917Y896983D01*
X1136000Y896692D01*
X1135917Y896358D01*
X1135667Y896067D01*
X1135292Y895900D01*
X1134875Y895858D01*
X1134333Y895942D01*
X1134042Y896067D01*
X1133750Y896275D01*
X1133542Y896567D01*
X1133500Y896858D01*
X1133583Y897150D01*
X1133792Y897358D01*
G01X1159768Y241384D02*
X1140568D01*
Y230184D01*
X1159768D01*
Y241384D01*
X1159368D01*
G01X1146417Y261500D02*
Y264000D01*
X1147417D01*
X1147750Y263875D01*
X1148000Y263583D01*
X1148083Y263250D01*
X1148000Y262917D01*
X1147792Y262667D01*
X1147417Y262542D01*
X1146417D01*
G01X1149517Y261500D02*
Y264000D01*
X1150558D01*
X1150892Y263875D01*
X1151100Y263708D01*
X1151183Y263375D01*
X1151100Y263042D01*
X1150850Y262833D01*
X1150558Y262708D01*
X1149517D01*
G01X1150558D02*
X1151183Y261500D01*
G01X1152742Y261792D02*
X1153033Y261583D01*
X1153367Y261500D01*
X1153700Y261583D01*
X1153992Y261833D01*
X1154200Y262208D01*
X1154283Y262583D01*
Y263042D01*
X1154200Y263417D01*
X1153992Y263750D01*
X1153742Y263917D01*
X1153450Y264000D01*
X1153117Y263917D01*
X1152867Y263750D01*
X1152700Y263500D01*
X1152617Y263167D01*
X1152700Y262875D01*
X1152908Y262583D01*
X1153158Y262417D01*
X1153450Y262375D01*
X1153783Y262458D01*
X1154033Y262667D01*
X1154283Y263042D01*
G01X1156550Y264000D02*
X1156217Y263917D01*
X1155967Y263708D01*
X1155800Y263458D01*
X1155675Y263125D01*
X1155633Y262750D01*
X1155675Y262375D01*
X1155800Y262042D01*
X1155967Y261792D01*
X1156217Y261583D01*
X1156550Y261500D01*
X1156883Y261583D01*
X1157133Y261792D01*
X1157300Y262042D01*
X1157425Y262375D01*
X1157467Y262750D01*
X1157425Y263125D01*
X1157300Y263458D01*
X1157133Y263708D01*
X1156883Y263917D01*
X1156550Y264000D01*
G01X1159650D02*
X1159317Y263917D01*
X1159067Y263708D01*
X1158900Y263458D01*
X1158775Y263125D01*
X1158733Y262750D01*
X1158775Y262375D01*
X1158900Y262042D01*
X1159067Y261792D01*
X1159317Y261583D01*
X1159650Y261500D01*
X1159983Y261583D01*
X1160233Y261792D01*
X1160400Y262042D01*
X1160525Y262375D01*
X1160567Y262750D01*
X1160525Y263125D01*
X1160400Y263458D01*
X1160233Y263708D01*
X1159983Y263917D01*
X1159650Y264000D01*
G01X1162750D02*
X1162417Y263917D01*
X1162167Y263708D01*
X1162000Y263458D01*
X1161875Y263125D01*
X1161833Y262750D01*
X1161875Y262375D01*
X1162000Y262042D01*
X1162167Y261792D01*
X1162417Y261583D01*
X1162750Y261500D01*
X1163083Y261583D01*
X1163333Y261792D01*
X1163500Y262042D01*
X1163625Y262375D01*
X1163667Y262750D01*
X1163625Y263125D01*
X1163500Y263458D01*
X1163333Y263708D01*
X1163083Y263917D01*
X1162750Y264000D01*
G01X1136800Y264500D02*
Y260500D01*
X1144200D01*
G01X1146417Y269500D02*
Y272000D01*
X1147417D01*
X1147750Y271875D01*
X1148000Y271583D01*
X1148083Y271250D01*
X1148000Y270917D01*
X1147792Y270667D01*
X1147417Y270542D01*
X1146417D01*
G01X1149517Y269500D02*
Y272000D01*
X1150558D01*
X1150892Y271875D01*
X1151100Y271708D01*
X1151183Y271375D01*
X1151100Y271042D01*
X1150850Y270833D01*
X1150558Y270708D01*
X1149517D01*
G01X1150558D02*
X1151183Y269500D01*
G01X1152742Y269792D02*
X1153033Y269583D01*
X1153367Y269500D01*
X1153700Y269583D01*
X1153992Y269833D01*
X1154200Y270208D01*
X1154283Y270583D01*
Y271042D01*
X1154200Y271417D01*
X1153992Y271750D01*
X1153742Y271917D01*
X1153450Y272000D01*
X1153117Y271917D01*
X1152867Y271750D01*
X1152700Y271500D01*
X1152617Y271167D01*
X1152700Y270875D01*
X1152908Y270583D01*
X1153158Y270417D01*
X1153450Y270375D01*
X1153783Y270458D01*
X1154033Y270667D01*
X1154283Y271042D01*
G01X1156550Y272000D02*
X1156217Y271917D01*
X1155967Y271708D01*
X1155800Y271458D01*
X1155675Y271125D01*
X1155633Y270750D01*
X1155675Y270375D01*
X1155800Y270042D01*
X1155967Y269792D01*
X1156217Y269583D01*
X1156550Y269500D01*
X1156883Y269583D01*
X1157133Y269792D01*
X1157300Y270042D01*
X1157425Y270375D01*
X1157467Y270750D01*
X1157425Y271125D01*
X1157300Y271458D01*
X1157133Y271708D01*
X1156883Y271917D01*
X1156550Y272000D01*
G01X1159650D02*
X1159317Y271917D01*
X1159067Y271708D01*
X1158900Y271458D01*
X1158775Y271125D01*
X1158733Y270750D01*
X1158775Y270375D01*
X1158900Y270042D01*
X1159067Y269792D01*
X1159317Y269583D01*
X1159650Y269500D01*
X1159983Y269583D01*
X1160233Y269792D01*
X1160400Y270042D01*
X1160525Y270375D01*
X1160567Y270750D01*
X1160525Y271125D01*
X1160400Y271458D01*
X1160233Y271708D01*
X1159983Y271917D01*
X1159650Y272000D01*
G01X1162750Y269500D02*
Y272000D01*
X1162250Y271500D01*
G01Y269500D02*
X1163250D01*
G01X1136800Y272500D02*
Y268500D01*
X1144200D01*
G01X1146417Y257500D02*
Y260000D01*
X1147417D01*
X1147750Y259875D01*
X1148000Y259583D01*
X1148083Y259250D01*
X1148000Y258917D01*
X1147792Y258667D01*
X1147417Y258542D01*
X1146417D01*
G01X1149517Y257500D02*
Y260000D01*
X1150558D01*
X1150892Y259875D01*
X1151100Y259708D01*
X1151183Y259375D01*
X1151100Y259042D01*
X1150850Y258833D01*
X1150558Y258708D01*
X1149517D01*
G01X1150558D02*
X1151183Y257500D01*
G01X1152742Y257792D02*
X1153033Y257583D01*
X1153367Y257500D01*
X1153700Y257583D01*
X1153992Y257833D01*
X1154200Y258208D01*
X1154283Y258583D01*
Y259042D01*
X1154200Y259417D01*
X1153992Y259750D01*
X1153742Y259917D01*
X1153450Y260000D01*
X1153117Y259917D01*
X1152867Y259750D01*
X1152700Y259500D01*
X1152617Y259167D01*
X1152700Y258875D01*
X1152908Y258583D01*
X1153158Y258417D01*
X1153450Y258375D01*
X1153783Y258458D01*
X1154033Y258667D01*
X1154283Y259042D01*
G01X1156550Y260000D02*
X1156217Y259917D01*
X1155967Y259708D01*
X1155800Y259458D01*
X1155675Y259125D01*
X1155633Y258750D01*
X1155675Y258375D01*
X1155800Y258042D01*
X1155967Y257792D01*
X1156217Y257583D01*
X1156550Y257500D01*
X1156883Y257583D01*
X1157133Y257792D01*
X1157300Y258042D01*
X1157425Y258375D01*
X1157467Y258750D01*
X1157425Y259125D01*
X1157300Y259458D01*
X1157133Y259708D01*
X1156883Y259917D01*
X1156550Y260000D01*
G01X1159650D02*
X1159317Y259917D01*
X1159067Y259708D01*
X1158900Y259458D01*
X1158775Y259125D01*
X1158733Y258750D01*
X1158775Y258375D01*
X1158900Y258042D01*
X1159067Y257792D01*
X1159317Y257583D01*
X1159650Y257500D01*
X1159983Y257583D01*
X1160233Y257792D01*
X1160400Y258042D01*
X1160525Y258375D01*
X1160567Y258750D01*
X1160525Y259125D01*
X1160400Y259458D01*
X1160233Y259708D01*
X1159983Y259917D01*
X1159650Y260000D01*
G01X1161958Y259583D02*
X1162208Y259833D01*
X1162500Y259958D01*
X1162833Y260000D01*
X1163250Y259917D01*
X1163542Y259708D01*
X1163625Y259458D01*
X1163583Y259208D01*
X1163417Y259000D01*
X1162583Y258583D01*
X1162208Y258292D01*
X1161958Y257875D01*
X1161875Y257500D01*
X1163625D01*
G01X1136800Y260500D02*
Y256500D01*
X1144200D01*
G01X1146417Y265500D02*
Y268000D01*
X1147417D01*
X1147750Y267875D01*
X1148000Y267583D01*
X1148083Y267250D01*
X1148000Y266917D01*
X1147792Y266667D01*
X1147417Y266542D01*
X1146417D01*
G01X1149517Y265500D02*
Y268000D01*
X1150558D01*
X1150892Y267875D01*
X1151100Y267708D01*
X1151183Y267375D01*
X1151100Y267042D01*
X1150850Y266833D01*
X1150558Y266708D01*
X1149517D01*
G01X1150558D02*
X1151183Y265500D01*
G01X1152742Y265792D02*
X1153033Y265583D01*
X1153367Y265500D01*
X1153700Y265583D01*
X1153992Y265833D01*
X1154200Y266208D01*
X1154283Y266583D01*
Y267042D01*
X1154200Y267417D01*
X1153992Y267750D01*
X1153742Y267917D01*
X1153450Y268000D01*
X1153117Y267917D01*
X1152867Y267750D01*
X1152700Y267500D01*
X1152617Y267167D01*
X1152700Y266875D01*
X1152908Y266583D01*
X1153158Y266417D01*
X1153450Y266375D01*
X1153783Y266458D01*
X1154033Y266667D01*
X1154283Y267042D01*
G01X1156550Y268000D02*
X1156217Y267917D01*
X1155967Y267708D01*
X1155800Y267458D01*
X1155675Y267125D01*
X1155633Y266750D01*
X1155675Y266375D01*
X1155800Y266042D01*
X1155967Y265792D01*
X1156217Y265583D01*
X1156550Y265500D01*
X1156883Y265583D01*
X1157133Y265792D01*
X1157300Y266042D01*
X1157425Y266375D01*
X1157467Y266750D01*
X1157425Y267125D01*
X1157300Y267458D01*
X1157133Y267708D01*
X1156883Y267917D01*
X1156550Y268000D01*
G01X1159650D02*
X1159317Y267917D01*
X1159067Y267708D01*
X1158900Y267458D01*
X1158775Y267125D01*
X1158733Y266750D01*
X1158775Y266375D01*
X1158900Y266042D01*
X1159067Y265792D01*
X1159317Y265583D01*
X1159650Y265500D01*
X1159983Y265583D01*
X1160233Y265792D01*
X1160400Y266042D01*
X1160525Y266375D01*
X1160567Y266750D01*
X1160525Y267125D01*
X1160400Y267458D01*
X1160233Y267708D01*
X1159983Y267917D01*
X1159650Y268000D01*
G01X1161833Y266000D02*
X1162083Y265708D01*
X1162417Y265542D01*
X1162792Y265500D01*
X1163125Y265542D01*
X1163458Y265750D01*
X1163667Y266000D01*
X1163708Y266250D01*
X1163625Y266542D01*
X1163333Y266750D01*
X1163042Y266833D01*
X1162667D01*
G01X1163042D02*
X1163292Y266958D01*
X1163500Y267167D01*
X1163583Y267417D01*
X1163500Y267667D01*
X1163292Y267875D01*
X1162917Y268000D01*
X1162542Y267958D01*
X1162167Y267792D01*
G01X1136800Y268500D02*
Y264500D01*
X1144200D01*
G01X1146485Y285784D02*
Y288284D01*
X1147526D01*
X1147860Y288159D01*
X1148068Y287992D01*
X1148151Y287659D01*
X1148068Y287326D01*
X1147818Y287117D01*
X1147526Y286992D01*
X1146485D01*
G01X1147526D02*
X1148151Y285784D01*
G01X1149501Y286159D02*
X1149751Y285951D01*
X1150043Y285826D01*
X1150418Y285784D01*
X1150793Y285867D01*
X1151085Y286034D01*
X1151293Y286326D01*
X1151335Y286659D01*
X1151251Y286992D01*
X1151043Y287201D01*
X1150751Y287367D01*
X1150460Y287409D01*
X1150168Y287367D01*
X1149793Y287201D01*
X1149918Y288284D01*
X1151043D01*
G01X1152726Y287867D02*
X1152976Y288117D01*
X1153268Y288242D01*
X1153601Y288284D01*
X1154018Y288201D01*
X1154310Y287992D01*
X1154393Y287742D01*
X1154351Y287492D01*
X1154185Y287284D01*
X1153351Y286867D01*
X1152976Y286576D01*
X1152726Y286159D01*
X1152643Y285784D01*
X1154393D01*
G01X1155826Y287867D02*
X1156076Y288117D01*
X1156368Y288242D01*
X1156701Y288284D01*
X1157118Y288201D01*
X1157410Y287992D01*
X1157493Y287742D01*
X1157451Y287492D01*
X1157285Y287284D01*
X1156451Y286867D01*
X1156076Y286576D01*
X1155826Y286159D01*
X1155743Y285784D01*
X1157493D01*
G01X1136768Y288284D02*
Y284284D01*
X1144168D01*
G01X1146417Y273500D02*
Y276000D01*
X1147417D01*
X1147750Y275875D01*
X1148000Y275583D01*
X1148083Y275250D01*
X1148000Y274917D01*
X1147792Y274667D01*
X1147417Y274542D01*
X1146417D01*
G01X1149517Y273500D02*
Y276000D01*
X1150558D01*
X1150892Y275875D01*
X1151100Y275708D01*
X1151183Y275375D01*
X1151100Y275042D01*
X1150850Y274833D01*
X1150558Y274708D01*
X1149517D01*
G01X1150558D02*
X1151183Y273500D01*
G01X1152658Y274542D02*
X1152950Y274833D01*
X1153200Y275000D01*
X1153533Y275083D01*
X1153825Y275000D01*
X1154033Y274833D01*
X1154200Y274583D01*
X1154242Y274292D01*
X1154200Y274042D01*
X1154033Y273792D01*
X1153783Y273583D01*
X1153492Y273500D01*
X1153158Y273583D01*
X1152867Y273833D01*
X1152700Y274208D01*
X1152658Y274625D01*
X1152742Y275167D01*
X1152867Y275458D01*
X1153075Y275750D01*
X1153367Y275958D01*
X1153658Y276000D01*
X1153950Y275917D01*
X1154158Y275708D01*
G01X1156550Y273500D02*
X1156842Y273542D01*
X1157175Y273667D01*
X1157383Y273875D01*
X1157467Y274167D01*
X1157383Y274458D01*
X1157133Y274708D01*
X1156758Y274833D01*
X1156342D01*
X1156092Y274917D01*
X1155883Y275125D01*
X1155800Y275417D01*
X1155925Y275708D01*
X1156217Y275917D01*
X1156550Y276000D01*
X1156883Y275917D01*
X1157175Y275708D01*
X1157300Y275417D01*
X1157217Y275125D01*
X1157008Y274917D01*
X1156758Y274833D01*
X1156342D01*
X1155967Y274708D01*
X1155717Y274458D01*
X1155633Y274167D01*
X1155717Y273875D01*
X1155925Y273667D01*
X1156258Y273542D01*
X1156550Y273500D01*
G01X1159650D02*
X1159942Y273542D01*
X1160275Y273667D01*
X1160483Y273875D01*
X1160567Y274167D01*
X1160483Y274458D01*
X1160233Y274708D01*
X1159858Y274833D01*
X1159442D01*
X1159192Y274917D01*
X1158983Y275125D01*
X1158900Y275417D01*
X1159025Y275708D01*
X1159317Y275917D01*
X1159650Y276000D01*
X1159983Y275917D01*
X1160275Y275708D01*
X1160400Y275417D01*
X1160317Y275125D01*
X1160108Y274917D01*
X1159858Y274833D01*
X1159442D01*
X1159067Y274708D01*
X1158817Y274458D01*
X1158733Y274167D01*
X1158817Y273875D01*
X1159025Y273667D01*
X1159358Y273542D01*
X1159650Y273500D01*
G01X1162750D02*
X1163042Y273542D01*
X1163375Y273667D01*
X1163583Y273875D01*
X1163667Y274167D01*
X1163583Y274458D01*
X1163333Y274708D01*
X1162958Y274833D01*
X1162542D01*
X1162292Y274917D01*
X1162083Y275125D01*
X1162000Y275417D01*
X1162125Y275708D01*
X1162417Y275917D01*
X1162750Y276000D01*
X1163083Y275917D01*
X1163375Y275708D01*
X1163500Y275417D01*
X1163417Y275125D01*
X1163208Y274917D01*
X1162958Y274833D01*
X1162542D01*
X1162167Y274708D01*
X1161917Y274458D01*
X1161833Y274167D01*
X1161917Y273875D01*
X1162125Y273667D01*
X1162458Y273542D01*
X1162750Y273500D01*
G01X1144200Y272500D02*
Y276500D01*
X1136800D01*
G01X1146417Y277500D02*
Y280000D01*
X1147417D01*
X1147750Y279875D01*
X1148000Y279583D01*
X1148083Y279250D01*
X1148000Y278917D01*
X1147792Y278667D01*
X1147417Y278542D01*
X1146417D01*
G01X1149517Y277500D02*
Y280000D01*
X1150558D01*
X1150892Y279875D01*
X1151100Y279708D01*
X1151183Y279375D01*
X1151100Y279042D01*
X1150850Y278833D01*
X1150558Y278708D01*
X1149517D01*
G01X1150558D02*
X1151183Y277500D01*
G01X1152658Y278542D02*
X1152950Y278833D01*
X1153200Y279000D01*
X1153533Y279083D01*
X1153825Y279000D01*
X1154033Y278833D01*
X1154200Y278583D01*
X1154242Y278292D01*
X1154200Y278042D01*
X1154033Y277792D01*
X1153783Y277583D01*
X1153492Y277500D01*
X1153158Y277583D01*
X1152867Y277833D01*
X1152700Y278208D01*
X1152658Y278625D01*
X1152742Y279167D01*
X1152867Y279458D01*
X1153075Y279750D01*
X1153367Y279958D01*
X1153658Y280000D01*
X1153950Y279917D01*
X1154158Y279708D01*
G01X1156550Y277500D02*
X1156842Y277542D01*
X1157175Y277667D01*
X1157383Y277875D01*
X1157467Y278167D01*
X1157383Y278458D01*
X1157133Y278708D01*
X1156758Y278833D01*
X1156342D01*
X1156092Y278917D01*
X1155883Y279125D01*
X1155800Y279417D01*
X1155925Y279708D01*
X1156217Y279917D01*
X1156550Y280000D01*
X1156883Y279917D01*
X1157175Y279708D01*
X1157300Y279417D01*
X1157217Y279125D01*
X1157008Y278917D01*
X1156758Y278833D01*
X1156342D01*
X1155967Y278708D01*
X1155717Y278458D01*
X1155633Y278167D01*
X1155717Y277875D01*
X1155925Y277667D01*
X1156258Y277542D01*
X1156550Y277500D01*
G01X1159650D02*
X1159942Y277542D01*
X1160275Y277667D01*
X1160483Y277875D01*
X1160567Y278167D01*
X1160483Y278458D01*
X1160233Y278708D01*
X1159858Y278833D01*
X1159442D01*
X1159192Y278917D01*
X1158983Y279125D01*
X1158900Y279417D01*
X1159025Y279708D01*
X1159317Y279917D01*
X1159650Y280000D01*
X1159983Y279917D01*
X1160275Y279708D01*
X1160400Y279417D01*
X1160317Y279125D01*
X1160108Y278917D01*
X1159858Y278833D01*
X1159442D01*
X1159067Y278708D01*
X1158817Y278458D01*
X1158733Y278167D01*
X1158817Y277875D01*
X1159025Y277667D01*
X1159358Y277542D01*
X1159650Y277500D01*
G01X1162042Y277792D02*
X1162333Y277583D01*
X1162667Y277500D01*
X1163000Y277583D01*
X1163292Y277833D01*
X1163500Y278208D01*
X1163583Y278583D01*
Y279042D01*
X1163500Y279417D01*
X1163292Y279750D01*
X1163042Y279917D01*
X1162750Y280000D01*
X1162417Y279917D01*
X1162167Y279750D01*
X1162000Y279500D01*
X1161917Y279167D01*
X1162000Y278875D01*
X1162208Y278583D01*
X1162458Y278417D01*
X1162750Y278375D01*
X1163083Y278458D01*
X1163333Y278667D01*
X1163583Y279042D01*
G01X1136800Y280500D02*
Y276500D01*
X1144200D01*
G01X1148235Y284076D02*
X1147985Y284201D01*
X1147693Y284284D01*
X1147360D01*
X1146985Y284159D01*
X1146693Y283951D01*
X1146485Y283701D01*
X1146318Y283284D01*
X1146276Y282909D01*
X1146360Y282534D01*
X1146485Y282284D01*
X1146735Y282034D01*
X1147026Y281867D01*
X1147318Y281784D01*
X1147610D01*
X1147901Y281867D01*
X1148151Y281992D01*
X1148360Y282159D01*
G01X1149626Y283867D02*
X1149876Y284117D01*
X1150168Y284242D01*
X1150501Y284284D01*
X1150918Y284201D01*
X1151210Y283992D01*
X1151293Y283742D01*
X1151251Y283492D01*
X1151085Y283284D01*
X1150251Y282867D01*
X1149876Y282576D01*
X1149626Y282159D01*
X1149543Y281784D01*
X1151293D01*
G01X1152726Y282826D02*
X1153018Y283117D01*
X1153268Y283284D01*
X1153601Y283367D01*
X1153893Y283284D01*
X1154101Y283117D01*
X1154268Y282867D01*
X1154310Y282576D01*
X1154268Y282326D01*
X1154101Y282076D01*
X1153851Y281867D01*
X1153560Y281784D01*
X1153226Y281867D01*
X1152935Y282117D01*
X1152768Y282492D01*
X1152726Y282909D01*
X1152810Y283451D01*
X1152935Y283742D01*
X1153143Y284034D01*
X1153435Y284242D01*
X1153726Y284284D01*
X1154018Y284201D01*
X1154226Y283992D01*
G01X1155826Y282826D02*
X1156118Y283117D01*
X1156368Y283284D01*
X1156701Y283367D01*
X1156993Y283284D01*
X1157201Y283117D01*
X1157368Y282867D01*
X1157410Y282576D01*
X1157368Y282326D01*
X1157201Y282076D01*
X1156951Y281867D01*
X1156660Y281784D01*
X1156326Y281867D01*
X1156035Y282117D01*
X1155868Y282492D01*
X1155826Y282909D01*
X1155910Y283451D01*
X1156035Y283742D01*
X1156243Y284034D01*
X1156535Y284242D01*
X1156826Y284284D01*
X1157118Y284201D01*
X1157326Y283992D01*
G01X1135017Y581000D02*
Y583500D01*
X1136058D01*
X1136392Y583375D01*
X1136600Y583208D01*
X1136683Y582875D01*
X1136600Y582542D01*
X1136350Y582333D01*
X1136058Y582208D01*
X1135017D01*
G01X1136058D02*
X1136683Y581000D01*
G01X1138033Y581500D02*
X1138283Y581208D01*
X1138617Y581042D01*
X1138992Y581000D01*
X1139325Y581042D01*
X1139658Y581250D01*
X1139867Y581500D01*
X1139908Y581750D01*
X1139825Y582042D01*
X1139533Y582250D01*
X1139242Y582333D01*
X1138867D01*
G01X1139242D02*
X1139492Y582458D01*
X1139700Y582667D01*
X1139783Y582917D01*
X1139700Y583167D01*
X1139492Y583375D01*
X1139117Y583500D01*
X1138742Y583458D01*
X1138367Y583292D01*
G01X1141342Y581292D02*
X1141633Y581083D01*
X1141967Y581000D01*
X1142300Y581083D01*
X1142592Y581333D01*
X1142800Y581708D01*
X1142883Y582083D01*
Y582542D01*
X1142800Y582917D01*
X1142592Y583250D01*
X1142342Y583417D01*
X1142050Y583500D01*
X1141717Y583417D01*
X1141467Y583250D01*
X1141300Y583000D01*
X1141217Y582667D01*
X1141300Y582375D01*
X1141508Y582083D01*
X1141758Y581917D01*
X1142050Y581875D01*
X1142383Y581958D01*
X1142633Y582167D01*
X1142883Y582542D01*
G01X1144442Y581292D02*
X1144733Y581083D01*
X1145067Y581000D01*
X1145400Y581083D01*
X1145692Y581333D01*
X1145900Y581708D01*
X1145983Y582083D01*
Y582542D01*
X1145900Y582917D01*
X1145692Y583250D01*
X1145442Y583417D01*
X1145150Y583500D01*
X1144817Y583417D01*
X1144567Y583250D01*
X1144400Y583000D01*
X1144317Y582667D01*
X1144400Y582375D01*
X1144608Y582083D01*
X1144858Y581917D01*
X1145150Y581875D01*
X1145483Y581958D01*
X1145733Y582167D01*
X1145983Y582542D01*
G01X1151934Y586872D02*
X1147934D01*
Y579472D01*
G01X1144300Y599000D02*
Y595000D01*
X1151700D01*
G01X1136767Y587792D02*
X1136517Y587917D01*
X1136225Y588000D01*
X1135892D01*
X1135517Y587875D01*
X1135225Y587667D01*
X1135017Y587417D01*
X1134850Y587000D01*
X1134808Y586625D01*
X1134892Y586250D01*
X1135017Y586000D01*
X1135267Y585750D01*
X1135558Y585583D01*
X1135850Y585500D01*
X1136142D01*
X1136433Y585583D01*
X1136683Y585708D01*
X1136892Y585875D01*
G01X1138158Y587583D02*
X1138408Y587833D01*
X1138700Y587958D01*
X1139033Y588000D01*
X1139450Y587917D01*
X1139742Y587708D01*
X1139825Y587458D01*
X1139783Y587208D01*
X1139617Y587000D01*
X1138783Y586583D01*
X1138408Y586292D01*
X1138158Y585875D01*
X1138075Y585500D01*
X1139825D01*
G01X1141133Y586000D02*
X1141383Y585708D01*
X1141717Y585542D01*
X1142092Y585500D01*
X1142425Y585542D01*
X1142758Y585750D01*
X1142967Y586000D01*
X1143008Y586250D01*
X1142925Y586542D01*
X1142633Y586750D01*
X1142342Y586833D01*
X1141967D01*
G01X1142342D02*
X1142592Y586958D01*
X1142800Y587167D01*
X1142883Y587417D01*
X1142800Y587667D01*
X1142592Y587875D01*
X1142217Y588000D01*
X1141842Y587958D01*
X1141467Y587792D01*
G01X1144233Y586000D02*
X1144483Y585708D01*
X1144817Y585542D01*
X1145192Y585500D01*
X1145525Y585542D01*
X1145858Y585750D01*
X1146067Y586000D01*
X1146108Y586250D01*
X1146025Y586542D01*
X1145733Y586750D01*
X1145442Y586833D01*
X1145067D01*
G01X1145442D02*
X1145692Y586958D01*
X1145900Y587167D01*
X1145983Y587417D01*
X1145900Y587667D01*
X1145692Y587875D01*
X1145317Y588000D01*
X1144942Y587958D01*
X1144567Y587792D01*
G01X1146483Y611000D02*
Y609208D01*
X1146650Y608833D01*
X1146983Y608583D01*
X1147400Y608500D01*
X1147817Y608583D01*
X1148150Y608833D01*
X1148317Y609208D01*
Y611000D01*
G01X1149708Y610583D02*
X1149958Y610833D01*
X1150250Y610958D01*
X1150583Y611000D01*
X1151000Y610917D01*
X1151292Y610708D01*
X1151375Y610458D01*
X1151333Y610208D01*
X1151167Y610000D01*
X1150333Y609583D01*
X1149958Y609292D01*
X1149708Y608875D01*
X1149625Y608500D01*
X1151375D01*
G01X1153600D02*
Y611000D01*
X1153100Y610500D01*
G01Y608500D02*
X1154100D01*
G01X1139500Y627700D02*
X1135500D01*
Y620300D01*
G01X1153500Y632200D02*
X1149500D01*
Y624800D01*
G01Y617300D02*
X1153500D01*
Y624700D01*
G01X1135000Y629300D02*
X1139000D01*
Y636700D01*
G01X1143200Y616000D02*
Y620000D01*
X1135800D01*
G01X1140000Y620300D02*
X1144000D01*
Y627700D01*
G01X1148500D02*
X1144500D01*
Y620300D01*
G01X1148000Y639700D02*
X1144000D01*
Y632300D01*
G01X1153500Y639700D02*
X1149500D01*
Y632300D01*
G01X1145500Y739017D02*
X1143000D01*
Y740058D01*
X1143125Y740392D01*
X1143292Y740600D01*
X1143625Y740683D01*
X1143958Y740600D01*
X1144167Y740350D01*
X1144292Y740058D01*
Y739017D01*
G01Y740058D02*
X1145500Y740683D01*
G01X1143417Y742158D02*
X1143167Y742408D01*
X1143042Y742700D01*
X1143000Y743033D01*
X1143083Y743450D01*
X1143292Y743742D01*
X1143542Y743825D01*
X1143792Y743783D01*
X1144000Y743617D01*
X1144417Y742783D01*
X1144708Y742408D01*
X1145125Y742158D01*
X1145500Y742075D01*
Y743825D01*
G01X1143417Y745258D02*
X1143167Y745508D01*
X1143042Y745800D01*
X1143000Y746133D01*
X1143083Y746550D01*
X1143292Y746842D01*
X1143542Y746925D01*
X1143792Y746883D01*
X1144000Y746717D01*
X1144417Y745883D01*
X1144708Y745508D01*
X1145125Y745258D01*
X1145500Y745175D01*
Y746925D01*
G01X1145208Y748442D02*
X1145417Y748733D01*
X1145500Y749067D01*
X1145417Y749400D01*
X1145167Y749692D01*
X1144792Y749900D01*
X1144417Y749983D01*
X1143958D01*
X1143583Y749900D01*
X1143250Y749692D01*
X1143083Y749442D01*
X1143000Y749150D01*
X1143083Y748817D01*
X1143250Y748567D01*
X1143500Y748400D01*
X1143833Y748317D01*
X1144125Y748400D01*
X1144417Y748608D01*
X1144583Y748858D01*
X1144625Y749150D01*
X1144542Y749483D01*
X1144333Y749733D01*
X1143958Y749983D01*
G01X1149466Y741461D02*
X1149341Y741211D01*
X1149258Y740919D01*
Y740586D01*
X1149383Y740211D01*
X1149591Y739919D01*
X1149841Y739711D01*
X1150258Y739544D01*
X1150633Y739502D01*
X1151008Y739586D01*
X1151258Y739711D01*
X1151508Y739961D01*
X1151675Y740252D01*
X1151758Y740544D01*
Y740836D01*
X1151675Y741127D01*
X1151550Y741377D01*
X1151383Y741586D01*
G01X1151758Y743644D02*
X1149258D01*
X1149758Y743144D01*
G01X1151758D02*
Y744144D01*
G01Y746661D02*
X1151216Y746744D01*
X1150758Y746869D01*
X1150341Y747036D01*
X1149883Y747244D01*
X1149258Y747577D01*
Y745911D01*
G01X1151383Y748927D02*
X1151591Y749177D01*
X1151716Y749469D01*
X1151758Y749844D01*
X1151675Y750219D01*
X1151508Y750511D01*
X1151216Y750719D01*
X1150883Y750761D01*
X1150550Y750677D01*
X1150341Y750469D01*
X1150175Y750177D01*
X1150133Y749886D01*
X1150175Y749594D01*
X1150341Y749219D01*
X1149258Y749344D01*
Y750469D01*
G01X1134708Y740767D02*
X1134583Y740517D01*
X1134500Y740225D01*
Y739892D01*
X1134625Y739517D01*
X1134833Y739225D01*
X1135083Y739017D01*
X1135500Y738850D01*
X1135875Y738808D01*
X1136250Y738892D01*
X1136500Y739017D01*
X1136750Y739267D01*
X1136917Y739558D01*
X1137000Y739850D01*
Y740142D01*
X1136917Y740433D01*
X1136792Y740683D01*
X1136625Y740892D01*
G01X1137000Y742950D02*
X1134500D01*
X1135000Y742450D01*
G01X1137000D02*
Y743450D01*
G01Y746050D02*
X1136958Y746342D01*
X1136833Y746675D01*
X1136625Y746883D01*
X1136333Y746967D01*
X1136042Y746883D01*
X1135792Y746633D01*
X1135667Y746258D01*
Y745842D01*
X1135583Y745592D01*
X1135375Y745383D01*
X1135083Y745300D01*
X1134792Y745425D01*
X1134583Y745717D01*
X1134500Y746050D01*
X1134583Y746383D01*
X1134792Y746675D01*
X1135083Y746800D01*
X1135375Y746717D01*
X1135583Y746508D01*
X1135667Y746258D01*
Y745842D01*
X1135792Y745467D01*
X1136042Y745217D01*
X1136333Y745133D01*
X1136625Y745217D01*
X1136833Y745425D01*
X1136958Y745758D01*
X1137000Y746050D01*
G01Y749650D02*
X1134500D01*
X1136292Y748108D01*
Y750192D01*
G01X1141218Y751664D02*
X1145218D01*
Y759064D01*
G01X1136300Y829000D02*
Y825000D01*
X1143700D01*
G01X1145800Y820000D02*
Y816000D01*
X1153200D01*
G01X1138017Y835500D02*
Y838000D01*
X1139058D01*
X1139392Y837875D01*
X1139600Y837708D01*
X1139683Y837375D01*
X1139600Y837042D01*
X1139350Y836833D01*
X1139058Y836708D01*
X1138017D01*
G01X1139058D02*
X1139683Y835500D01*
G01X1141158Y837583D02*
X1141408Y837833D01*
X1141700Y837958D01*
X1142033Y838000D01*
X1142450Y837917D01*
X1142742Y837708D01*
X1142825Y837458D01*
X1142783Y837208D01*
X1142617Y837000D01*
X1141783Y836583D01*
X1141408Y836292D01*
X1141158Y835875D01*
X1141075Y835500D01*
X1142825D01*
G01X1144133Y836000D02*
X1144383Y835708D01*
X1144717Y835542D01*
X1145092Y835500D01*
X1145425Y835542D01*
X1145758Y835750D01*
X1145967Y836000D01*
X1146008Y836250D01*
X1145925Y836542D01*
X1145633Y836750D01*
X1145342Y836833D01*
X1144967D01*
G01X1145342D02*
X1145592Y836958D01*
X1145800Y837167D01*
X1145883Y837417D01*
X1145800Y837667D01*
X1145592Y837875D01*
X1145217Y838000D01*
X1144842Y837958D01*
X1144467Y837792D01*
G01X1148150Y835500D02*
Y838000D01*
X1147650Y837500D01*
G01Y835500D02*
X1148650D01*
G01X1139767Y833292D02*
X1139517Y833417D01*
X1139225Y833500D01*
X1138892D01*
X1138517Y833375D01*
X1138225Y833167D01*
X1138017Y832917D01*
X1137850Y832500D01*
X1137808Y832125D01*
X1137892Y831750D01*
X1138017Y831500D01*
X1138267Y831250D01*
X1138558Y831083D01*
X1138850Y831000D01*
X1139142D01*
X1139433Y831083D01*
X1139683Y831208D01*
X1139892Y831375D01*
G01X1141950Y831000D02*
Y833500D01*
X1141450Y833000D01*
G01Y831000D02*
X1142450D01*
G01X1144967D02*
X1145050Y831542D01*
X1145175Y832000D01*
X1145342Y832417D01*
X1145550Y832875D01*
X1145883Y833500D01*
X1144217D01*
G01X1148067Y831000D02*
X1148150Y831542D01*
X1148275Y832000D01*
X1148442Y832417D01*
X1148650Y832875D01*
X1148983Y833500D01*
X1147317D01*
G01X1148517Y854500D02*
Y857000D01*
X1149517D01*
X1149850Y856875D01*
X1150100Y856583D01*
X1150183Y856250D01*
X1150100Y855917D01*
X1149892Y855667D01*
X1149517Y855542D01*
X1148517D01*
G01X1151617Y854500D02*
Y857000D01*
X1152658D01*
X1152992Y856875D01*
X1153200Y856708D01*
X1153283Y856375D01*
X1153200Y856042D01*
X1152950Y855833D01*
X1152658Y855708D01*
X1151617D01*
G01X1152658D02*
X1153283Y854500D01*
G01X1155467D02*
X1155550Y855042D01*
X1155675Y855500D01*
X1155842Y855917D01*
X1156050Y856375D01*
X1156383Y857000D01*
X1154717D01*
G01X1157942Y854792D02*
X1158233Y854583D01*
X1158567Y854500D01*
X1158900Y854583D01*
X1159192Y854833D01*
X1159400Y855208D01*
X1159483Y855583D01*
Y856042D01*
X1159400Y856417D01*
X1159192Y856750D01*
X1158942Y856917D01*
X1158650Y857000D01*
X1158317Y856917D01*
X1158067Y856750D01*
X1157900Y856500D01*
X1157817Y856167D01*
X1157900Y855875D01*
X1158108Y855583D01*
X1158358Y855417D01*
X1158650Y855375D01*
X1158983Y855458D01*
X1159233Y855667D01*
X1159483Y856042D01*
G01X1145168Y856284D02*
Y860284D01*
X1137768D01*
G01X1148517Y859000D02*
Y861500D01*
X1149517D01*
X1149850Y861375D01*
X1150100Y861083D01*
X1150183Y860750D01*
X1150100Y860417D01*
X1149892Y860167D01*
X1149517Y860042D01*
X1148517D01*
G01X1153367Y861292D02*
X1153117Y861417D01*
X1152825Y861500D01*
X1152492D01*
X1152117Y861375D01*
X1151825Y861167D01*
X1151617Y860917D01*
X1151450Y860500D01*
X1151408Y860125D01*
X1151492Y859750D01*
X1151617Y859500D01*
X1151867Y859250D01*
X1152158Y859083D01*
X1152450Y859000D01*
X1152742D01*
X1153033Y859083D01*
X1153283Y859208D01*
X1153492Y859375D01*
G01X1155550Y859000D02*
X1155842Y859042D01*
X1156175Y859167D01*
X1156383Y859375D01*
X1156467Y859667D01*
X1156383Y859958D01*
X1156133Y860208D01*
X1155758Y860333D01*
X1155342D01*
X1155092Y860417D01*
X1154883Y860625D01*
X1154800Y860917D01*
X1154925Y861208D01*
X1155217Y861417D01*
X1155550Y861500D01*
X1155883Y861417D01*
X1156175Y861208D01*
X1156300Y860917D01*
X1156217Y860625D01*
X1156008Y860417D01*
X1155758Y860333D01*
X1155342D01*
X1154967Y860208D01*
X1154717Y859958D01*
X1154633Y859667D01*
X1154717Y859375D01*
X1154925Y859167D01*
X1155258Y859042D01*
X1155550Y859000D01*
G01X1158650D02*
Y861500D01*
X1158150Y861000D01*
G01Y859000D02*
X1159150D01*
G01X1142968Y889301D02*
X1140468D01*
Y890301D01*
X1140593Y890634D01*
X1140885Y890884D01*
X1141218Y890967D01*
X1141551Y890884D01*
X1141801Y890676D01*
X1141926Y890301D01*
Y889301D01*
G01X1140676Y894151D02*
X1140551Y893901D01*
X1140468Y893609D01*
Y893276D01*
X1140593Y892901D01*
X1140801Y892609D01*
X1141051Y892401D01*
X1141468Y892234D01*
X1141843Y892192D01*
X1142218Y892276D01*
X1142468Y892401D01*
X1142718Y892651D01*
X1142885Y892942D01*
X1142968Y893234D01*
Y893526D01*
X1142885Y893817D01*
X1142760Y894067D01*
X1142593Y894276D01*
G01X1142968Y896334D02*
X1142926Y896626D01*
X1142801Y896959D01*
X1142593Y897167D01*
X1142301Y897251D01*
X1142010Y897167D01*
X1141760Y896917D01*
X1141635Y896542D01*
Y896126D01*
X1141551Y895876D01*
X1141343Y895667D01*
X1141051Y895584D01*
X1140760Y895709D01*
X1140551Y896001D01*
X1140468Y896334D01*
X1140551Y896667D01*
X1140760Y896959D01*
X1141051Y897084D01*
X1141343Y897001D01*
X1141551Y896792D01*
X1141635Y896542D01*
Y896126D01*
X1141760Y895751D01*
X1142010Y895501D01*
X1142301Y895417D01*
X1142593Y895501D01*
X1142801Y895709D01*
X1142926Y896042D01*
X1142968Y896334D01*
G01X1140885Y898642D02*
X1140635Y898892D01*
X1140510Y899184D01*
X1140468Y899517D01*
X1140551Y899934D01*
X1140760Y900226D01*
X1141010Y900309D01*
X1141260Y900267D01*
X1141468Y900101D01*
X1141885Y899267D01*
X1142176Y898892D01*
X1142593Y898642D01*
X1142968Y898559D01*
Y900309D01*
G01X1150968Y889301D02*
X1148468D01*
Y890301D01*
X1148593Y890634D01*
X1148885Y890884D01*
X1149218Y890967D01*
X1149551Y890884D01*
X1149801Y890676D01*
X1149926Y890301D01*
Y889301D01*
G01X1148676Y894151D02*
X1148551Y893901D01*
X1148468Y893609D01*
Y893276D01*
X1148593Y892901D01*
X1148801Y892609D01*
X1149051Y892401D01*
X1149468Y892234D01*
X1149843Y892192D01*
X1150218Y892276D01*
X1150468Y892401D01*
X1150718Y892651D01*
X1150885Y892942D01*
X1150968Y893234D01*
Y893526D01*
X1150885Y893817D01*
X1150760Y894067D01*
X1150593Y894276D01*
G01X1150968Y896334D02*
X1150926Y896626D01*
X1150801Y896959D01*
X1150593Y897167D01*
X1150301Y897251D01*
X1150010Y897167D01*
X1149760Y896917D01*
X1149635Y896542D01*
Y896126D01*
X1149551Y895876D01*
X1149343Y895667D01*
X1149051Y895584D01*
X1148760Y895709D01*
X1148551Y896001D01*
X1148468Y896334D01*
X1148551Y896667D01*
X1148760Y896959D01*
X1149051Y897084D01*
X1149343Y897001D01*
X1149551Y896792D01*
X1149635Y896542D01*
Y896126D01*
X1149760Y895751D01*
X1150010Y895501D01*
X1150301Y895417D01*
X1150593Y895501D01*
X1150801Y895709D01*
X1150926Y896042D01*
X1150968Y896334D01*
G01X1150468Y898517D02*
X1150760Y898767D01*
X1150926Y899101D01*
X1150968Y899476D01*
X1150926Y899809D01*
X1150718Y900142D01*
X1150468Y900351D01*
X1150218Y900392D01*
X1149926Y900309D01*
X1149718Y900017D01*
X1149635Y899726D01*
Y899351D01*
G01Y899726D02*
X1149510Y899976D01*
X1149301Y900184D01*
X1149051Y900267D01*
X1148801Y900184D01*
X1148593Y899976D01*
X1148468Y899601D01*
X1148510Y899226D01*
X1148676Y898851D01*
G01X1159668Y233784D02*
X1157568Y235584D01*
X1159668Y237784D01*
G01X1165017Y237000D02*
Y239500D01*
X1166058D01*
X1166392Y239375D01*
X1166600Y239208D01*
X1166683Y238875D01*
X1166600Y238542D01*
X1166350Y238333D01*
X1166058Y238208D01*
X1165017D01*
G01X1166058D02*
X1166683Y237000D01*
G01X1168158Y239083D02*
X1168408Y239333D01*
X1168700Y239458D01*
X1169033Y239500D01*
X1169450Y239417D01*
X1169742Y239208D01*
X1169825Y238958D01*
X1169783Y238708D01*
X1169617Y238500D01*
X1168783Y238083D01*
X1168408Y237792D01*
X1168158Y237375D01*
X1168075Y237000D01*
X1169825D01*
G01X1172050Y239500D02*
X1171717Y239417D01*
X1171467Y239208D01*
X1171300Y238958D01*
X1171175Y238625D01*
X1171133Y238250D01*
X1171175Y237875D01*
X1171300Y237542D01*
X1171467Y237292D01*
X1171717Y237083D01*
X1172050Y237000D01*
X1172383Y237083D01*
X1172633Y237292D01*
X1172800Y237542D01*
X1172925Y237875D01*
X1172967Y238250D01*
X1172925Y238625D01*
X1172800Y238958D01*
X1172633Y239208D01*
X1172383Y239417D01*
X1172050Y239500D01*
G01X1174442Y237292D02*
X1174733Y237083D01*
X1175067Y237000D01*
X1175400Y237083D01*
X1175692Y237333D01*
X1175900Y237708D01*
X1175983Y238083D01*
Y238542D01*
X1175900Y238917D01*
X1175692Y239250D01*
X1175442Y239417D01*
X1175150Y239500D01*
X1174817Y239417D01*
X1174567Y239250D01*
X1174400Y239000D01*
X1174317Y238667D01*
X1174400Y238375D01*
X1174608Y238083D01*
X1174858Y237917D01*
X1175150Y237875D01*
X1175483Y237958D01*
X1175733Y238167D01*
X1175983Y238542D01*
G01X1161385Y225767D02*
X1161260Y225517D01*
X1161177Y225225D01*
Y224892D01*
X1161302Y224517D01*
X1161510Y224225D01*
X1161760Y224017D01*
X1162177Y223850D01*
X1162552Y223808D01*
X1162927Y223892D01*
X1163177Y224017D01*
X1163427Y224267D01*
X1163594Y224558D01*
X1163677Y224850D01*
Y225142D01*
X1163594Y225433D01*
X1163469Y225683D01*
X1163302Y225892D01*
G01X1161594Y227158D02*
X1161344Y227408D01*
X1161219Y227700D01*
X1161177Y228033D01*
X1161260Y228450D01*
X1161469Y228742D01*
X1161719Y228825D01*
X1161969Y228783D01*
X1162177Y228617D01*
X1162594Y227783D01*
X1162885Y227408D01*
X1163302Y227158D01*
X1163677Y227075D01*
Y228825D01*
G01Y231050D02*
X1163635Y231342D01*
X1163510Y231675D01*
X1163302Y231883D01*
X1163010Y231967D01*
X1162719Y231883D01*
X1162469Y231633D01*
X1162344Y231258D01*
Y230842D01*
X1162260Y230592D01*
X1162052Y230383D01*
X1161760Y230300D01*
X1161469Y230425D01*
X1161260Y230717D01*
X1161177Y231050D01*
X1161260Y231383D01*
X1161469Y231675D01*
X1161760Y231800D01*
X1162052Y231717D01*
X1162260Y231508D01*
X1162344Y231258D01*
Y230842D01*
X1162469Y230467D01*
X1162719Y230217D01*
X1163010Y230133D01*
X1163302Y230217D01*
X1163510Y230425D01*
X1163635Y230758D01*
X1163677Y231050D01*
G01Y234650D02*
X1161177D01*
X1162969Y233108D01*
Y235192D01*
G01X1165385Y225767D02*
X1165260Y225517D01*
X1165177Y225225D01*
Y224892D01*
X1165302Y224517D01*
X1165510Y224225D01*
X1165760Y224017D01*
X1166177Y223850D01*
X1166552Y223808D01*
X1166927Y223892D01*
X1167177Y224017D01*
X1167427Y224267D01*
X1167594Y224558D01*
X1167677Y224850D01*
Y225142D01*
X1167594Y225433D01*
X1167469Y225683D01*
X1167302Y225892D01*
G01X1165594Y227158D02*
X1165344Y227408D01*
X1165219Y227700D01*
X1165177Y228033D01*
X1165260Y228450D01*
X1165469Y228742D01*
X1165719Y228825D01*
X1165969Y228783D01*
X1166177Y228617D01*
X1166594Y227783D01*
X1166885Y227408D01*
X1167302Y227158D01*
X1167677Y227075D01*
Y228825D01*
G01Y231050D02*
X1167635Y231342D01*
X1167510Y231675D01*
X1167302Y231883D01*
X1167010Y231967D01*
X1166719Y231883D01*
X1166469Y231633D01*
X1166344Y231258D01*
Y230842D01*
X1166260Y230592D01*
X1166052Y230383D01*
X1165760Y230300D01*
X1165469Y230425D01*
X1165260Y230717D01*
X1165177Y231050D01*
X1165260Y231383D01*
X1165469Y231675D01*
X1165760Y231800D01*
X1166052Y231717D01*
X1166260Y231508D01*
X1166344Y231258D01*
Y230842D01*
X1166469Y230467D01*
X1166719Y230217D01*
X1167010Y230133D01*
X1167302Y230217D01*
X1167510Y230425D01*
X1167635Y230758D01*
X1167677Y231050D01*
G01X1167302Y233233D02*
X1167510Y233483D01*
X1167635Y233775D01*
X1167677Y234150D01*
X1167594Y234525D01*
X1167427Y234817D01*
X1167135Y235025D01*
X1166802Y235067D01*
X1166469Y234983D01*
X1166260Y234775D01*
X1166094Y234483D01*
X1166052Y234192D01*
X1166094Y233900D01*
X1166260Y233525D01*
X1165177Y233650D01*
Y234775D01*
G01X1160468Y248084D02*
X1164468D01*
Y255484D01*
G01X1166017Y243500D02*
Y246000D01*
X1167058D01*
X1167392Y245875D01*
X1167600Y245708D01*
X1167683Y245375D01*
X1167600Y245042D01*
X1167350Y244833D01*
X1167058Y244708D01*
X1166017D01*
G01X1167058D02*
X1167683Y243500D01*
G01X1169158Y245583D02*
X1169408Y245833D01*
X1169700Y245958D01*
X1170033Y246000D01*
X1170450Y245917D01*
X1170742Y245708D01*
X1170825Y245458D01*
X1170783Y245208D01*
X1170617Y245000D01*
X1169783Y244583D01*
X1169408Y244292D01*
X1169158Y243875D01*
X1169075Y243500D01*
X1170825D01*
G01X1173050Y246000D02*
X1172717Y245917D01*
X1172467Y245708D01*
X1172300Y245458D01*
X1172175Y245125D01*
X1172133Y244750D01*
X1172175Y244375D01*
X1172300Y244042D01*
X1172467Y243792D01*
X1172717Y243583D01*
X1173050Y243500D01*
X1173383Y243583D01*
X1173633Y243792D01*
X1173800Y244042D01*
X1173925Y244375D01*
X1173967Y244750D01*
X1173925Y245125D01*
X1173800Y245458D01*
X1173633Y245708D01*
X1173383Y245917D01*
X1173050Y246000D01*
G01X1176067Y243500D02*
X1176150Y244042D01*
X1176275Y244500D01*
X1176442Y244917D01*
X1176650Y245375D01*
X1176983Y246000D01*
X1175317D01*
G01X1166017Y247500D02*
Y250000D01*
X1167058D01*
X1167392Y249875D01*
X1167600Y249708D01*
X1167683Y249375D01*
X1167600Y249042D01*
X1167350Y248833D01*
X1167058Y248708D01*
X1166017D01*
G01X1167058D02*
X1167683Y247500D01*
G01X1169158Y249583D02*
X1169408Y249833D01*
X1169700Y249958D01*
X1170033Y250000D01*
X1170450Y249917D01*
X1170742Y249708D01*
X1170825Y249458D01*
X1170783Y249208D01*
X1170617Y249000D01*
X1169783Y248583D01*
X1169408Y248292D01*
X1169158Y247875D01*
X1169075Y247500D01*
X1170825D01*
G01X1173050D02*
Y250000D01*
X1172550Y249500D01*
G01Y247500D02*
X1173550D01*
G01X1176150D02*
X1176442Y247542D01*
X1176775Y247667D01*
X1176983Y247875D01*
X1177067Y248167D01*
X1176983Y248458D01*
X1176733Y248708D01*
X1176358Y248833D01*
X1175942D01*
X1175692Y248917D01*
X1175483Y249125D01*
X1175400Y249417D01*
X1175525Y249708D01*
X1175817Y249917D01*
X1176150Y250000D01*
X1176483Y249917D01*
X1176775Y249708D01*
X1176900Y249417D01*
X1176817Y249125D01*
X1176608Y248917D01*
X1176358Y248833D01*
X1175942D01*
X1175567Y248708D01*
X1175317Y248458D01*
X1175233Y248167D01*
X1175317Y247875D01*
X1175525Y247667D01*
X1175858Y247542D01*
X1176150Y247500D01*
G01X1165000Y356017D02*
X1162500D01*
Y357058D01*
X1162625Y357392D01*
X1162792Y357600D01*
X1163125Y357683D01*
X1163458Y357600D01*
X1163667Y357350D01*
X1163792Y357058D01*
Y356017D01*
G01Y357058D02*
X1165000Y357683D01*
G01Y359950D02*
X1162500D01*
X1163000Y359450D01*
G01X1165000D02*
Y360450D01*
G01X1164625Y362133D02*
X1164833Y362383D01*
X1164958Y362675D01*
X1165000Y363050D01*
X1164917Y363425D01*
X1164750Y363717D01*
X1164458Y363925D01*
X1164125Y363967D01*
X1163792Y363883D01*
X1163583Y363675D01*
X1163417Y363383D01*
X1163375Y363092D01*
X1163417Y362800D01*
X1163583Y362425D01*
X1162500Y362550D01*
Y363675D01*
G01X1164708Y365442D02*
X1164917Y365733D01*
X1165000Y366067D01*
X1164917Y366400D01*
X1164667Y366692D01*
X1164292Y366900D01*
X1163917Y366983D01*
X1163458D01*
X1163083Y366900D01*
X1162750Y366692D01*
X1162583Y366442D01*
X1162500Y366150D01*
X1162583Y365817D01*
X1162750Y365567D01*
X1163000Y365400D01*
X1163333Y365317D01*
X1163625Y365400D01*
X1163917Y365608D01*
X1164083Y365858D01*
X1164125Y366150D01*
X1164042Y366483D01*
X1163833Y366733D01*
X1163458Y366983D01*
G01X1169000Y354467D02*
X1166500D01*
Y355508D01*
X1166625Y355842D01*
X1166792Y356050D01*
X1167125Y356133D01*
X1167458Y356050D01*
X1167667Y355800D01*
X1167792Y355508D01*
Y354467D01*
G01Y355508D02*
X1169000Y356133D01*
G01X1168625Y357483D02*
X1168833Y357733D01*
X1168958Y358025D01*
X1169000Y358400D01*
X1168917Y358775D01*
X1168750Y359067D01*
X1168458Y359275D01*
X1168125Y359317D01*
X1167792Y359233D01*
X1167583Y359025D01*
X1167417Y358733D01*
X1167375Y358442D01*
X1167417Y358150D01*
X1167583Y357775D01*
X1166500Y357900D01*
Y359025D01*
G01X1168500Y360583D02*
X1168792Y360833D01*
X1168958Y361167D01*
X1169000Y361542D01*
X1168958Y361875D01*
X1168750Y362208D01*
X1168500Y362417D01*
X1168250Y362458D01*
X1167958Y362375D01*
X1167750Y362083D01*
X1167667Y361792D01*
Y361417D01*
G01Y361792D02*
X1167542Y362042D01*
X1167333Y362250D01*
X1167083Y362333D01*
X1166833Y362250D01*
X1166625Y362042D01*
X1166500Y361667D01*
X1166542Y361292D01*
X1166708Y360917D01*
G01X1166500Y364600D02*
X1166583Y364267D01*
X1166792Y364017D01*
X1167042Y363850D01*
X1167375Y363725D01*
X1167750Y363683D01*
X1168125Y363725D01*
X1168458Y363850D01*
X1168708Y364017D01*
X1168917Y364267D01*
X1169000Y364600D01*
X1168917Y364933D01*
X1168708Y365183D01*
X1168458Y365350D01*
X1168125Y365475D01*
X1167750Y365517D01*
X1167375Y365475D01*
X1167042Y365350D01*
X1166792Y365183D01*
X1166583Y364933D01*
X1166500Y364600D01*
G01X1169000Y367700D02*
X1168958Y367992D01*
X1168833Y368325D01*
X1168625Y368533D01*
X1168333Y368617D01*
X1168042Y368533D01*
X1167792Y368283D01*
X1167667Y367908D01*
Y367492D01*
X1167583Y367242D01*
X1167375Y367033D01*
X1167083Y366950D01*
X1166792Y367075D01*
X1166583Y367367D01*
X1166500Y367700D01*
X1166583Y368033D01*
X1166792Y368325D01*
X1167083Y368450D01*
X1167375Y368367D01*
X1167583Y368158D01*
X1167667Y367908D01*
Y367492D01*
X1167792Y367117D01*
X1168042Y366867D01*
X1168333Y366783D01*
X1168625Y366867D01*
X1168833Y367075D01*
X1168958Y367408D01*
X1169000Y367700D01*
G01X1164767Y381292D02*
X1164517Y381417D01*
X1164225Y381500D01*
X1163892D01*
X1163517Y381375D01*
X1163225Y381167D01*
X1163017Y380917D01*
X1162850Y380500D01*
X1162808Y380125D01*
X1162892Y379750D01*
X1163017Y379500D01*
X1163267Y379250D01*
X1163558Y379083D01*
X1163850Y379000D01*
X1164142D01*
X1164433Y379083D01*
X1164683Y379208D01*
X1164892Y379375D01*
G01X1166033Y379500D02*
X1166283Y379208D01*
X1166617Y379042D01*
X1166992Y379000D01*
X1167325Y379042D01*
X1167658Y379250D01*
X1167867Y379500D01*
X1167908Y379750D01*
X1167825Y380042D01*
X1167533Y380250D01*
X1167242Y380333D01*
X1166867D01*
G01X1167242D02*
X1167492Y380458D01*
X1167700Y380667D01*
X1167783Y380917D01*
X1167700Y381167D01*
X1167492Y381375D01*
X1167117Y381500D01*
X1166742Y381458D01*
X1166367Y381292D01*
G01X1169258Y381083D02*
X1169508Y381333D01*
X1169800Y381458D01*
X1170133Y381500D01*
X1170550Y381417D01*
X1170842Y381208D01*
X1170925Y380958D01*
X1170883Y380708D01*
X1170717Y380500D01*
X1169883Y380083D01*
X1169508Y379792D01*
X1169258Y379375D01*
X1169175Y379000D01*
X1170925D01*
G01X1172358Y380042D02*
X1172650Y380333D01*
X1172900Y380500D01*
X1173233Y380583D01*
X1173525Y380500D01*
X1173733Y380333D01*
X1173900Y380083D01*
X1173942Y379792D01*
X1173900Y379542D01*
X1173733Y379292D01*
X1173483Y379083D01*
X1173192Y379000D01*
X1172858Y379083D01*
X1172567Y379333D01*
X1172400Y379708D01*
X1172358Y380125D01*
X1172442Y380667D01*
X1172567Y380958D01*
X1172775Y381250D01*
X1173067Y381458D01*
X1173358Y381500D01*
X1173650Y381417D01*
X1173858Y381208D01*
G01X1154584Y568522D02*
Y593822D01*
X1185284D01*
Y568522D01*
X1154584D01*
G01X1175534Y596372D02*
Y615572D01*
X1164334D01*
Y596372D01*
X1175534D01*
Y596772D01*
G01X1156500Y646000D02*
X1171500D01*
Y631000D01*
X1155000D01*
Y627500D01*
G01X1158517Y627000D02*
Y629500D01*
X1159558D01*
X1159892Y629375D01*
X1160100Y629208D01*
X1160183Y628875D01*
X1160100Y628542D01*
X1159850Y628333D01*
X1159558Y628208D01*
X1158517D01*
G01X1159558D02*
X1160183Y627000D01*
G01X1161658Y628042D02*
X1161950Y628333D01*
X1162200Y628500D01*
X1162533Y628583D01*
X1162825Y628500D01*
X1163033Y628333D01*
X1163200Y628083D01*
X1163242Y627792D01*
X1163200Y627542D01*
X1163033Y627292D01*
X1162783Y627083D01*
X1162492Y627000D01*
X1162158Y627083D01*
X1161867Y627333D01*
X1161700Y627708D01*
X1161658Y628125D01*
X1161742Y628667D01*
X1161867Y628958D01*
X1162075Y629250D01*
X1162367Y629458D01*
X1162658Y629500D01*
X1162950Y629417D01*
X1163158Y629208D01*
G01X1165467Y627000D02*
X1165550Y627542D01*
X1165675Y628000D01*
X1165842Y628417D01*
X1166050Y628875D01*
X1166383Y629500D01*
X1164717D01*
G01X1167942Y627292D02*
X1168233Y627083D01*
X1168567Y627000D01*
X1168900Y627083D01*
X1169192Y627333D01*
X1169400Y627708D01*
X1169483Y628083D01*
Y628542D01*
X1169400Y628917D01*
X1169192Y629250D01*
X1168942Y629417D01*
X1168650Y629500D01*
X1168317Y629417D01*
X1168067Y629250D01*
X1167900Y629000D01*
X1167817Y628667D01*
X1167900Y628375D01*
X1168108Y628083D01*
X1168358Y627917D01*
X1168650Y627875D01*
X1168983Y627958D01*
X1169233Y628167D01*
X1169483Y628542D01*
G01X1161500Y625700D02*
X1157500D01*
Y618300D01*
G01X1165500Y618800D02*
X1169500D01*
Y626200D01*
G01X1153500Y632300D02*
X1157500D01*
Y639700D01*
G01Y632300D02*
X1161500D01*
Y639700D01*
G01X1165500Y632300D02*
X1169500D01*
Y639700D01*
G01X1161500Y632300D02*
X1165500D01*
Y639700D01*
G01X1160708Y740767D02*
X1160583Y740517D01*
X1160500Y740225D01*
Y739892D01*
X1160625Y739517D01*
X1160833Y739225D01*
X1161083Y739017D01*
X1161500Y738850D01*
X1161875Y738808D01*
X1162250Y738892D01*
X1162500Y739017D01*
X1162750Y739267D01*
X1162917Y739558D01*
X1163000Y739850D01*
Y740142D01*
X1162917Y740433D01*
X1162792Y740683D01*
X1162625Y740892D01*
G01X1163000Y742950D02*
X1160500D01*
X1161000Y742450D01*
G01X1163000D02*
Y743450D01*
G01Y745967D02*
X1162458Y746050D01*
X1162000Y746175D01*
X1161583Y746342D01*
X1161125Y746550D01*
X1160500Y746883D01*
Y745217D01*
G01X1163000Y749150D02*
X1162958Y749442D01*
X1162833Y749775D01*
X1162625Y749983D01*
X1162333Y750067D01*
X1162042Y749983D01*
X1161792Y749733D01*
X1161667Y749358D01*
Y748942D01*
X1161583Y748692D01*
X1161375Y748483D01*
X1161083Y748400D01*
X1160792Y748525D01*
X1160583Y748817D01*
X1160500Y749150D01*
X1160583Y749483D01*
X1160792Y749775D01*
X1161083Y749900D01*
X1161375Y749817D01*
X1161583Y749608D01*
X1161667Y749358D01*
Y748942D01*
X1161792Y748567D01*
X1162042Y748317D01*
X1162333Y748233D01*
X1162625Y748317D01*
X1162833Y748525D01*
X1162958Y748858D01*
X1163000Y749150D01*
G01X1164708Y740767D02*
X1164583Y740517D01*
X1164500Y740225D01*
Y739892D01*
X1164625Y739517D01*
X1164833Y739225D01*
X1165083Y739017D01*
X1165500Y738850D01*
X1165875Y738808D01*
X1166250Y738892D01*
X1166500Y739017D01*
X1166750Y739267D01*
X1166917Y739558D01*
X1167000Y739850D01*
Y740142D01*
X1166917Y740433D01*
X1166792Y740683D01*
X1166625Y740892D01*
G01X1167000Y742950D02*
X1164500D01*
X1165000Y742450D01*
G01X1167000D02*
Y743450D01*
G01Y746050D02*
X1166958Y746342D01*
X1166833Y746675D01*
X1166625Y746883D01*
X1166333Y746967D01*
X1166042Y746883D01*
X1165792Y746633D01*
X1165667Y746258D01*
Y745842D01*
X1165583Y745592D01*
X1165375Y745383D01*
X1165083Y745300D01*
X1164792Y745425D01*
X1164583Y745717D01*
X1164500Y746050D01*
X1164583Y746383D01*
X1164792Y746675D01*
X1165083Y746800D01*
X1165375Y746717D01*
X1165583Y746508D01*
X1165667Y746258D01*
Y745842D01*
X1165792Y745467D01*
X1166042Y745217D01*
X1166333Y745133D01*
X1166625Y745217D01*
X1166833Y745425D01*
X1166958Y745758D01*
X1167000Y746050D01*
G01X1166625Y748233D02*
X1166833Y748483D01*
X1166958Y748775D01*
X1167000Y749150D01*
X1166917Y749525D01*
X1166750Y749817D01*
X1166458Y750025D01*
X1166125Y750067D01*
X1165792Y749983D01*
X1165583Y749775D01*
X1165417Y749483D01*
X1165375Y749192D01*
X1165417Y748900D01*
X1165583Y748525D01*
X1164500Y748650D01*
Y749775D01*
G01X1157017Y760000D02*
Y762500D01*
X1158058D01*
X1158392Y762375D01*
X1158600Y762208D01*
X1158683Y761875D01*
X1158600Y761542D01*
X1158350Y761333D01*
X1158058Y761208D01*
X1157017D01*
G01X1158058D02*
X1158683Y760000D01*
G01X1160158Y761042D02*
X1160450Y761333D01*
X1160700Y761500D01*
X1161033Y761583D01*
X1161325Y761500D01*
X1161533Y761333D01*
X1161700Y761083D01*
X1161742Y760792D01*
X1161700Y760542D01*
X1161533Y760292D01*
X1161283Y760083D01*
X1160992Y760000D01*
X1160658Y760083D01*
X1160367Y760333D01*
X1160200Y760708D01*
X1160158Y761125D01*
X1160242Y761667D01*
X1160367Y761958D01*
X1160575Y762250D01*
X1160867Y762458D01*
X1161158Y762500D01*
X1161450Y762417D01*
X1161658Y762208D01*
G01X1163967Y760000D02*
X1164050Y760542D01*
X1164175Y761000D01*
X1164342Y761417D01*
X1164550Y761875D01*
X1164883Y762500D01*
X1163217D01*
G01X1167150D02*
X1166817Y762417D01*
X1166567Y762208D01*
X1166400Y761958D01*
X1166275Y761625D01*
X1166233Y761250D01*
X1166275Y760875D01*
X1166400Y760542D01*
X1166567Y760292D01*
X1166817Y760083D01*
X1167150Y760000D01*
X1167483Y760083D01*
X1167733Y760292D01*
X1167900Y760542D01*
X1168025Y760875D01*
X1168067Y761250D01*
X1168025Y761625D01*
X1167900Y761958D01*
X1167733Y762208D01*
X1167483Y762417D01*
X1167150Y762500D01*
G01X1159483Y811500D02*
Y809708D01*
X1159650Y809333D01*
X1159983Y809083D01*
X1160400Y809000D01*
X1160817Y809083D01*
X1161150Y809333D01*
X1161317Y809708D01*
Y811500D01*
G01X1163500Y809000D02*
Y811500D01*
X1163000Y811000D01*
G01Y809000D02*
X1164000D01*
G01X1166600D02*
X1166892Y809042D01*
X1167225Y809167D01*
X1167433Y809375D01*
X1167517Y809667D01*
X1167433Y809958D01*
X1167183Y810208D01*
X1166808Y810333D01*
X1166392D01*
X1166142Y810417D01*
X1165933Y810625D01*
X1165850Y810917D01*
X1165975Y811208D01*
X1166267Y811417D01*
X1166600Y811500D01*
X1166933Y811417D01*
X1167225Y811208D01*
X1167350Y810917D01*
X1167267Y810625D01*
X1167058Y810417D01*
X1166808Y810333D01*
X1166392D01*
X1166017Y810208D01*
X1165767Y809958D01*
X1165683Y809667D01*
X1165767Y809375D01*
X1165975Y809167D01*
X1166308Y809042D01*
X1166600Y809000D01*
G01X1153267Y837792D02*
X1153017Y837917D01*
X1152725Y838000D01*
X1152392D01*
X1152017Y837875D01*
X1151725Y837667D01*
X1151517Y837417D01*
X1151350Y837000D01*
X1151308Y836625D01*
X1151392Y836250D01*
X1151517Y836000D01*
X1151767Y835750D01*
X1152058Y835583D01*
X1152350Y835500D01*
X1152642D01*
X1152933Y835583D01*
X1153183Y835708D01*
X1153392Y835875D01*
G01X1155450Y835500D02*
Y838000D01*
X1154950Y837500D01*
G01Y835500D02*
X1155950D01*
G01X1158550D02*
X1158842Y835542D01*
X1159175Y835667D01*
X1159383Y835875D01*
X1159467Y836167D01*
X1159383Y836458D01*
X1159133Y836708D01*
X1158758Y836833D01*
X1158342D01*
X1158092Y836917D01*
X1157883Y837125D01*
X1157800Y837417D01*
X1157925Y837708D01*
X1158217Y837917D01*
X1158550Y838000D01*
X1158883Y837917D01*
X1159175Y837708D01*
X1159300Y837417D01*
X1159217Y837125D01*
X1159008Y836917D01*
X1158758Y836833D01*
X1158342D01*
X1157967Y836708D01*
X1157717Y836458D01*
X1157633Y836167D01*
X1157717Y835875D01*
X1157925Y835667D01*
X1158258Y835542D01*
X1158550Y835500D01*
G01X1161650Y838000D02*
X1161317Y837917D01*
X1161067Y837708D01*
X1160900Y837458D01*
X1160775Y837125D01*
X1160733Y836750D01*
X1160775Y836375D01*
X1160900Y836042D01*
X1161067Y835792D01*
X1161317Y835583D01*
X1161650Y835500D01*
X1161983Y835583D01*
X1162233Y835792D01*
X1162400Y836042D01*
X1162525Y836375D01*
X1162567Y836750D01*
X1162525Y837125D01*
X1162400Y837458D01*
X1162233Y837708D01*
X1161983Y837917D01*
X1161650Y838000D01*
G01X1153267Y833292D02*
X1153017Y833417D01*
X1152725Y833500D01*
X1152392D01*
X1152017Y833375D01*
X1151725Y833167D01*
X1151517Y832917D01*
X1151350Y832500D01*
X1151308Y832125D01*
X1151392Y831750D01*
X1151517Y831500D01*
X1151767Y831250D01*
X1152058Y831083D01*
X1152350Y831000D01*
X1152642D01*
X1152933Y831083D01*
X1153183Y831208D01*
X1153392Y831375D01*
G01X1155450Y831000D02*
Y833500D01*
X1154950Y833000D01*
G01Y831000D02*
X1155950D01*
G01X1158467D02*
X1158550Y831542D01*
X1158675Y832000D01*
X1158842Y832417D01*
X1159050Y832875D01*
X1159383Y833500D01*
X1157717D01*
G01X1160942Y831292D02*
X1161233Y831083D01*
X1161567Y831000D01*
X1161900Y831083D01*
X1162192Y831333D01*
X1162400Y831708D01*
X1162483Y832083D01*
Y832542D01*
X1162400Y832917D01*
X1162192Y833250D01*
X1161942Y833417D01*
X1161650Y833500D01*
X1161317Y833417D01*
X1161067Y833250D01*
X1160900Y833000D01*
X1160817Y832667D01*
X1160900Y832375D01*
X1161108Y832083D01*
X1161358Y831917D01*
X1161650Y831875D01*
X1161983Y831958D01*
X1162233Y832167D01*
X1162483Y832542D01*
G01X1158968Y889301D02*
X1156468D01*
Y890301D01*
X1156593Y890634D01*
X1156885Y890884D01*
X1157218Y890967D01*
X1157551Y890884D01*
X1157801Y890676D01*
X1157926Y890301D01*
Y889301D01*
G01X1156676Y894151D02*
X1156551Y893901D01*
X1156468Y893609D01*
Y893276D01*
X1156593Y892901D01*
X1156801Y892609D01*
X1157051Y892401D01*
X1157468Y892234D01*
X1157843Y892192D01*
X1158218Y892276D01*
X1158468Y892401D01*
X1158718Y892651D01*
X1158885Y892942D01*
X1158968Y893234D01*
Y893526D01*
X1158885Y893817D01*
X1158760Y894067D01*
X1158593Y894276D01*
G01X1158968Y896334D02*
X1158926Y896626D01*
X1158801Y896959D01*
X1158593Y897167D01*
X1158301Y897251D01*
X1158010Y897167D01*
X1157760Y896917D01*
X1157635Y896542D01*
Y896126D01*
X1157551Y895876D01*
X1157343Y895667D01*
X1157051Y895584D01*
X1156760Y895709D01*
X1156551Y896001D01*
X1156468Y896334D01*
X1156551Y896667D01*
X1156760Y896959D01*
X1157051Y897084D01*
X1157343Y897001D01*
X1157551Y896792D01*
X1157635Y896542D01*
Y896126D01*
X1157760Y895751D01*
X1158010Y895501D01*
X1158301Y895417D01*
X1158593Y895501D01*
X1158801Y895709D01*
X1158926Y896042D01*
X1158968Y896334D01*
G01Y899934D02*
X1156468D01*
X1158260Y898392D01*
Y900476D01*
G01X1166968Y889301D02*
X1164468D01*
Y890301D01*
X1164593Y890634D01*
X1164885Y890884D01*
X1165218Y890967D01*
X1165551Y890884D01*
X1165801Y890676D01*
X1165926Y890301D01*
Y889301D01*
G01X1164676Y894151D02*
X1164551Y893901D01*
X1164468Y893609D01*
Y893276D01*
X1164593Y892901D01*
X1164801Y892609D01*
X1165051Y892401D01*
X1165468Y892234D01*
X1165843Y892192D01*
X1166218Y892276D01*
X1166468Y892401D01*
X1166718Y892651D01*
X1166885Y892942D01*
X1166968Y893234D01*
Y893526D01*
X1166885Y893817D01*
X1166760Y894067D01*
X1166593Y894276D01*
G01X1166968Y896334D02*
X1166926Y896626D01*
X1166801Y896959D01*
X1166593Y897167D01*
X1166301Y897251D01*
X1166010Y897167D01*
X1165760Y896917D01*
X1165635Y896542D01*
Y896126D01*
X1165551Y895876D01*
X1165343Y895667D01*
X1165051Y895584D01*
X1164760Y895709D01*
X1164551Y896001D01*
X1164468Y896334D01*
X1164551Y896667D01*
X1164760Y896959D01*
X1165051Y897084D01*
X1165343Y897001D01*
X1165551Y896792D01*
X1165635Y896542D01*
Y896126D01*
X1165760Y895751D01*
X1166010Y895501D01*
X1166301Y895417D01*
X1166593Y895501D01*
X1166801Y895709D01*
X1166926Y896042D01*
X1166968Y896334D01*
G01X1166593Y898517D02*
X1166801Y898767D01*
X1166926Y899059D01*
X1166968Y899434D01*
X1166885Y899809D01*
X1166718Y900101D01*
X1166426Y900309D01*
X1166093Y900351D01*
X1165760Y900267D01*
X1165551Y900059D01*
X1165385Y899767D01*
X1165343Y899476D01*
X1165385Y899184D01*
X1165551Y898809D01*
X1164468Y898934D01*
Y900059D01*
G01X1169385Y225767D02*
X1169260Y225517D01*
X1169177Y225225D01*
Y224892D01*
X1169302Y224517D01*
X1169510Y224225D01*
X1169760Y224017D01*
X1170177Y223850D01*
X1170552Y223808D01*
X1170927Y223892D01*
X1171177Y224017D01*
X1171427Y224267D01*
X1171594Y224558D01*
X1171677Y224850D01*
Y225142D01*
X1171594Y225433D01*
X1171469Y225683D01*
X1171302Y225892D01*
G01X1169594Y227158D02*
X1169344Y227408D01*
X1169219Y227700D01*
X1169177Y228033D01*
X1169260Y228450D01*
X1169469Y228742D01*
X1169719Y228825D01*
X1169969Y228783D01*
X1170177Y228617D01*
X1170594Y227783D01*
X1170885Y227408D01*
X1171302Y227158D01*
X1171677Y227075D01*
Y228825D01*
G01Y231050D02*
X1171635Y231342D01*
X1171510Y231675D01*
X1171302Y231883D01*
X1171010Y231967D01*
X1170719Y231883D01*
X1170469Y231633D01*
X1170344Y231258D01*
Y230842D01*
X1170260Y230592D01*
X1170052Y230383D01*
X1169760Y230300D01*
X1169469Y230425D01*
X1169260Y230717D01*
X1169177Y231050D01*
X1169260Y231383D01*
X1169469Y231675D01*
X1169760Y231800D01*
X1170052Y231717D01*
X1170260Y231508D01*
X1170344Y231258D01*
Y230842D01*
X1170469Y230467D01*
X1170719Y230217D01*
X1171010Y230133D01*
X1171302Y230217D01*
X1171510Y230425D01*
X1171635Y230758D01*
X1171677Y231050D01*
G01X1171177Y233233D02*
X1171469Y233483D01*
X1171635Y233817D01*
X1171677Y234192D01*
X1171635Y234525D01*
X1171427Y234858D01*
X1171177Y235067D01*
X1170927Y235108D01*
X1170635Y235025D01*
X1170427Y234733D01*
X1170344Y234442D01*
Y234067D01*
G01Y234442D02*
X1170219Y234692D01*
X1170010Y234900D01*
X1169760Y234983D01*
X1169510Y234900D01*
X1169302Y234692D01*
X1169177Y234317D01*
X1169219Y233942D01*
X1169385Y233567D01*
G01X1170000Y252467D02*
X1167500D01*
Y253467D01*
X1167625Y253800D01*
X1167917Y254050D01*
X1168250Y254133D01*
X1168583Y254050D01*
X1168833Y253842D01*
X1168958Y253467D01*
Y252467D01*
G01X1170000Y255567D02*
X1167500D01*
Y256608D01*
X1167625Y256942D01*
X1167792Y257150D01*
X1168125Y257233D01*
X1168458Y257150D01*
X1168667Y256900D01*
X1168792Y256608D01*
Y255567D01*
G01Y256608D02*
X1170000Y257233D01*
G01Y259500D02*
X1167500D01*
X1168000Y259000D01*
G01X1170000D02*
Y260000D01*
G01Y262600D02*
X1167500D01*
X1168000Y262100D01*
G01X1170000D02*
Y263100D01*
G01Y265700D02*
X1169958Y265992D01*
X1169833Y266325D01*
X1169625Y266533D01*
X1169333Y266617D01*
X1169042Y266533D01*
X1168792Y266283D01*
X1168667Y265908D01*
Y265492D01*
X1168583Y265242D01*
X1168375Y265033D01*
X1168083Y264950D01*
X1167792Y265075D01*
X1167583Y265367D01*
X1167500Y265700D01*
X1167583Y266033D01*
X1167792Y266325D01*
X1168083Y266450D01*
X1168375Y266367D01*
X1168583Y266158D01*
X1168667Y265908D01*
Y265492D01*
X1168792Y265117D01*
X1169042Y264867D01*
X1169333Y264783D01*
X1169625Y264867D01*
X1169833Y265075D01*
X1169958Y265408D01*
X1170000Y265700D01*
G01X1186700Y242000D02*
Y246000D01*
X1179300D01*
G01X1186700Y235000D02*
Y239000D01*
X1179300D01*
G01X1186700Y246000D02*
Y250000D01*
X1179300D01*
G01X1182517Y346500D02*
Y349000D01*
X1183558D01*
X1183892Y348875D01*
X1184100Y348708D01*
X1184183Y348375D01*
X1184100Y348042D01*
X1183850Y347833D01*
X1183558Y347708D01*
X1182517D01*
G01X1183558D02*
X1184183Y346500D01*
G01X1186450D02*
Y349000D01*
X1185950Y348500D01*
G01Y346500D02*
X1186950D01*
G01X1188758Y347542D02*
X1189050Y347833D01*
X1189300Y348000D01*
X1189633Y348083D01*
X1189925Y348000D01*
X1190133Y347833D01*
X1190300Y347583D01*
X1190342Y347292D01*
X1190300Y347042D01*
X1190133Y346792D01*
X1189883Y346583D01*
X1189592Y346500D01*
X1189258Y346583D01*
X1188967Y346833D01*
X1188800Y347208D01*
X1188758Y347625D01*
X1188842Y348167D01*
X1188967Y348458D01*
X1189175Y348750D01*
X1189467Y348958D01*
X1189758Y349000D01*
X1190050Y348917D01*
X1190258Y348708D01*
G01X1191858Y348583D02*
X1192108Y348833D01*
X1192400Y348958D01*
X1192733Y349000D01*
X1193150Y348917D01*
X1193442Y348708D01*
X1193525Y348458D01*
X1193483Y348208D01*
X1193317Y348000D01*
X1192483Y347583D01*
X1192108Y347292D01*
X1191858Y346875D01*
X1191775Y346500D01*
X1193525D01*
G01X1182467Y351000D02*
Y353500D01*
X1183508D01*
X1183842Y353375D01*
X1184050Y353208D01*
X1184133Y352875D01*
X1184050Y352542D01*
X1183800Y352333D01*
X1183508Y352208D01*
X1182467D01*
G01X1183508D02*
X1184133Y351000D01*
G01X1185483Y351375D02*
X1185733Y351167D01*
X1186025Y351042D01*
X1186400Y351000D01*
X1186775Y351083D01*
X1187067Y351250D01*
X1187275Y351542D01*
X1187317Y351875D01*
X1187233Y352208D01*
X1187025Y352417D01*
X1186733Y352583D01*
X1186442Y352625D01*
X1186150Y352583D01*
X1185775Y352417D01*
X1185900Y353500D01*
X1187025D01*
G01X1188583Y351500D02*
X1188833Y351208D01*
X1189167Y351042D01*
X1189542Y351000D01*
X1189875Y351042D01*
X1190208Y351250D01*
X1190417Y351500D01*
X1190458Y351750D01*
X1190375Y352042D01*
X1190083Y352250D01*
X1189792Y352333D01*
X1189417D01*
G01X1189792D02*
X1190042Y352458D01*
X1190250Y352667D01*
X1190333Y352917D01*
X1190250Y353167D01*
X1190042Y353375D01*
X1189667Y353500D01*
X1189292Y353458D01*
X1188917Y353292D01*
G01X1192600Y353500D02*
X1192267Y353417D01*
X1192017Y353208D01*
X1191850Y352958D01*
X1191725Y352625D01*
X1191683Y352250D01*
X1191725Y351875D01*
X1191850Y351542D01*
X1192017Y351292D01*
X1192267Y351083D01*
X1192600Y351000D01*
X1192933Y351083D01*
X1193183Y351292D01*
X1193350Y351542D01*
X1193475Y351875D01*
X1193517Y352250D01*
X1193475Y352625D01*
X1193350Y352958D01*
X1193183Y353208D01*
X1192933Y353417D01*
X1192600Y353500D01*
G01X1194992Y351292D02*
X1195283Y351083D01*
X1195617Y351000D01*
X1195950Y351083D01*
X1196242Y351333D01*
X1196450Y351708D01*
X1196533Y352083D01*
Y352542D01*
X1196450Y352917D01*
X1196242Y353250D01*
X1195992Y353417D01*
X1195700Y353500D01*
X1195367Y353417D01*
X1195117Y353250D01*
X1194950Y353000D01*
X1194867Y352667D01*
X1194950Y352375D01*
X1195158Y352083D01*
X1195408Y351917D01*
X1195700Y351875D01*
X1196033Y351958D01*
X1196283Y352167D01*
X1196533Y352542D01*
G01X1176000Y358300D02*
X1180000D01*
Y365700D01*
G01Y358300D02*
X1184000D01*
Y365700D01*
G01X1190750Y378000D02*
Y386000D01*
X1178800D01*
Y378000D01*
X1190750D01*
G01X1178800Y384150D02*
X1180800Y382150D01*
X1178800Y380150D01*
G01X1181000Y405700D02*
X1177000D01*
Y398300D01*
G01X1181000D02*
X1185000D01*
Y405700D01*
G01X1167934Y596472D02*
X1169734Y598572D01*
X1171934Y596472D01*
G01X1175850Y633000D02*
Y630500D01*
G01X1174892Y633000D02*
X1176808D01*
G01X1178117Y630500D02*
Y633000D01*
X1179117D01*
X1179450Y632875D01*
X1179700Y632583D01*
X1179783Y632250D01*
X1179700Y631917D01*
X1179492Y631667D01*
X1179117Y631542D01*
X1178117D01*
G01X1181342Y630792D02*
X1181633Y630583D01*
X1181967Y630500D01*
X1182300Y630583D01*
X1182592Y630833D01*
X1182800Y631208D01*
X1182883Y631583D01*
Y632042D01*
X1182800Y632417D01*
X1182592Y632750D01*
X1182342Y632917D01*
X1182050Y633000D01*
X1181717Y632917D01*
X1181467Y632750D01*
X1181300Y632500D01*
X1181217Y632167D01*
X1181300Y631875D01*
X1181508Y631583D01*
X1181758Y631417D01*
X1182050Y631375D01*
X1182383Y631458D01*
X1182633Y631667D01*
X1182883Y632042D01*
G01X1184358Y632583D02*
X1184608Y632833D01*
X1184900Y632958D01*
X1185233Y633000D01*
X1185650Y632917D01*
X1185942Y632708D01*
X1186025Y632458D01*
X1185983Y632208D01*
X1185817Y632000D01*
X1184983Y631583D01*
X1184608Y631292D01*
X1184358Y630875D01*
X1184275Y630500D01*
X1186025D01*
G01X1171300Y623000D02*
Y619000D01*
X1178700D01*
G01X1175517Y625000D02*
Y627500D01*
X1176558D01*
X1176892Y627375D01*
X1177100Y627208D01*
X1177183Y626875D01*
X1177100Y626542D01*
X1176850Y626333D01*
X1176558Y626208D01*
X1175517D01*
G01X1176558D02*
X1177183Y625000D01*
G01X1178658Y627083D02*
X1178908Y627333D01*
X1179200Y627458D01*
X1179533Y627500D01*
X1179950Y627417D01*
X1180242Y627208D01*
X1180325Y626958D01*
X1180283Y626708D01*
X1180117Y626500D01*
X1179283Y626083D01*
X1178908Y625792D01*
X1178658Y625375D01*
X1178575Y625000D01*
X1180325D01*
G01X1181842Y625292D02*
X1182133Y625083D01*
X1182467Y625000D01*
X1182800Y625083D01*
X1183092Y625333D01*
X1183300Y625708D01*
X1183383Y626083D01*
Y626542D01*
X1183300Y626917D01*
X1183092Y627250D01*
X1182842Y627417D01*
X1182550Y627500D01*
X1182217Y627417D01*
X1181967Y627250D01*
X1181800Y627000D01*
X1181717Y626667D01*
X1181800Y626375D01*
X1182008Y626083D01*
X1182258Y625917D01*
X1182550Y625875D01*
X1182883Y625958D01*
X1183133Y626167D01*
X1183383Y626542D01*
G01X1185650Y625000D02*
Y627500D01*
X1185150Y627000D01*
G01Y625000D02*
X1186150D01*
G01X1175500Y637350D02*
X1178000D01*
G01X1175500Y636392D02*
Y638308D01*
G01X1178000Y639617D02*
X1175500D01*
Y640617D01*
X1175625Y640950D01*
X1175917Y641200D01*
X1176250Y641283D01*
X1176583Y641200D01*
X1176833Y640992D01*
X1176958Y640617D01*
Y639617D01*
G01X1177708Y642842D02*
X1177917Y643133D01*
X1178000Y643467D01*
X1177917Y643800D01*
X1177667Y644092D01*
X1177292Y644300D01*
X1176917Y644383D01*
X1176458D01*
X1176083Y644300D01*
X1175750Y644092D01*
X1175583Y643842D01*
X1175500Y643550D01*
X1175583Y643217D01*
X1175750Y642967D01*
X1176000Y642800D01*
X1176333Y642717D01*
X1176625Y642800D01*
X1176917Y643008D01*
X1177083Y643258D01*
X1177125Y643550D01*
X1177042Y643883D01*
X1176833Y644133D01*
X1176458Y644383D01*
G01X1178000Y647150D02*
X1175500D01*
X1177292Y645608D01*
Y647692D01*
G01X1169017Y735000D02*
Y737500D01*
X1170058D01*
X1170392Y737375D01*
X1170600Y737208D01*
X1170683Y736875D01*
X1170600Y736542D01*
X1170350Y736333D01*
X1170058Y736208D01*
X1169017D01*
G01X1170058D02*
X1170683Y735000D01*
G01X1172158Y736042D02*
X1172450Y736333D01*
X1172700Y736500D01*
X1173033Y736583D01*
X1173325Y736500D01*
X1173533Y736333D01*
X1173700Y736083D01*
X1173742Y735792D01*
X1173700Y735542D01*
X1173533Y735292D01*
X1173283Y735083D01*
X1172992Y735000D01*
X1172658Y735083D01*
X1172367Y735333D01*
X1172200Y735708D01*
X1172158Y736125D01*
X1172242Y736667D01*
X1172367Y736958D01*
X1172575Y737250D01*
X1172867Y737458D01*
X1173158Y737500D01*
X1173450Y737417D01*
X1173658Y737208D01*
G01X1176050Y735000D02*
Y737500D01*
X1175550Y737000D01*
G01Y735000D02*
X1176550D01*
G01X1178233Y735500D02*
X1178483Y735208D01*
X1178817Y735042D01*
X1179192Y735000D01*
X1179525Y735042D01*
X1179858Y735250D01*
X1180067Y735500D01*
X1180108Y735750D01*
X1180025Y736042D01*
X1179733Y736250D01*
X1179442Y736333D01*
X1179067D01*
G01X1179442D02*
X1179692Y736458D01*
X1179900Y736667D01*
X1179983Y736917D01*
X1179900Y737167D01*
X1179692Y737375D01*
X1179317Y737500D01*
X1178942Y737458D01*
X1178567Y737292D01*
G01X1174000Y759200D02*
X1170000D01*
Y751800D01*
G01X1182000Y761017D02*
X1179500D01*
Y762058D01*
X1179625Y762392D01*
X1179792Y762600D01*
X1180125Y762683D01*
X1180458Y762600D01*
X1180667Y762350D01*
X1180792Y762058D01*
Y761017D01*
G01Y762058D02*
X1182000Y762683D01*
G01X1181625Y764033D02*
X1181833Y764283D01*
X1181958Y764575D01*
X1182000Y764950D01*
X1181917Y765325D01*
X1181750Y765617D01*
X1181458Y765825D01*
X1181125Y765867D01*
X1180792Y765783D01*
X1180583Y765575D01*
X1180417Y765283D01*
X1180375Y764992D01*
X1180417Y764700D01*
X1180583Y764325D01*
X1179500Y764450D01*
Y765575D01*
G01X1182000Y768050D02*
X1181958Y768342D01*
X1181833Y768675D01*
X1181625Y768883D01*
X1181333Y768967D01*
X1181042Y768883D01*
X1180792Y768633D01*
X1180667Y768258D01*
Y767842D01*
X1180583Y767592D01*
X1180375Y767383D01*
X1180083Y767300D01*
X1179792Y767425D01*
X1179583Y767717D01*
X1179500Y768050D01*
X1179583Y768383D01*
X1179792Y768675D01*
X1180083Y768800D01*
X1180375Y768717D01*
X1180583Y768508D01*
X1180667Y768258D01*
Y767842D01*
X1180792Y767467D01*
X1181042Y767217D01*
X1181333Y767133D01*
X1181625Y767217D01*
X1181833Y767425D01*
X1181958Y767758D01*
X1182000Y768050D01*
G01X1181500Y770233D02*
X1181792Y770483D01*
X1181958Y770817D01*
X1182000Y771192D01*
X1181958Y771525D01*
X1181750Y771858D01*
X1181500Y772067D01*
X1181250Y772108D01*
X1180958Y772025D01*
X1180750Y771733D01*
X1180667Y771442D01*
Y771067D01*
G01Y771442D02*
X1180542Y771692D01*
X1180333Y771900D01*
X1180083Y771983D01*
X1179833Y771900D01*
X1179625Y771692D01*
X1179500Y771317D01*
X1179542Y770942D01*
X1179708Y770567D01*
G01X1182000Y759200D02*
X1178000D01*
Y751800D01*
G01X1186000Y761017D02*
X1183500D01*
Y762058D01*
X1183625Y762392D01*
X1183792Y762600D01*
X1184125Y762683D01*
X1184458Y762600D01*
X1184667Y762350D01*
X1184792Y762058D01*
Y761017D01*
G01Y762058D02*
X1186000Y762683D01*
G01X1185625Y764033D02*
X1185833Y764283D01*
X1185958Y764575D01*
X1186000Y764950D01*
X1185917Y765325D01*
X1185750Y765617D01*
X1185458Y765825D01*
X1185125Y765867D01*
X1184792Y765783D01*
X1184583Y765575D01*
X1184417Y765283D01*
X1184375Y764992D01*
X1184417Y764700D01*
X1184583Y764325D01*
X1183500Y764450D01*
Y765575D01*
G01X1186000Y768050D02*
X1185958Y768342D01*
X1185833Y768675D01*
X1185625Y768883D01*
X1185333Y768967D01*
X1185042Y768883D01*
X1184792Y768633D01*
X1184667Y768258D01*
Y767842D01*
X1184583Y767592D01*
X1184375Y767383D01*
X1184083Y767300D01*
X1183792Y767425D01*
X1183583Y767717D01*
X1183500Y768050D01*
X1183583Y768383D01*
X1183792Y768675D01*
X1184083Y768800D01*
X1184375Y768717D01*
X1184583Y768508D01*
X1184667Y768258D01*
Y767842D01*
X1184792Y767467D01*
X1185042Y767217D01*
X1185333Y767133D01*
X1185625Y767217D01*
X1185833Y767425D01*
X1185958Y767758D01*
X1186000Y768050D01*
G01Y771650D02*
X1183500D01*
X1185292Y770108D01*
Y772192D01*
G01X1186000Y759200D02*
X1182000D01*
Y751800D01*
G01X1178000Y761017D02*
X1175500D01*
Y762058D01*
X1175625Y762392D01*
X1175792Y762600D01*
X1176125Y762683D01*
X1176458Y762600D01*
X1176667Y762350D01*
X1176792Y762058D01*
Y761017D01*
G01Y762058D02*
X1178000Y762683D01*
G01X1176958Y764158D02*
X1176667Y764450D01*
X1176500Y764700D01*
X1176417Y765033D01*
X1176500Y765325D01*
X1176667Y765533D01*
X1176917Y765700D01*
X1177208Y765742D01*
X1177458Y765700D01*
X1177708Y765533D01*
X1177917Y765283D01*
X1178000Y764992D01*
X1177917Y764658D01*
X1177667Y764367D01*
X1177292Y764200D01*
X1176875Y764158D01*
X1176333Y764242D01*
X1176042Y764367D01*
X1175750Y764575D01*
X1175542Y764867D01*
X1175500Y765158D01*
X1175583Y765450D01*
X1175792Y765658D01*
G01X1178000Y768050D02*
X1175500D01*
X1176000Y767550D01*
G01X1178000D02*
Y768550D01*
G01Y771650D02*
X1175500D01*
X1177292Y770108D01*
Y772192D01*
G01X1178000Y759200D02*
X1174000D01*
Y751800D01*
G01X1180337Y783292D02*
X1180087Y783417D01*
X1179795Y783500D01*
X1179462D01*
X1179087Y783375D01*
X1178795Y783167D01*
X1178587Y782917D01*
X1178420Y782500D01*
X1178378Y782125D01*
X1178462Y781750D01*
X1178587Y781500D01*
X1178837Y781250D01*
X1179128Y781083D01*
X1179420Y781000D01*
X1179712D01*
X1180003Y781083D01*
X1180253Y781208D01*
X1180462Y781375D01*
G01X1181728Y783083D02*
X1181978Y783333D01*
X1182270Y783458D01*
X1182603Y783500D01*
X1183020Y783417D01*
X1183312Y783208D01*
X1183395Y782958D01*
X1183353Y782708D01*
X1183187Y782500D01*
X1182353Y782083D01*
X1181978Y781792D01*
X1181728Y781375D01*
X1181645Y781000D01*
X1183395D01*
G01X1185620Y783500D02*
X1185287Y783417D01*
X1185037Y783208D01*
X1184870Y782958D01*
X1184745Y782625D01*
X1184703Y782250D01*
X1184745Y781875D01*
X1184870Y781542D01*
X1185037Y781292D01*
X1185287Y781083D01*
X1185620Y781000D01*
X1185953Y781083D01*
X1186203Y781292D01*
X1186370Y781542D01*
X1186495Y781875D01*
X1186537Y782250D01*
X1186495Y782625D01*
X1186370Y782958D01*
X1186203Y783208D01*
X1185953Y783417D01*
X1185620Y783500D01*
G01X1188720D02*
X1188387Y783417D01*
X1188137Y783208D01*
X1187970Y782958D01*
X1187845Y782625D01*
X1187803Y782250D01*
X1187845Y781875D01*
X1187970Y781542D01*
X1188137Y781292D01*
X1188387Y781083D01*
X1188720Y781000D01*
X1189053Y781083D01*
X1189303Y781292D01*
X1189470Y781542D01*
X1189595Y781875D01*
X1189637Y782250D01*
X1189595Y782625D01*
X1189470Y782958D01*
X1189303Y783208D01*
X1189053Y783417D01*
X1188720Y783500D01*
G01X1174000Y826017D02*
X1171500D01*
Y827017D01*
X1171625Y827350D01*
X1171917Y827600D01*
X1172250Y827683D01*
X1172583Y827600D01*
X1172833Y827392D01*
X1172958Y827017D01*
Y826017D01*
G01X1174000Y829117D02*
X1171500D01*
Y830158D01*
X1171625Y830492D01*
X1171792Y830700D01*
X1172125Y830783D01*
X1172458Y830700D01*
X1172667Y830450D01*
X1172792Y830158D01*
Y829117D01*
G01Y830158D02*
X1174000Y830783D01*
G01Y832967D02*
X1173458Y833050D01*
X1173000Y833175D01*
X1172583Y833342D01*
X1172125Y833550D01*
X1171500Y833883D01*
Y832217D01*
G01X1174000Y836150D02*
X1173958Y836442D01*
X1173833Y836775D01*
X1173625Y836983D01*
X1173333Y837067D01*
X1173042Y836983D01*
X1172792Y836733D01*
X1172667Y836358D01*
Y835942D01*
X1172583Y835692D01*
X1172375Y835483D01*
X1172083Y835400D01*
X1171792Y835525D01*
X1171583Y835817D01*
X1171500Y836150D01*
X1171583Y836483D01*
X1171792Y836775D01*
X1172083Y836900D01*
X1172375Y836817D01*
X1172583Y836608D01*
X1172667Y836358D01*
Y835942D01*
X1172792Y835567D01*
X1173042Y835317D01*
X1173333Y835233D01*
X1173625Y835317D01*
X1173833Y835525D01*
X1173958Y835858D01*
X1174000Y836150D01*
G01X1184500Y822700D02*
X1176500D01*
Y840300D01*
X1184500D01*
Y822700D01*
G01X1178500Y872500D02*
Y858500D01*
G01D02*
X1191500D01*
G01X1176400Y862567D02*
X1173900D01*
Y863567D01*
X1174025Y863900D01*
X1174317Y864150D01*
X1174650Y864233D01*
X1174983Y864150D01*
X1175233Y863942D01*
X1175358Y863567D01*
Y862567D01*
G01X1176400Y866500D02*
X1176358Y866167D01*
X1176192Y865875D01*
X1175942Y865625D01*
X1175650Y865458D01*
X1175317Y865375D01*
X1174983D01*
X1174650Y865458D01*
X1174358Y865625D01*
X1174108Y865875D01*
X1173942Y866167D01*
X1173900Y866500D01*
X1173942Y866833D01*
X1174108Y867125D01*
X1174358Y867375D01*
X1174650Y867542D01*
X1174983Y867625D01*
X1175317D01*
X1175650Y867542D01*
X1175942Y867375D01*
X1176192Y867125D01*
X1176358Y866833D01*
X1176400Y866500D01*
G01X1175733Y866833D02*
X1176400Y867333D01*
G01Y869517D02*
X1175858Y869600D01*
X1175400Y869725D01*
X1174983Y869892D01*
X1174525Y870100D01*
X1173900Y870433D01*
Y868767D01*
G01X1191500Y872500D02*
X1178500D01*
G01X1196208Y218267D02*
X1196083Y218017D01*
X1196000Y217725D01*
Y217392D01*
X1196125Y217017D01*
X1196333Y216725D01*
X1196583Y216517D01*
X1197000Y216350D01*
X1197375Y216308D01*
X1197750Y216392D01*
X1198000Y216517D01*
X1198250Y216767D01*
X1198417Y217058D01*
X1198500Y217350D01*
Y217642D01*
X1198417Y217933D01*
X1198292Y218183D01*
X1198125Y218392D01*
G01X1196417Y219658D02*
X1196167Y219908D01*
X1196042Y220200D01*
X1196000Y220533D01*
X1196083Y220950D01*
X1196292Y221242D01*
X1196542Y221325D01*
X1196792Y221283D01*
X1197000Y221117D01*
X1197417Y220283D01*
X1197708Y219908D01*
X1198125Y219658D01*
X1198500Y219575D01*
Y221325D01*
G01Y223550D02*
X1198458Y223842D01*
X1198333Y224175D01*
X1198125Y224383D01*
X1197833Y224467D01*
X1197542Y224383D01*
X1197292Y224133D01*
X1197167Y223758D01*
Y223342D01*
X1197083Y223092D01*
X1196875Y222883D01*
X1196583Y222800D01*
X1196292Y222925D01*
X1196083Y223217D01*
X1196000Y223550D01*
X1196083Y223883D01*
X1196292Y224175D01*
X1196583Y224300D01*
X1196875Y224217D01*
X1197083Y224008D01*
X1197167Y223758D01*
Y223342D01*
X1197292Y222967D01*
X1197542Y222717D01*
X1197833Y222633D01*
X1198125Y222717D01*
X1198333Y222925D01*
X1198458Y223258D01*
X1198500Y223550D01*
G01Y226567D02*
X1197958Y226650D01*
X1197500Y226775D01*
X1197083Y226942D01*
X1196625Y227150D01*
X1196000Y227483D01*
Y225817D01*
G01X1197877Y236000D02*
Y240000D01*
X1190477D01*
G01X1197877Y240500D02*
Y244500D01*
X1190477D01*
G01X1197877Y245500D02*
Y249500D01*
X1190477D01*
G01X1197877Y250500D02*
Y254500D01*
X1190477D01*
G01X1197868Y262060D02*
Y266060D01*
X1190468D01*
G01X1197868Y266560D02*
Y270560D01*
X1190468D01*
G01X1187694Y272500D02*
Y275000D01*
X1188735D01*
X1189069Y274875D01*
X1189277Y274708D01*
X1189360Y274375D01*
X1189277Y274042D01*
X1189027Y273833D01*
X1188735Y273708D01*
X1187694D01*
G01X1188735D02*
X1189360Y272500D01*
G01X1190835Y274583D02*
X1191085Y274833D01*
X1191377Y274958D01*
X1191710Y275000D01*
X1192127Y274917D01*
X1192419Y274708D01*
X1192502Y274458D01*
X1192460Y274208D01*
X1192294Y274000D01*
X1191460Y273583D01*
X1191085Y273292D01*
X1190835Y272875D01*
X1190752Y272500D01*
X1192502D01*
G01X1194727Y275000D02*
X1194394Y274917D01*
X1194144Y274708D01*
X1193977Y274458D01*
X1193852Y274125D01*
X1193810Y273750D01*
X1193852Y273375D01*
X1193977Y273042D01*
X1194144Y272792D01*
X1194394Y272583D01*
X1194727Y272500D01*
X1195060Y272583D01*
X1195310Y272792D01*
X1195477Y273042D01*
X1195602Y273375D01*
X1195644Y273750D01*
X1195602Y274125D01*
X1195477Y274458D01*
X1195310Y274708D01*
X1195060Y274917D01*
X1194727Y275000D01*
G01X1196910Y272875D02*
X1197160Y272667D01*
X1197452Y272542D01*
X1197827Y272500D01*
X1198202Y272583D01*
X1198494Y272750D01*
X1198702Y273042D01*
X1198744Y273375D01*
X1198660Y273708D01*
X1198452Y273917D01*
X1198160Y274083D01*
X1197869Y274125D01*
X1197577Y274083D01*
X1197202Y273917D01*
X1197327Y275000D01*
X1198452D01*
G01X1187694Y277000D02*
Y279500D01*
X1188735D01*
X1189069Y279375D01*
X1189277Y279208D01*
X1189360Y278875D01*
X1189277Y278542D01*
X1189027Y278333D01*
X1188735Y278208D01*
X1187694D01*
G01X1188735D02*
X1189360Y277000D01*
G01X1190835Y279083D02*
X1191085Y279333D01*
X1191377Y279458D01*
X1191710Y279500D01*
X1192127Y279417D01*
X1192419Y279208D01*
X1192502Y278958D01*
X1192460Y278708D01*
X1192294Y278500D01*
X1191460Y278083D01*
X1191085Y277792D01*
X1190835Y277375D01*
X1190752Y277000D01*
X1192502D01*
G01X1194727Y279500D02*
X1194394Y279417D01*
X1194144Y279208D01*
X1193977Y278958D01*
X1193852Y278625D01*
X1193810Y278250D01*
X1193852Y277875D01*
X1193977Y277542D01*
X1194144Y277292D01*
X1194394Y277083D01*
X1194727Y277000D01*
X1195060Y277083D01*
X1195310Y277292D01*
X1195477Y277542D01*
X1195602Y277875D01*
X1195644Y278250D01*
X1195602Y278625D01*
X1195477Y278958D01*
X1195310Y279208D01*
X1195060Y279417D01*
X1194727Y279500D01*
G01X1197035Y278042D02*
X1197327Y278333D01*
X1197577Y278500D01*
X1197910Y278583D01*
X1198202Y278500D01*
X1198410Y278333D01*
X1198577Y278083D01*
X1198619Y277792D01*
X1198577Y277542D01*
X1198410Y277292D01*
X1198160Y277083D01*
X1197869Y277000D01*
X1197535Y277083D01*
X1197244Y277333D01*
X1197077Y277708D01*
X1197035Y278125D01*
X1197119Y278667D01*
X1197244Y278958D01*
X1197452Y279250D01*
X1197744Y279458D01*
X1198035Y279500D01*
X1198327Y279417D01*
X1198535Y279208D01*
G01X1187694Y282000D02*
Y284500D01*
X1188735D01*
X1189069Y284375D01*
X1189277Y284208D01*
X1189360Y283875D01*
X1189277Y283542D01*
X1189027Y283333D01*
X1188735Y283208D01*
X1187694D01*
G01X1188735D02*
X1189360Y282000D01*
G01X1190835Y284083D02*
X1191085Y284333D01*
X1191377Y284458D01*
X1191710Y284500D01*
X1192127Y284417D01*
X1192419Y284208D01*
X1192502Y283958D01*
X1192460Y283708D01*
X1192294Y283500D01*
X1191460Y283083D01*
X1191085Y282792D01*
X1190835Y282375D01*
X1190752Y282000D01*
X1192502D01*
G01X1194727D02*
Y284500D01*
X1194227Y284000D01*
G01Y282000D02*
X1195227D01*
G01X1196910Y282375D02*
X1197160Y282167D01*
X1197452Y282042D01*
X1197827Y282000D01*
X1198202Y282083D01*
X1198494Y282250D01*
X1198702Y282542D01*
X1198744Y282875D01*
X1198660Y283208D01*
X1198452Y283417D01*
X1198160Y283583D01*
X1197869Y283625D01*
X1197577Y283583D01*
X1197202Y283417D01*
X1197327Y284500D01*
X1198452D01*
G01X1187694Y287000D02*
Y289500D01*
X1188735D01*
X1189069Y289375D01*
X1189277Y289208D01*
X1189360Y288875D01*
X1189277Y288542D01*
X1189027Y288333D01*
X1188735Y288208D01*
X1187694D01*
G01X1188735D02*
X1189360Y287000D01*
G01X1190835Y289083D02*
X1191085Y289333D01*
X1191377Y289458D01*
X1191710Y289500D01*
X1192127Y289417D01*
X1192419Y289208D01*
X1192502Y288958D01*
X1192460Y288708D01*
X1192294Y288500D01*
X1191460Y288083D01*
X1191085Y287792D01*
X1190835Y287375D01*
X1190752Y287000D01*
X1192502D01*
G01X1193935Y289083D02*
X1194185Y289333D01*
X1194477Y289458D01*
X1194810Y289500D01*
X1195227Y289417D01*
X1195519Y289208D01*
X1195602Y288958D01*
X1195560Y288708D01*
X1195394Y288500D01*
X1194560Y288083D01*
X1194185Y287792D01*
X1193935Y287375D01*
X1193852Y287000D01*
X1195602D01*
G01X1197827Y289500D02*
X1197494Y289417D01*
X1197244Y289208D01*
X1197077Y288958D01*
X1196952Y288625D01*
X1196910Y288250D01*
X1196952Y287875D01*
X1197077Y287542D01*
X1197244Y287292D01*
X1197494Y287083D01*
X1197827Y287000D01*
X1198160Y287083D01*
X1198410Y287292D01*
X1198577Y287542D01*
X1198702Y287875D01*
X1198744Y288250D01*
X1198702Y288625D01*
X1198577Y288958D01*
X1198410Y289208D01*
X1198160Y289417D01*
X1197827Y289500D01*
G01X1190185Y294560D02*
Y297060D01*
X1191226D01*
X1191560Y296935D01*
X1191768Y296768D01*
X1191851Y296435D01*
X1191768Y296102D01*
X1191518Y295893D01*
X1191226Y295768D01*
X1190185D01*
G01X1191226D02*
X1191851Y294560D01*
G01X1193326Y296643D02*
X1193576Y296893D01*
X1193868Y297018D01*
X1194201Y297060D01*
X1194618Y296977D01*
X1194910Y296768D01*
X1194993Y296518D01*
X1194951Y296268D01*
X1194785Y296060D01*
X1193951Y295643D01*
X1193576Y295352D01*
X1193326Y294935D01*
X1193243Y294560D01*
X1194993D01*
G01X1197135D02*
X1197218Y295102D01*
X1197343Y295560D01*
X1197510Y295977D01*
X1197718Y296435D01*
X1198051Y297060D01*
X1196385D01*
G01X1200318D02*
X1199985Y296977D01*
X1199735Y296768D01*
X1199568Y296518D01*
X1199443Y296185D01*
X1199401Y295810D01*
X1199443Y295435D01*
X1199568Y295102D01*
X1199735Y294852D01*
X1199985Y294643D01*
X1200318Y294560D01*
X1200651Y294643D01*
X1200901Y294852D01*
X1201068Y295102D01*
X1201193Y295435D01*
X1201235Y295810D01*
X1201193Y296185D01*
X1201068Y296518D01*
X1200901Y296768D01*
X1200651Y296977D01*
X1200318Y297060D01*
G01X1190185Y299060D02*
Y301560D01*
X1191226D01*
X1191560Y301435D01*
X1191768Y301268D01*
X1191851Y300935D01*
X1191768Y300602D01*
X1191518Y300393D01*
X1191226Y300268D01*
X1190185D01*
G01X1191226D02*
X1191851Y299060D01*
G01X1193326Y301143D02*
X1193576Y301393D01*
X1193868Y301518D01*
X1194201Y301560D01*
X1194618Y301477D01*
X1194910Y301268D01*
X1194993Y301018D01*
X1194951Y300768D01*
X1194785Y300560D01*
X1193951Y300143D01*
X1193576Y299852D01*
X1193326Y299435D01*
X1193243Y299060D01*
X1194993D01*
G01X1197135D02*
X1197218Y299602D01*
X1197343Y300060D01*
X1197510Y300477D01*
X1197718Y300935D01*
X1198051Y301560D01*
X1196385D01*
G01X1200318Y299060D02*
Y301560D01*
X1199818Y301060D01*
G01Y299060D02*
X1200818D01*
G01X1191700Y357000D02*
Y361000D01*
X1184300D01*
G01X1191700Y361500D02*
Y365500D01*
X1184300D01*
G01X1196000Y377433D02*
X1197792D01*
X1198167Y377600D01*
X1198417Y377933D01*
X1198500Y378350D01*
X1198417Y378767D01*
X1198167Y379100D01*
X1197792Y379267D01*
X1196000D01*
G01X1198500Y381450D02*
X1196000D01*
X1196500Y380950D01*
G01X1198500D02*
Y381950D01*
G01X1198000Y383633D02*
X1198292Y383883D01*
X1198458Y384217D01*
X1198500Y384592D01*
X1198458Y384925D01*
X1198250Y385258D01*
X1198000Y385467D01*
X1197750Y385508D01*
X1197458Y385425D01*
X1197250Y385133D01*
X1197167Y384842D01*
Y384467D01*
G01Y384842D02*
X1197042Y385092D01*
X1196833Y385300D01*
X1196583Y385383D01*
X1196333Y385300D01*
X1196125Y385092D01*
X1196000Y384717D01*
X1196042Y384342D01*
X1196208Y383967D01*
G01X1198500Y388150D02*
X1196000D01*
X1197792Y386608D01*
Y388692D01*
G01X1197000Y398300D02*
X1201000D01*
Y405700D01*
G01X1193000D02*
X1189000D01*
Y398300D01*
G01X1197000Y405700D02*
X1193000D01*
Y398300D01*
G01X1185000D02*
X1189000D01*
Y405700D01*
G01X1199000Y408017D02*
X1196500D01*
Y409058D01*
X1196625Y409392D01*
X1196792Y409600D01*
X1197125Y409683D01*
X1197458Y409600D01*
X1197667Y409350D01*
X1197792Y409058D01*
Y408017D01*
G01Y409058D02*
X1199000Y409683D01*
G01Y411950D02*
X1196500D01*
X1197000Y411450D01*
G01X1199000D02*
Y412450D01*
G01X1197958Y414258D02*
X1197667Y414550D01*
X1197500Y414800D01*
X1197417Y415133D01*
X1197500Y415425D01*
X1197667Y415633D01*
X1197917Y415800D01*
X1198208Y415842D01*
X1198458Y415800D01*
X1198708Y415633D01*
X1198917Y415383D01*
X1199000Y415092D01*
X1198917Y414758D01*
X1198667Y414467D01*
X1198292Y414300D01*
X1197875Y414258D01*
X1197333Y414342D01*
X1197042Y414467D01*
X1196750Y414675D01*
X1196542Y414967D01*
X1196500Y415258D01*
X1196583Y415550D01*
X1196792Y415758D01*
G01X1199000Y418150D02*
X1196500D01*
X1197000Y417650D01*
G01X1199000D02*
Y418650D01*
G01X1195000Y408017D02*
X1192500D01*
Y409058D01*
X1192625Y409392D01*
X1192792Y409600D01*
X1193125Y409683D01*
X1193458Y409600D01*
X1193667Y409350D01*
X1193792Y409058D01*
Y408017D01*
G01Y409058D02*
X1195000Y409683D01*
G01Y411950D02*
X1192500D01*
X1193000Y411450D01*
G01X1195000D02*
Y412450D01*
G01X1193958Y414258D02*
X1193667Y414550D01*
X1193500Y414800D01*
X1193417Y415133D01*
X1193500Y415425D01*
X1193667Y415633D01*
X1193917Y415800D01*
X1194208Y415842D01*
X1194458Y415800D01*
X1194708Y415633D01*
X1194917Y415383D01*
X1195000Y415092D01*
X1194917Y414758D01*
X1194667Y414467D01*
X1194292Y414300D01*
X1193875Y414258D01*
X1193333Y414342D01*
X1193042Y414467D01*
X1192750Y414675D01*
X1192542Y414967D01*
X1192500Y415258D01*
X1192583Y415550D01*
X1192792Y415758D01*
G01X1194625Y417233D02*
X1194833Y417483D01*
X1194958Y417775D01*
X1195000Y418150D01*
X1194917Y418525D01*
X1194750Y418817D01*
X1194458Y419025D01*
X1194125Y419067D01*
X1193792Y418983D01*
X1193583Y418775D01*
X1193417Y418483D01*
X1193375Y418192D01*
X1193417Y417900D01*
X1193583Y417525D01*
X1192500Y417650D01*
Y418775D01*
G01X1187000Y408017D02*
X1184500D01*
Y409058D01*
X1184625Y409392D01*
X1184792Y409600D01*
X1185125Y409683D01*
X1185458Y409600D01*
X1185667Y409350D01*
X1185792Y409058D01*
Y408017D01*
G01Y409058D02*
X1187000Y409683D01*
G01X1186625Y411033D02*
X1186833Y411283D01*
X1186958Y411575D01*
X1187000Y411950D01*
X1186917Y412325D01*
X1186750Y412617D01*
X1186458Y412825D01*
X1186125Y412867D01*
X1185792Y412783D01*
X1185583Y412575D01*
X1185417Y412283D01*
X1185375Y411992D01*
X1185417Y411700D01*
X1185583Y411325D01*
X1184500Y411450D01*
Y412575D01*
G01X1187000Y415050D02*
X1186958Y415342D01*
X1186833Y415675D01*
X1186625Y415883D01*
X1186333Y415967D01*
X1186042Y415883D01*
X1185792Y415633D01*
X1185667Y415258D01*
Y414842D01*
X1185583Y414592D01*
X1185375Y414383D01*
X1185083Y414300D01*
X1184792Y414425D01*
X1184583Y414717D01*
X1184500Y415050D01*
X1184583Y415383D01*
X1184792Y415675D01*
X1185083Y415800D01*
X1185375Y415717D01*
X1185583Y415508D01*
X1185667Y415258D01*
Y414842D01*
X1185792Y414467D01*
X1186042Y414217D01*
X1186333Y414133D01*
X1186625Y414217D01*
X1186833Y414425D01*
X1186958Y414758D01*
X1187000Y415050D01*
G01X1186708Y417442D02*
X1186917Y417733D01*
X1187000Y418067D01*
X1186917Y418400D01*
X1186667Y418692D01*
X1186292Y418900D01*
X1185917Y418983D01*
X1185458D01*
X1185083Y418900D01*
X1184750Y418692D01*
X1184583Y418442D01*
X1184500Y418150D01*
X1184583Y417817D01*
X1184750Y417567D01*
X1185000Y417400D01*
X1185333Y417317D01*
X1185625Y417400D01*
X1185917Y417608D01*
X1186083Y417858D01*
X1186125Y418150D01*
X1186042Y418483D01*
X1185833Y418733D01*
X1185458Y418983D01*
G01X1191000Y408017D02*
X1188500D01*
Y409058D01*
X1188625Y409392D01*
X1188792Y409600D01*
X1189125Y409683D01*
X1189458Y409600D01*
X1189667Y409350D01*
X1189792Y409058D01*
Y408017D01*
G01Y409058D02*
X1191000Y409683D01*
G01X1190625Y411033D02*
X1190833Y411283D01*
X1190958Y411575D01*
X1191000Y411950D01*
X1190917Y412325D01*
X1190750Y412617D01*
X1190458Y412825D01*
X1190125Y412867D01*
X1189792Y412783D01*
X1189583Y412575D01*
X1189417Y412283D01*
X1189375Y411992D01*
X1189417Y411700D01*
X1189583Y411325D01*
X1188500Y411450D01*
Y412575D01*
G01X1190708Y414342D02*
X1190917Y414633D01*
X1191000Y414967D01*
X1190917Y415300D01*
X1190667Y415592D01*
X1190292Y415800D01*
X1189917Y415883D01*
X1189458D01*
X1189083Y415800D01*
X1188750Y415592D01*
X1188583Y415342D01*
X1188500Y415050D01*
X1188583Y414717D01*
X1188750Y414467D01*
X1189000Y414300D01*
X1189333Y414217D01*
X1189625Y414300D01*
X1189917Y414508D01*
X1190083Y414758D01*
X1190125Y415050D01*
X1190042Y415383D01*
X1189833Y415633D01*
X1189458Y415883D01*
G01X1188500Y418150D02*
X1188583Y417817D01*
X1188792Y417567D01*
X1189042Y417400D01*
X1189375Y417275D01*
X1189750Y417233D01*
X1190125Y417275D01*
X1190458Y417400D01*
X1190708Y417567D01*
X1190917Y417817D01*
X1191000Y418150D01*
X1190917Y418483D01*
X1190708Y418733D01*
X1190458Y418900D01*
X1190125Y419025D01*
X1189750Y419067D01*
X1189375Y419025D01*
X1189042Y418900D01*
X1188792Y418733D01*
X1188583Y418483D01*
X1188500Y418150D01*
G01X1191017Y431500D02*
Y434000D01*
X1192017D01*
X1192350Y433875D01*
X1192600Y433583D01*
X1192683Y433250D01*
X1192600Y432917D01*
X1192392Y432667D01*
X1192017Y432542D01*
X1191017D01*
G01X1194117Y431500D02*
Y434000D01*
X1195158D01*
X1195492Y433875D01*
X1195700Y433708D01*
X1195783Y433375D01*
X1195700Y433042D01*
X1195450Y432833D01*
X1195158Y432708D01*
X1194117D01*
G01X1195158D02*
X1195783Y431500D01*
G01X1197133Y432000D02*
X1197383Y431708D01*
X1197717Y431542D01*
X1198092Y431500D01*
X1198425Y431542D01*
X1198758Y431750D01*
X1198967Y432000D01*
X1199008Y432250D01*
X1198925Y432542D01*
X1198633Y432750D01*
X1198342Y432833D01*
X1197967D01*
G01X1198342D02*
X1198592Y432958D01*
X1198800Y433167D01*
X1198883Y433417D01*
X1198800Y433667D01*
X1198592Y433875D01*
X1198217Y434000D01*
X1197842Y433958D01*
X1197467Y433792D01*
G01X1201650Y431500D02*
Y434000D01*
X1200108Y432208D01*
X1202192D01*
G01X1186367Y433792D02*
X1186117Y433917D01*
X1185825Y434000D01*
X1185492D01*
X1185117Y433875D01*
X1184825Y433667D01*
X1184617Y433417D01*
X1184450Y433000D01*
X1184408Y432625D01*
X1184492Y432250D01*
X1184617Y432000D01*
X1184867Y431750D01*
X1185158Y431583D01*
X1185450Y431500D01*
X1185742D01*
X1186033Y431583D01*
X1186283Y431708D01*
X1186492Y431875D01*
G01X1187633D02*
X1187883Y431667D01*
X1188175Y431542D01*
X1188550Y431500D01*
X1188925Y431583D01*
X1189217Y431750D01*
X1189425Y432042D01*
X1189467Y432375D01*
X1189383Y432708D01*
X1189175Y432917D01*
X1188883Y433083D01*
X1188592Y433125D01*
X1188300Y433083D01*
X1187925Y432917D01*
X1188050Y434000D01*
X1189175D01*
G01X1189517Y450500D02*
Y453000D01*
X1190517D01*
X1190850Y452875D01*
X1191100Y452583D01*
X1191183Y452250D01*
X1191100Y451917D01*
X1190892Y451667D01*
X1190517Y451542D01*
X1189517D01*
G01X1192617Y450500D02*
Y453000D01*
X1193658D01*
X1193992Y452875D01*
X1194200Y452708D01*
X1194283Y452375D01*
X1194200Y452042D01*
X1193950Y451833D01*
X1193658Y451708D01*
X1192617D01*
G01X1193658D02*
X1194283Y450500D01*
G01X1195758Y452583D02*
X1196008Y452833D01*
X1196300Y452958D01*
X1196633Y453000D01*
X1197050Y452917D01*
X1197342Y452708D01*
X1197425Y452458D01*
X1197383Y452208D01*
X1197217Y452000D01*
X1196383Y451583D01*
X1196008Y451292D01*
X1195758Y450875D01*
X1195675Y450500D01*
X1197425D01*
G01X1199650D02*
Y453000D01*
X1199150Y452500D01*
G01Y450500D02*
X1200150D01*
G01X1190000Y579575D02*
X1187500Y581325D01*
G01Y579575D02*
X1190000Y581325D01*
G01Y583550D02*
X1187500D01*
X1188000Y583050D01*
G01X1190000D02*
Y584050D01*
G01X1196000Y579525D02*
X1193500Y581275D01*
G01Y579525D02*
X1196000Y581275D01*
G01Y583500D02*
X1193500D01*
X1194000Y583000D01*
G01X1196000D02*
Y584000D01*
G01X1193500Y586600D02*
X1193583Y586267D01*
X1193792Y586017D01*
X1194042Y585850D01*
X1194375Y585725D01*
X1194750Y585683D01*
X1195125Y585725D01*
X1195458Y585850D01*
X1195708Y586017D01*
X1195917Y586267D01*
X1196000Y586600D01*
X1195917Y586933D01*
X1195708Y587183D01*
X1195458Y587350D01*
X1195125Y587475D01*
X1194750Y587517D01*
X1194375Y587475D01*
X1194042Y587350D01*
X1193792Y587183D01*
X1193583Y586933D01*
X1193500Y586600D01*
G01X1225300Y572040D02*
X1198900D01*
G01D02*
Y601640D01*
G01X1193000Y593517D02*
X1190500D01*
Y594558D01*
X1190625Y594892D01*
X1190792Y595100D01*
X1191125Y595183D01*
X1191458Y595100D01*
X1191667Y594850D01*
X1191792Y594558D01*
Y593517D01*
G01Y594558D02*
X1193000Y595183D01*
G01X1192625Y596533D02*
X1192833Y596783D01*
X1192958Y597075D01*
X1193000Y597450D01*
X1192917Y597825D01*
X1192750Y598117D01*
X1192458Y598325D01*
X1192125Y598367D01*
X1191792Y598283D01*
X1191583Y598075D01*
X1191417Y597783D01*
X1191375Y597492D01*
X1191417Y597200D01*
X1191583Y596825D01*
X1190500Y596950D01*
Y598075D01*
G01X1190917Y599758D02*
X1190667Y600008D01*
X1190542Y600300D01*
X1190500Y600633D01*
X1190583Y601050D01*
X1190792Y601342D01*
X1191042Y601425D01*
X1191292Y601383D01*
X1191500Y601217D01*
X1191917Y600383D01*
X1192208Y600008D01*
X1192625Y599758D01*
X1193000Y599675D01*
Y601425D01*
G01Y603650D02*
X1192958Y603942D01*
X1192833Y604275D01*
X1192625Y604483D01*
X1192333Y604567D01*
X1192042Y604483D01*
X1191792Y604233D01*
X1191667Y603858D01*
Y603442D01*
X1191583Y603192D01*
X1191375Y602983D01*
X1191083Y602900D01*
X1190792Y603025D01*
X1190583Y603317D01*
X1190500Y603650D01*
X1190583Y603983D01*
X1190792Y604275D01*
X1191083Y604400D01*
X1191375Y604317D01*
X1191583Y604108D01*
X1191667Y603858D01*
Y603442D01*
X1191792Y603067D01*
X1192042Y602817D01*
X1192333Y602733D01*
X1192625Y602817D01*
X1192833Y603025D01*
X1192958Y603358D01*
X1193000Y603650D01*
G01X1184500Y595300D02*
X1188500D01*
Y602700D01*
G01X1198900Y601640D02*
X1225300D01*
G01X1192500Y609300D02*
X1195000D01*
G01X1192500Y608342D02*
Y610258D01*
G01X1195000Y611567D02*
X1192500D01*
Y612567D01*
X1192625Y612900D01*
X1192917Y613150D01*
X1193250Y613233D01*
X1193583Y613150D01*
X1193833Y612942D01*
X1193958Y612567D01*
Y611567D01*
G01X1195000Y615500D02*
X1192500D01*
X1193000Y615000D01*
G01X1195000D02*
Y616000D01*
G01X1194625Y617683D02*
X1194833Y617933D01*
X1194958Y618225D01*
X1195000Y618600D01*
X1194917Y618975D01*
X1194750Y619267D01*
X1194458Y619475D01*
X1194125Y619517D01*
X1193792Y619433D01*
X1193583Y619225D01*
X1193417Y618933D01*
X1193375Y618642D01*
X1193417Y618350D01*
X1193583Y617975D01*
X1192500Y618100D01*
Y619225D01*
G01X1195000Y621700D02*
X1194958Y621992D01*
X1194833Y622325D01*
X1194625Y622533D01*
X1194333Y622617D01*
X1194042Y622533D01*
X1193792Y622283D01*
X1193667Y621908D01*
Y621492D01*
X1193583Y621242D01*
X1193375Y621033D01*
X1193083Y620950D01*
X1192792Y621075D01*
X1192583Y621367D01*
X1192500Y621700D01*
X1192583Y622033D01*
X1192792Y622325D01*
X1193083Y622450D01*
X1193375Y622367D01*
X1193583Y622158D01*
X1193667Y621908D01*
Y621492D01*
X1193792Y621117D01*
X1194042Y620867D01*
X1194333Y620783D01*
X1194625Y620867D01*
X1194833Y621075D01*
X1194958Y621408D01*
X1195000Y621700D01*
G01X1189000Y611017D02*
X1186500D01*
Y612058D01*
X1186625Y612392D01*
X1186792Y612600D01*
X1187125Y612683D01*
X1187458Y612600D01*
X1187667Y612350D01*
X1187792Y612058D01*
Y611017D01*
G01Y612058D02*
X1189000Y612683D01*
G01X1187958Y614158D02*
X1187667Y614450D01*
X1187500Y614700D01*
X1187417Y615033D01*
X1187500Y615325D01*
X1187667Y615533D01*
X1187917Y615700D01*
X1188208Y615742D01*
X1188458Y615700D01*
X1188708Y615533D01*
X1188917Y615283D01*
X1189000Y614992D01*
X1188917Y614658D01*
X1188667Y614367D01*
X1188292Y614200D01*
X1187875Y614158D01*
X1187333Y614242D01*
X1187042Y614367D01*
X1186750Y614575D01*
X1186542Y614867D01*
X1186500Y615158D01*
X1186583Y615450D01*
X1186792Y615658D01*
G01X1189000Y617967D02*
X1188458Y618050D01*
X1188000Y618175D01*
X1187583Y618342D01*
X1187125Y618550D01*
X1186500Y618883D01*
Y617217D01*
G01X1186917Y620358D02*
X1186667Y620608D01*
X1186542Y620900D01*
X1186500Y621233D01*
X1186583Y621650D01*
X1186792Y621942D01*
X1187042Y622025D01*
X1187292Y621983D01*
X1187500Y621817D01*
X1187917Y620983D01*
X1188208Y620608D01*
X1188625Y620358D01*
X1189000Y620275D01*
Y622025D01*
G01X1202000Y615017D02*
X1199500D01*
Y616058D01*
X1199625Y616392D01*
X1199792Y616600D01*
X1200125Y616683D01*
X1200458Y616600D01*
X1200667Y616350D01*
X1200792Y616058D01*
Y615017D01*
G01Y616058D02*
X1202000Y616683D01*
G01X1201625Y618033D02*
X1201833Y618283D01*
X1201958Y618575D01*
X1202000Y618950D01*
X1201917Y619325D01*
X1201750Y619617D01*
X1201458Y619825D01*
X1201125Y619867D01*
X1200792Y619783D01*
X1200583Y619575D01*
X1200417Y619283D01*
X1200375Y618992D01*
X1200417Y618700D01*
X1200583Y618325D01*
X1199500Y618450D01*
Y619575D01*
G01X1200958Y621258D02*
X1200667Y621550D01*
X1200500Y621800D01*
X1200417Y622133D01*
X1200500Y622425D01*
X1200667Y622633D01*
X1200917Y622800D01*
X1201208Y622842D01*
X1201458Y622800D01*
X1201708Y622633D01*
X1201917Y622383D01*
X1202000Y622092D01*
X1201917Y621758D01*
X1201667Y621467D01*
X1201292Y621300D01*
X1200875Y621258D01*
X1200333Y621342D01*
X1200042Y621467D01*
X1199750Y621675D01*
X1199542Y621967D01*
X1199500Y622258D01*
X1199583Y622550D01*
X1199792Y622758D01*
G01X1199917Y624358D02*
X1199667Y624608D01*
X1199542Y624900D01*
X1199500Y625233D01*
X1199583Y625650D01*
X1199792Y625942D01*
X1200042Y626025D01*
X1200292Y625983D01*
X1200500Y625817D01*
X1200917Y624983D01*
X1201208Y624608D01*
X1201625Y624358D01*
X1202000Y624275D01*
Y626025D01*
G01X1205700Y603500D02*
Y607500D01*
X1198300D01*
G01X1203000Y636200D02*
X1199000D01*
Y628800D01*
G01X1197500Y640850D02*
X1200000D01*
G01X1197500Y639892D02*
Y641808D01*
G01X1200000Y643117D02*
X1197500D01*
Y644117D01*
X1197625Y644450D01*
X1197917Y644700D01*
X1198250Y644783D01*
X1198583Y644700D01*
X1198833Y644492D01*
X1198958Y644117D01*
Y643117D01*
G01X1199708Y646342D02*
X1199917Y646633D01*
X1200000Y646967D01*
X1199917Y647300D01*
X1199667Y647592D01*
X1199292Y647800D01*
X1198917Y647883D01*
X1198458D01*
X1198083Y647800D01*
X1197750Y647592D01*
X1197583Y647342D01*
X1197500Y647050D01*
X1197583Y646717D01*
X1197750Y646467D01*
X1198000Y646300D01*
X1198333Y646217D01*
X1198625Y646300D01*
X1198917Y646508D01*
X1199083Y646758D01*
X1199125Y647050D01*
X1199042Y647383D01*
X1198833Y647633D01*
X1198458Y647883D01*
G01X1200000Y650150D02*
X1197500D01*
X1198000Y649650D01*
G01X1200000D02*
Y650650D01*
G01X1189000Y639350D02*
X1191500D01*
G01X1189000Y638392D02*
Y640308D01*
G01X1191500Y641617D02*
X1189000D01*
Y642617D01*
X1189125Y642950D01*
X1189417Y643200D01*
X1189750Y643283D01*
X1190083Y643200D01*
X1190333Y642992D01*
X1190458Y642617D01*
Y641617D01*
G01X1191208Y644842D02*
X1191417Y645133D01*
X1191500Y645467D01*
X1191417Y645800D01*
X1191167Y646092D01*
X1190792Y646300D01*
X1190417Y646383D01*
X1189958D01*
X1189583Y646300D01*
X1189250Y646092D01*
X1189083Y645842D01*
X1189000Y645550D01*
X1189083Y645217D01*
X1189250Y644967D01*
X1189500Y644800D01*
X1189833Y644717D01*
X1190125Y644800D01*
X1190417Y645008D01*
X1190583Y645258D01*
X1190625Y645550D01*
X1190542Y645883D01*
X1190333Y646133D01*
X1189958Y646383D01*
G01X1191125Y647733D02*
X1191333Y647983D01*
X1191458Y648275D01*
X1191500Y648650D01*
X1191417Y649025D01*
X1191250Y649317D01*
X1190958Y649525D01*
X1190625Y649567D01*
X1190292Y649483D01*
X1190083Y649275D01*
X1189917Y648983D01*
X1189875Y648692D01*
X1189917Y648400D01*
X1190083Y648025D01*
X1189000Y648150D01*
Y649275D01*
G01X1199000Y670983D02*
X1200792D01*
X1201167Y671150D01*
X1201417Y671483D01*
X1201500Y671900D01*
X1201417Y672317D01*
X1201167Y672650D01*
X1200792Y672817D01*
X1199000D01*
G01X1201500Y675500D02*
X1199000D01*
X1200792Y673958D01*
Y676042D01*
G01X1199000Y678100D02*
X1199083Y677767D01*
X1199292Y677517D01*
X1199542Y677350D01*
X1199875Y677225D01*
X1200250Y677183D01*
X1200625Y677225D01*
X1200958Y677350D01*
X1201208Y677517D01*
X1201417Y677767D01*
X1201500Y678100D01*
X1201417Y678433D01*
X1201208Y678683D01*
X1200958Y678850D01*
X1200625Y678975D01*
X1200250Y679017D01*
X1199875Y678975D01*
X1199542Y678850D01*
X1199292Y678683D01*
X1199083Y678433D01*
X1199000Y678100D01*
G01X1197000Y693300D02*
X1199500D01*
G01X1197000Y692342D02*
Y694258D01*
G01X1199500Y695567D02*
X1197000D01*
Y696567D01*
X1197125Y696900D01*
X1197417Y697150D01*
X1197750Y697233D01*
X1198083Y697150D01*
X1198333Y696942D01*
X1198458Y696567D01*
Y695567D01*
G01X1199500Y699500D02*
X1197000D01*
X1197500Y699000D01*
G01X1199500D02*
Y700000D01*
G01Y702517D02*
X1198958Y702600D01*
X1198500Y702725D01*
X1198083Y702892D01*
X1197625Y703100D01*
X1197000Y703433D01*
Y701767D01*
G01X1198458Y704908D02*
X1198167Y705200D01*
X1198000Y705450D01*
X1197917Y705783D01*
X1198000Y706075D01*
X1198167Y706283D01*
X1198417Y706450D01*
X1198708Y706492D01*
X1198958Y706450D01*
X1199208Y706283D01*
X1199417Y706033D01*
X1199500Y705742D01*
X1199417Y705408D01*
X1199167Y705117D01*
X1198792Y704950D01*
X1198375Y704908D01*
X1197833Y704992D01*
X1197542Y705117D01*
X1197250Y705325D01*
X1197042Y705617D01*
X1197000Y705908D01*
X1197083Y706200D01*
X1197292Y706408D01*
G01X1196500Y716800D02*
X1199000D01*
G01X1196500Y715842D02*
Y717758D01*
G01X1199000Y719067D02*
X1196500D01*
Y720067D01*
X1196625Y720400D01*
X1196917Y720650D01*
X1197250Y720733D01*
X1197583Y720650D01*
X1197833Y720442D01*
X1197958Y720067D01*
Y719067D01*
G01X1199000Y723000D02*
X1196500D01*
X1197000Y722500D01*
G01X1199000D02*
Y723500D01*
G01Y726100D02*
X1196500D01*
X1197000Y725600D01*
G01X1199000D02*
Y726600D01*
G01Y729700D02*
X1196500D01*
X1198292Y728158D01*
Y730242D01*
G01X1188300Y737000D02*
Y734500D01*
G01X1187342Y737000D02*
X1189258D01*
G01X1190567Y734500D02*
Y737000D01*
X1191567D01*
X1191900Y736875D01*
X1192150Y736583D01*
X1192233Y736250D01*
X1192150Y735917D01*
X1191942Y735667D01*
X1191567Y735542D01*
X1190567D01*
G01X1194500Y734500D02*
Y737000D01*
X1194000Y736500D01*
G01Y734500D02*
X1195000D01*
G01X1197600D02*
Y737000D01*
X1197100Y736500D01*
G01Y734500D02*
X1198100D01*
G01X1199783Y735000D02*
X1200033Y734708D01*
X1200367Y734542D01*
X1200742Y734500D01*
X1201075Y734542D01*
X1201408Y734750D01*
X1201617Y735000D01*
X1201658Y735250D01*
X1201575Y735542D01*
X1201283Y735750D01*
X1200992Y735833D01*
X1200617D01*
G01X1200992D02*
X1201242Y735958D01*
X1201450Y736167D01*
X1201533Y736417D01*
X1201450Y736667D01*
X1201242Y736875D01*
X1200867Y737000D01*
X1200492Y736958D01*
X1200117Y736792D01*
G01X1191000Y747700D02*
X1187000D01*
Y740300D01*
G01X1193517Y739000D02*
Y741500D01*
X1194558D01*
X1194892Y741375D01*
X1195100Y741208D01*
X1195183Y740875D01*
X1195100Y740542D01*
X1194850Y740333D01*
X1194558Y740208D01*
X1193517D01*
G01X1194558D02*
X1195183Y739000D01*
G01X1196658Y741083D02*
X1196908Y741333D01*
X1197200Y741458D01*
X1197533Y741500D01*
X1197950Y741417D01*
X1198242Y741208D01*
X1198325Y740958D01*
X1198283Y740708D01*
X1198117Y740500D01*
X1197283Y740083D01*
X1196908Y739792D01*
X1196658Y739375D01*
X1196575Y739000D01*
X1198325D01*
G01X1199758Y741083D02*
X1200008Y741333D01*
X1200300Y741458D01*
X1200633Y741500D01*
X1201050Y741417D01*
X1201342Y741208D01*
X1201425Y740958D01*
X1201383Y740708D01*
X1201217Y740500D01*
X1200383Y740083D01*
X1200008Y739792D01*
X1199758Y739375D01*
X1199675Y739000D01*
X1201425D01*
G01X1202858Y740042D02*
X1203150Y740333D01*
X1203400Y740500D01*
X1203733Y740583D01*
X1204025Y740500D01*
X1204233Y740333D01*
X1204400Y740083D01*
X1204442Y739792D01*
X1204400Y739542D01*
X1204233Y739292D01*
X1203983Y739083D01*
X1203692Y739000D01*
X1203358Y739083D01*
X1203067Y739333D01*
X1202900Y739708D01*
X1202858Y740125D01*
X1202942Y740667D01*
X1203067Y740958D01*
X1203275Y741250D01*
X1203567Y741458D01*
X1203858Y741500D01*
X1204150Y741417D01*
X1204358Y741208D01*
G01X1196817Y745292D02*
X1196567Y745417D01*
X1196275Y745500D01*
X1195942D01*
X1195567Y745375D01*
X1195275Y745167D01*
X1195067Y744917D01*
X1194900Y744500D01*
X1194858Y744125D01*
X1194942Y743750D01*
X1195067Y743500D01*
X1195317Y743250D01*
X1195608Y743083D01*
X1195900Y743000D01*
X1196192D01*
X1196483Y743083D01*
X1196733Y743208D01*
X1196942Y743375D01*
G01X1199000Y743000D02*
X1199292Y743042D01*
X1199625Y743167D01*
X1199833Y743375D01*
X1199917Y743667D01*
X1199833Y743958D01*
X1199583Y744208D01*
X1199208Y744333D01*
X1198792D01*
X1198542Y744417D01*
X1198333Y744625D01*
X1198250Y744917D01*
X1198375Y745208D01*
X1198667Y745417D01*
X1199000Y745500D01*
X1199333Y745417D01*
X1199625Y745208D01*
X1199750Y744917D01*
X1199667Y744625D01*
X1199458Y744417D01*
X1199208Y744333D01*
X1198792D01*
X1198417Y744208D01*
X1198167Y743958D01*
X1198083Y743667D01*
X1198167Y743375D01*
X1198375Y743167D01*
X1198708Y743042D01*
X1199000Y743000D01*
G01X1201392Y743292D02*
X1201683Y743083D01*
X1202017Y743000D01*
X1202350Y743083D01*
X1202642Y743333D01*
X1202850Y743708D01*
X1202933Y744083D01*
Y744542D01*
X1202850Y744917D01*
X1202642Y745250D01*
X1202392Y745417D01*
X1202100Y745500D01*
X1201767Y745417D01*
X1201517Y745250D01*
X1201350Y745000D01*
X1201267Y744667D01*
X1201350Y744375D01*
X1201558Y744083D01*
X1201808Y743917D01*
X1202100Y743875D01*
X1202433Y743958D01*
X1202683Y744167D01*
X1202933Y744542D01*
G01X1203968Y766484D02*
X1199968D01*
Y759084D01*
G01X1194000Y761017D02*
X1191500D01*
Y762058D01*
X1191625Y762392D01*
X1191792Y762600D01*
X1192125Y762683D01*
X1192458Y762600D01*
X1192667Y762350D01*
X1192792Y762058D01*
Y761017D01*
G01Y762058D02*
X1194000Y762683D01*
G01Y764950D02*
X1191500D01*
X1192000Y764450D01*
G01X1194000D02*
Y765450D01*
G01Y767967D02*
X1193458Y768050D01*
X1193000Y768175D01*
X1192583Y768342D01*
X1192125Y768550D01*
X1191500Y768883D01*
Y767217D01*
G01X1193500Y770233D02*
X1193792Y770483D01*
X1193958Y770817D01*
X1194000Y771192D01*
X1193958Y771525D01*
X1193750Y771858D01*
X1193500Y772067D01*
X1193250Y772108D01*
X1192958Y772025D01*
X1192750Y771733D01*
X1192667Y771442D01*
Y771067D01*
G01Y771442D02*
X1192542Y771692D01*
X1192333Y771900D01*
X1192083Y771983D01*
X1191833Y771900D01*
X1191625Y771692D01*
X1191500Y771317D01*
X1191542Y770942D01*
X1191708Y770567D01*
G01X1194000Y759200D02*
X1190000D01*
Y751800D01*
G01X1195208Y748817D02*
X1195083Y748567D01*
X1195000Y748275D01*
Y747942D01*
X1195125Y747567D01*
X1195333Y747275D01*
X1195583Y747067D01*
X1196000Y746900D01*
X1196375Y746858D01*
X1196750Y746942D01*
X1197000Y747067D01*
X1197250Y747317D01*
X1197417Y747608D01*
X1197500Y747900D01*
Y748192D01*
X1197417Y748483D01*
X1197292Y748733D01*
X1197125Y748942D01*
G01X1197500Y751000D02*
X1197458Y751292D01*
X1197333Y751625D01*
X1197125Y751833D01*
X1196833Y751917D01*
X1196542Y751833D01*
X1196292Y751583D01*
X1196167Y751208D01*
Y750792D01*
X1196083Y750542D01*
X1195875Y750333D01*
X1195583Y750250D01*
X1195292Y750375D01*
X1195083Y750667D01*
X1195000Y751000D01*
X1195083Y751333D01*
X1195292Y751625D01*
X1195583Y751750D01*
X1195875Y751667D01*
X1196083Y751458D01*
X1196167Y751208D01*
Y750792D01*
X1196292Y750417D01*
X1196542Y750167D01*
X1196833Y750083D01*
X1197125Y750167D01*
X1197333Y750375D01*
X1197458Y750708D01*
X1197500Y751000D01*
G01X1197125Y753183D02*
X1197333Y753433D01*
X1197458Y753725D01*
X1197500Y754100D01*
X1197417Y754475D01*
X1197250Y754767D01*
X1196958Y754975D01*
X1196625Y755017D01*
X1196292Y754933D01*
X1196083Y754725D01*
X1195917Y754433D01*
X1195875Y754142D01*
X1195917Y753850D01*
X1196083Y753475D01*
X1195000Y753600D01*
Y754725D01*
G01X1187708Y762767D02*
X1187583Y762517D01*
X1187500Y762225D01*
Y761892D01*
X1187625Y761517D01*
X1187833Y761225D01*
X1188083Y761017D01*
X1188500Y760850D01*
X1188875Y760808D01*
X1189250Y760892D01*
X1189500Y761017D01*
X1189750Y761267D01*
X1189917Y761558D01*
X1190000Y761850D01*
Y762142D01*
X1189917Y762433D01*
X1189792Y762683D01*
X1189625Y762892D01*
G01X1189500Y764033D02*
X1189792Y764283D01*
X1189958Y764617D01*
X1190000Y764992D01*
X1189958Y765325D01*
X1189750Y765658D01*
X1189500Y765867D01*
X1189250Y765908D01*
X1188958Y765825D01*
X1188750Y765533D01*
X1188667Y765242D01*
Y764867D01*
G01Y765242D02*
X1188542Y765492D01*
X1188333Y765700D01*
X1188083Y765783D01*
X1187833Y765700D01*
X1187625Y765492D01*
X1187500Y765117D01*
X1187542Y764742D01*
X1187708Y764367D01*
G01X1190000Y768050D02*
X1187500D01*
X1188000Y767550D01*
G01X1190000D02*
Y768550D01*
G01X1189708Y770442D02*
X1189917Y770733D01*
X1190000Y771067D01*
X1189917Y771400D01*
X1189667Y771692D01*
X1189292Y771900D01*
X1188917Y771983D01*
X1188458D01*
X1188083Y771900D01*
X1187750Y771692D01*
X1187583Y771442D01*
X1187500Y771150D01*
X1187583Y770817D01*
X1187750Y770567D01*
X1188000Y770400D01*
X1188333Y770317D01*
X1188625Y770400D01*
X1188917Y770608D01*
X1189083Y770858D01*
X1189125Y771150D01*
X1189042Y771483D01*
X1188833Y771733D01*
X1188458Y771983D01*
G01X1191483Y794000D02*
Y792208D01*
X1191650Y791833D01*
X1191983Y791583D01*
X1192400Y791500D01*
X1192817Y791583D01*
X1193150Y791833D01*
X1193317Y792208D01*
Y794000D01*
G01X1195500Y791500D02*
Y794000D01*
X1195000Y793500D01*
G01Y791500D02*
X1196000D01*
G01X1197808Y793583D02*
X1198058Y793833D01*
X1198350Y793958D01*
X1198683Y794000D01*
X1199100Y793917D01*
X1199392Y793708D01*
X1199475Y793458D01*
X1199433Y793208D01*
X1199267Y793000D01*
X1198433Y792583D01*
X1198058Y792292D01*
X1197808Y791875D01*
X1197725Y791500D01*
X1199475D01*
G01X1191735Y814576D02*
X1191485Y814701D01*
X1191193Y814784D01*
X1190860D01*
X1190485Y814659D01*
X1190193Y814451D01*
X1189985Y814201D01*
X1189818Y813784D01*
X1189776Y813409D01*
X1189860Y813034D01*
X1189985Y812784D01*
X1190235Y812534D01*
X1190526Y812367D01*
X1190818Y812284D01*
X1191110D01*
X1191401Y812367D01*
X1191651Y812492D01*
X1191860Y812659D01*
G01X1193918Y812284D02*
Y814784D01*
X1193418Y814284D01*
G01Y812284D02*
X1194418D01*
G01X1197518D02*
Y814784D01*
X1195976Y812992D01*
X1198060D01*
G01X1199326Y814367D02*
X1199576Y814617D01*
X1199868Y814742D01*
X1200201Y814784D01*
X1200618Y814701D01*
X1200910Y814492D01*
X1200993Y814242D01*
X1200951Y813992D01*
X1200785Y813784D01*
X1199951Y813367D01*
X1199576Y813076D01*
X1199326Y812659D01*
X1199243Y812284D01*
X1200993D01*
G01X1191767Y818792D02*
X1191517Y818917D01*
X1191225Y819000D01*
X1190892D01*
X1190517Y818875D01*
X1190225Y818667D01*
X1190017Y818417D01*
X1189850Y818000D01*
X1189808Y817625D01*
X1189892Y817250D01*
X1190017Y817000D01*
X1190267Y816750D01*
X1190558Y816583D01*
X1190850Y816500D01*
X1191142D01*
X1191433Y816583D01*
X1191683Y816708D01*
X1191892Y816875D01*
G01X1193950Y816500D02*
Y819000D01*
X1193450Y818500D01*
G01Y816500D02*
X1194450D01*
G01X1197550D02*
Y819000D01*
X1196008Y817208D01*
X1198092D01*
G01X1199233Y817000D02*
X1199483Y816708D01*
X1199817Y816542D01*
X1200192Y816500D01*
X1200525Y816542D01*
X1200858Y816750D01*
X1201067Y817000D01*
X1201108Y817250D01*
X1201025Y817542D01*
X1200733Y817750D01*
X1200442Y817833D01*
X1200067D01*
G01X1200442D02*
X1200692Y817958D01*
X1200900Y818167D01*
X1200983Y818417D01*
X1200900Y818667D01*
X1200692Y818875D01*
X1200317Y819000D01*
X1199942Y818958D01*
X1199567Y818792D01*
G01X1202500Y837017D02*
X1200000D01*
Y838058D01*
X1200125Y838392D01*
X1200292Y838600D01*
X1200625Y838683D01*
X1200958Y838600D01*
X1201167Y838350D01*
X1201292Y838058D01*
Y837017D01*
G01Y838058D02*
X1202500Y838683D01*
G01X1201458Y840158D02*
X1201167Y840450D01*
X1201000Y840700D01*
X1200917Y841033D01*
X1201000Y841325D01*
X1201167Y841533D01*
X1201417Y841700D01*
X1201708Y841742D01*
X1201958Y841700D01*
X1202208Y841533D01*
X1202417Y841283D01*
X1202500Y840992D01*
X1202417Y840658D01*
X1202167Y840367D01*
X1201792Y840200D01*
X1201375Y840158D01*
X1200833Y840242D01*
X1200542Y840367D01*
X1200250Y840575D01*
X1200042Y840867D01*
X1200000Y841158D01*
X1200083Y841450D01*
X1200292Y841658D01*
G01X1202125Y843133D02*
X1202333Y843383D01*
X1202458Y843675D01*
X1202500Y844050D01*
X1202417Y844425D01*
X1202250Y844717D01*
X1201958Y844925D01*
X1201625Y844967D01*
X1201292Y844883D01*
X1201083Y844675D01*
X1200917Y844383D01*
X1200875Y844092D01*
X1200917Y843800D01*
X1201083Y843425D01*
X1200000Y843550D01*
Y844675D01*
G01X1201458Y846358D02*
X1201167Y846650D01*
X1201000Y846900D01*
X1200917Y847233D01*
X1201000Y847525D01*
X1201167Y847733D01*
X1201417Y847900D01*
X1201708Y847942D01*
X1201958Y847900D01*
X1202208Y847733D01*
X1202417Y847483D01*
X1202500Y847192D01*
X1202417Y846858D01*
X1202167Y846567D01*
X1201792Y846400D01*
X1201375Y846358D01*
X1200833Y846442D01*
X1200542Y846567D01*
X1200250Y846775D01*
X1200042Y847067D01*
X1200000Y847358D01*
X1200083Y847650D01*
X1200292Y847858D01*
G01X1198000Y837017D02*
X1195500D01*
Y838058D01*
X1195625Y838392D01*
X1195792Y838600D01*
X1196125Y838683D01*
X1196458Y838600D01*
X1196667Y838350D01*
X1196792Y838058D01*
Y837017D01*
G01Y838058D02*
X1198000Y838683D01*
G01X1196958Y840158D02*
X1196667Y840450D01*
X1196500Y840700D01*
X1196417Y841033D01*
X1196500Y841325D01*
X1196667Y841533D01*
X1196917Y841700D01*
X1197208Y841742D01*
X1197458Y841700D01*
X1197708Y841533D01*
X1197917Y841283D01*
X1198000Y840992D01*
X1197917Y840658D01*
X1197667Y840367D01*
X1197292Y840200D01*
X1196875Y840158D01*
X1196333Y840242D01*
X1196042Y840367D01*
X1195750Y840575D01*
X1195542Y840867D01*
X1195500Y841158D01*
X1195583Y841450D01*
X1195792Y841658D01*
G01X1198000Y844550D02*
X1195500D01*
X1197292Y843008D01*
Y845092D01*
G01X1198000Y847067D02*
X1197458Y847150D01*
X1197000Y847275D01*
X1196583Y847442D01*
X1196125Y847650D01*
X1195500Y847983D01*
Y846317D01*
G01X1193500Y858800D02*
Y872200D01*
G01X1203500Y858800D02*
X1193500D01*
G01X1191500Y858500D02*
Y872500D01*
G01X1203500Y857200D02*
X1199500D01*
Y849800D01*
G01X1195000D02*
X1199000D01*
Y857200D01*
G01Y873983D02*
X1200792D01*
X1201167Y874150D01*
X1201417Y874483D01*
X1201500Y874900D01*
X1201417Y875317D01*
X1201167Y875650D01*
X1200792Y875817D01*
X1199000D01*
G01X1201500Y878500D02*
X1199000D01*
X1200792Y876958D01*
Y879042D01*
G01X1199417Y880308D02*
X1199167Y880558D01*
X1199042Y880850D01*
X1199000Y881183D01*
X1199083Y881600D01*
X1199292Y881892D01*
X1199542Y881975D01*
X1199792Y881933D01*
X1200000Y881767D01*
X1200417Y880933D01*
X1200708Y880558D01*
X1201125Y880308D01*
X1201500Y880225D01*
Y881975D01*
G01X1193500Y872200D02*
X1203500D01*
G01X1194200Y873500D02*
Y877500D01*
X1186800D01*
G01X1185517Y881000D02*
Y883500D01*
X1186558D01*
X1186892Y883375D01*
X1187100Y883208D01*
X1187183Y882875D01*
X1187100Y882542D01*
X1186850Y882333D01*
X1186558Y882208D01*
X1185517D01*
G01X1186558D02*
X1187183Y881000D01*
G01X1188658Y882042D02*
X1188950Y882333D01*
X1189200Y882500D01*
X1189533Y882583D01*
X1189825Y882500D01*
X1190033Y882333D01*
X1190200Y882083D01*
X1190242Y881792D01*
X1190200Y881542D01*
X1190033Y881292D01*
X1189783Y881083D01*
X1189492Y881000D01*
X1189158Y881083D01*
X1188867Y881333D01*
X1188700Y881708D01*
X1188658Y882125D01*
X1188742Y882667D01*
X1188867Y882958D01*
X1189075Y883250D01*
X1189367Y883458D01*
X1189658Y883500D01*
X1189950Y883417D01*
X1190158Y883208D01*
G01X1191633Y881500D02*
X1191883Y881208D01*
X1192217Y881042D01*
X1192592Y881000D01*
X1192925Y881042D01*
X1193258Y881250D01*
X1193467Y881500D01*
X1193508Y881750D01*
X1193425Y882042D01*
X1193133Y882250D01*
X1192842Y882333D01*
X1192467D01*
G01X1192842D02*
X1193092Y882458D01*
X1193300Y882667D01*
X1193383Y882917D01*
X1193300Y883167D01*
X1193092Y883375D01*
X1192717Y883500D01*
X1192342Y883458D01*
X1191967Y883292D01*
G01X1195650Y881000D02*
X1195942Y881042D01*
X1196275Y881167D01*
X1196483Y881375D01*
X1196567Y881667D01*
X1196483Y881958D01*
X1196233Y882208D01*
X1195858Y882333D01*
X1195442D01*
X1195192Y882417D01*
X1194983Y882625D01*
X1194900Y882917D01*
X1195025Y883208D01*
X1195317Y883417D01*
X1195650Y883500D01*
X1195983Y883417D01*
X1196275Y883208D01*
X1196400Y882917D01*
X1196317Y882625D01*
X1196108Y882417D01*
X1195858Y882333D01*
X1195442D01*
X1195067Y882208D01*
X1194817Y881958D01*
X1194733Y881667D01*
X1194817Y881375D01*
X1195025Y881167D01*
X1195358Y881042D01*
X1195650Y881000D01*
G01X1210216Y390365D02*
Y176565D01*
X1237816D01*
Y390365D01*
X1210216D01*
G01X1204385Y218267D02*
X1204260Y218017D01*
X1204177Y217725D01*
Y217392D01*
X1204302Y217017D01*
X1204510Y216725D01*
X1204760Y216517D01*
X1205177Y216350D01*
X1205552Y216308D01*
X1205927Y216392D01*
X1206177Y216517D01*
X1206427Y216767D01*
X1206594Y217058D01*
X1206677Y217350D01*
Y217642D01*
X1206594Y217933D01*
X1206469Y218183D01*
X1206302Y218392D01*
G01X1204594Y219658D02*
X1204344Y219908D01*
X1204219Y220200D01*
X1204177Y220533D01*
X1204260Y220950D01*
X1204469Y221242D01*
X1204719Y221325D01*
X1204969Y221283D01*
X1205177Y221117D01*
X1205594Y220283D01*
X1205885Y219908D01*
X1206302Y219658D01*
X1206677Y219575D01*
Y221325D01*
G01Y223550D02*
X1206635Y223842D01*
X1206510Y224175D01*
X1206302Y224383D01*
X1206010Y224467D01*
X1205719Y224383D01*
X1205469Y224133D01*
X1205344Y223758D01*
Y223342D01*
X1205260Y223092D01*
X1205052Y222883D01*
X1204760Y222800D01*
X1204469Y222925D01*
X1204260Y223217D01*
X1204177Y223550D01*
X1204260Y223883D01*
X1204469Y224175D01*
X1204760Y224300D01*
X1205052Y224217D01*
X1205260Y224008D01*
X1205344Y223758D01*
Y223342D01*
X1205469Y222967D01*
X1205719Y222717D01*
X1206010Y222633D01*
X1206302Y222717D01*
X1206510Y222925D01*
X1206635Y223258D01*
X1206677Y223550D01*
G01Y226650D02*
X1206635Y226942D01*
X1206510Y227275D01*
X1206302Y227483D01*
X1206010Y227567D01*
X1205719Y227483D01*
X1205469Y227233D01*
X1205344Y226858D01*
Y226442D01*
X1205260Y226192D01*
X1205052Y225983D01*
X1204760Y225900D01*
X1204469Y226025D01*
X1204260Y226317D01*
X1204177Y226650D01*
X1204260Y226983D01*
X1204469Y227275D01*
X1204760Y227400D01*
X1205052Y227317D01*
X1205260Y227108D01*
X1205344Y226858D01*
Y226442D01*
X1205469Y226067D01*
X1205719Y225817D01*
X1206010Y225733D01*
X1206302Y225817D01*
X1206510Y226025D01*
X1206635Y226358D01*
X1206677Y226650D01*
G01X1200385Y218267D02*
X1200260Y218017D01*
X1200177Y217725D01*
Y217392D01*
X1200302Y217017D01*
X1200510Y216725D01*
X1200760Y216517D01*
X1201177Y216350D01*
X1201552Y216308D01*
X1201927Y216392D01*
X1202177Y216517D01*
X1202427Y216767D01*
X1202594Y217058D01*
X1202677Y217350D01*
Y217642D01*
X1202594Y217933D01*
X1202469Y218183D01*
X1202302Y218392D01*
G01X1200594Y219658D02*
X1200344Y219908D01*
X1200219Y220200D01*
X1200177Y220533D01*
X1200260Y220950D01*
X1200469Y221242D01*
X1200719Y221325D01*
X1200969Y221283D01*
X1201177Y221117D01*
X1201594Y220283D01*
X1201885Y219908D01*
X1202302Y219658D01*
X1202677Y219575D01*
Y221325D01*
G01Y223550D02*
X1202635Y223842D01*
X1202510Y224175D01*
X1202302Y224383D01*
X1202010Y224467D01*
X1201719Y224383D01*
X1201469Y224133D01*
X1201344Y223758D01*
Y223342D01*
X1201260Y223092D01*
X1201052Y222883D01*
X1200760Y222800D01*
X1200469Y222925D01*
X1200260Y223217D01*
X1200177Y223550D01*
X1200260Y223883D01*
X1200469Y224175D01*
X1200760Y224300D01*
X1201052Y224217D01*
X1201260Y224008D01*
X1201344Y223758D01*
Y223342D01*
X1201469Y222967D01*
X1201719Y222717D01*
X1202010Y222633D01*
X1202302Y222717D01*
X1202510Y222925D01*
X1202635Y223258D01*
X1202677Y223550D01*
G01X1201635Y225858D02*
X1201344Y226150D01*
X1201177Y226400D01*
X1201094Y226733D01*
X1201177Y227025D01*
X1201344Y227233D01*
X1201594Y227400D01*
X1201885Y227442D01*
X1202135Y227400D01*
X1202385Y227233D01*
X1202594Y226983D01*
X1202677Y226692D01*
X1202594Y226358D01*
X1202344Y226067D01*
X1201969Y225900D01*
X1201552Y225858D01*
X1201010Y225942D01*
X1200719Y226067D01*
X1200427Y226275D01*
X1200219Y226567D01*
X1200177Y226858D01*
X1200260Y227150D01*
X1200469Y227358D01*
G01X1202000Y358300D02*
X1204500D01*
G01X1202000Y357342D02*
Y359258D01*
G01X1204500Y360567D02*
X1202000D01*
Y361567D01*
X1202125Y361900D01*
X1202417Y362150D01*
X1202750Y362233D01*
X1203083Y362150D01*
X1203333Y361942D01*
X1203458Y361567D01*
Y360567D01*
G01X1204500Y364500D02*
X1202000D01*
X1202500Y364000D01*
G01X1204500D02*
Y365000D01*
G01X1203458Y366808D02*
X1203167Y367100D01*
X1203000Y367350D01*
X1202917Y367683D01*
X1203000Y367975D01*
X1203167Y368183D01*
X1203417Y368350D01*
X1203708Y368392D01*
X1203958Y368350D01*
X1204208Y368183D01*
X1204417Y367933D01*
X1204500Y367642D01*
X1204417Y367308D01*
X1204167Y367017D01*
X1203792Y366850D01*
X1203375Y366808D01*
X1202833Y366892D01*
X1202542Y367017D01*
X1202250Y367225D01*
X1202042Y367517D01*
X1202000Y367808D01*
X1202083Y368100D01*
X1202292Y368308D01*
G01X1203458Y369908D02*
X1203167Y370200D01*
X1203000Y370450D01*
X1202917Y370783D01*
X1203000Y371075D01*
X1203167Y371283D01*
X1203417Y371450D01*
X1203708Y371492D01*
X1203958Y371450D01*
X1204208Y371283D01*
X1204417Y371033D01*
X1204500Y370742D01*
X1204417Y370408D01*
X1204167Y370117D01*
X1203792Y369950D01*
X1203375Y369908D01*
X1202833Y369992D01*
X1202542Y370117D01*
X1202250Y370325D01*
X1202042Y370617D01*
X1202000Y370908D01*
X1202083Y371200D01*
X1202292Y371408D01*
G01X1215356Y394532D02*
Y397032D01*
X1216439Y394949D01*
X1217522Y397032D01*
Y394532D01*
G01X1220372D02*
X1218706D01*
Y397032D01*
X1220372D01*
G01X1219706Y395824D02*
X1218706D01*
G01X1221847Y397032D02*
X1223431D01*
X1221847Y394532D01*
X1223431D01*
G01X1226656Y396824D02*
X1226406Y396949D01*
X1226114Y397032D01*
X1225781D01*
X1225406Y396907D01*
X1225114Y396699D01*
X1224906Y396449D01*
X1224739Y396032D01*
X1224697Y395657D01*
X1224781Y395282D01*
X1224906Y395032D01*
X1225156Y394782D01*
X1225447Y394615D01*
X1225739Y394532D01*
X1226031D01*
X1226322Y394615D01*
X1226572Y394740D01*
X1226781Y394907D01*
G01X1227881Y394532D02*
Y397032D01*
X1229797Y394532D01*
Y397032D01*
G01X1231939Y394532D02*
Y397032D01*
X1231439Y396532D01*
G01Y394532D02*
X1232439D01*
G01X1207000Y408017D02*
X1204500D01*
Y409058D01*
X1204625Y409392D01*
X1204792Y409600D01*
X1205125Y409683D01*
X1205458Y409600D01*
X1205667Y409350D01*
X1205792Y409058D01*
Y408017D01*
G01Y409058D02*
X1207000Y409683D01*
G01Y411950D02*
X1204500D01*
X1205000Y411450D01*
G01X1207000D02*
Y412450D01*
G01X1205958Y414258D02*
X1205667Y414550D01*
X1205500Y414800D01*
X1205417Y415133D01*
X1205500Y415425D01*
X1205667Y415633D01*
X1205917Y415800D01*
X1206208Y415842D01*
X1206458Y415800D01*
X1206708Y415633D01*
X1206917Y415383D01*
X1207000Y415092D01*
X1206917Y414758D01*
X1206667Y414467D01*
X1206292Y414300D01*
X1205875Y414258D01*
X1205333Y414342D01*
X1205042Y414467D01*
X1204750Y414675D01*
X1204542Y414967D01*
X1204500Y415258D01*
X1204583Y415550D01*
X1204792Y415758D01*
G01X1204500Y418150D02*
X1204583Y417817D01*
X1204792Y417567D01*
X1205042Y417400D01*
X1205375Y417275D01*
X1205750Y417233D01*
X1206125Y417275D01*
X1206458Y417400D01*
X1206708Y417567D01*
X1206917Y417817D01*
X1207000Y418150D01*
X1206917Y418483D01*
X1206708Y418733D01*
X1206458Y418900D01*
X1206125Y419025D01*
X1205750Y419067D01*
X1205375Y419025D01*
X1205042Y418900D01*
X1204792Y418733D01*
X1204583Y418483D01*
X1204500Y418150D01*
G01X1203000Y408017D02*
X1200500D01*
Y409058D01*
X1200625Y409392D01*
X1200792Y409600D01*
X1201125Y409683D01*
X1201458Y409600D01*
X1201667Y409350D01*
X1201792Y409058D01*
Y408017D01*
G01Y409058D02*
X1203000Y409683D01*
G01Y411950D02*
X1200500D01*
X1201000Y411450D01*
G01X1203000D02*
Y412450D01*
G01X1201958Y414258D02*
X1201667Y414550D01*
X1201500Y414800D01*
X1201417Y415133D01*
X1201500Y415425D01*
X1201667Y415633D01*
X1201917Y415800D01*
X1202208Y415842D01*
X1202458Y415800D01*
X1202708Y415633D01*
X1202917Y415383D01*
X1203000Y415092D01*
X1202917Y414758D01*
X1202667Y414467D01*
X1202292Y414300D01*
X1201875Y414258D01*
X1201333Y414342D01*
X1201042Y414467D01*
X1200750Y414675D01*
X1200542Y414967D01*
X1200500Y415258D01*
X1200583Y415550D01*
X1200792Y415758D01*
G01X1203000Y418650D02*
X1200500D01*
X1202292Y417108D01*
Y419192D01*
G01X1219200Y442000D02*
Y446000D01*
X1211800D01*
G01X1219984Y430532D02*
Y434532D01*
X1212584D01*
G01X1205000Y436517D02*
X1202500D01*
Y437517D01*
X1202625Y437850D01*
X1202917Y438100D01*
X1203250Y438183D01*
X1203583Y438100D01*
X1203833Y437892D01*
X1203958Y437517D01*
Y436517D01*
G01X1205000Y439617D02*
X1202500D01*
Y440658D01*
X1202625Y440992D01*
X1202792Y441200D01*
X1203125Y441283D01*
X1203458Y441200D01*
X1203667Y440950D01*
X1203792Y440658D01*
Y439617D01*
G01Y440658D02*
X1205000Y441283D01*
G01X1204500Y442633D02*
X1204792Y442883D01*
X1204958Y443217D01*
X1205000Y443592D01*
X1204958Y443925D01*
X1204750Y444258D01*
X1204500Y444467D01*
X1204250Y444508D01*
X1203958Y444425D01*
X1203750Y444133D01*
X1203667Y443842D01*
Y443467D01*
G01Y443842D02*
X1203542Y444092D01*
X1203333Y444300D01*
X1203083Y444383D01*
X1202833Y444300D01*
X1202625Y444092D01*
X1202500Y443717D01*
X1202542Y443342D01*
X1202708Y442967D01*
G01X1203958Y445858D02*
X1203667Y446150D01*
X1203500Y446400D01*
X1203417Y446733D01*
X1203500Y447025D01*
X1203667Y447233D01*
X1203917Y447400D01*
X1204208Y447442D01*
X1204458Y447400D01*
X1204708Y447233D01*
X1204917Y446983D01*
X1205000Y446692D01*
X1204917Y446358D01*
X1204667Y446067D01*
X1204292Y445900D01*
X1203875Y445858D01*
X1203333Y445942D01*
X1203042Y446067D01*
X1202750Y446275D01*
X1202542Y446567D01*
X1202500Y446858D01*
X1202583Y447150D01*
X1202792Y447358D01*
G01X1204500Y449517D02*
X1202000D01*
Y450517D01*
X1202125Y450850D01*
X1202417Y451100D01*
X1202750Y451183D01*
X1203083Y451100D01*
X1203333Y450892D01*
X1203458Y450517D01*
Y449517D01*
G01X1204500Y452617D02*
X1202000D01*
Y453658D01*
X1202125Y453992D01*
X1202292Y454200D01*
X1202625Y454283D01*
X1202958Y454200D01*
X1203167Y453950D01*
X1203292Y453658D01*
Y452617D01*
G01Y453658D02*
X1204500Y454283D01*
G01Y456550D02*
X1202000D01*
X1202500Y456050D01*
G01X1204500D02*
Y457050D01*
G01Y459650D02*
X1204458Y459942D01*
X1204333Y460275D01*
X1204125Y460483D01*
X1203833Y460567D01*
X1203542Y460483D01*
X1203292Y460233D01*
X1203167Y459858D01*
Y459442D01*
X1203083Y459192D01*
X1202875Y458983D01*
X1202583Y458900D01*
X1202292Y459025D01*
X1202083Y459317D01*
X1202000Y459650D01*
X1202083Y459983D01*
X1202292Y460275D01*
X1202583Y460400D01*
X1202875Y460317D01*
X1203083Y460108D01*
X1203167Y459858D01*
Y459442D01*
X1203292Y459067D01*
X1203542Y458817D01*
X1203833Y458733D01*
X1204125Y458817D01*
X1204333Y459025D01*
X1204458Y459358D01*
X1204500Y459650D01*
G01X1209000Y449517D02*
X1206500D01*
Y450517D01*
X1206625Y450850D01*
X1206917Y451100D01*
X1207250Y451183D01*
X1207583Y451100D01*
X1207833Y450892D01*
X1207958Y450517D01*
Y449517D01*
G01X1209000Y452617D02*
X1206500D01*
Y453658D01*
X1206625Y453992D01*
X1206792Y454200D01*
X1207125Y454283D01*
X1207458Y454200D01*
X1207667Y453950D01*
X1207792Y453658D01*
Y452617D01*
G01Y453658D02*
X1209000Y454283D01*
G01X1206917Y455758D02*
X1206667Y456008D01*
X1206542Y456300D01*
X1206500Y456633D01*
X1206583Y457050D01*
X1206792Y457342D01*
X1207042Y457425D01*
X1207292Y457383D01*
X1207500Y457217D01*
X1207917Y456383D01*
X1208208Y456008D01*
X1208625Y455758D01*
X1209000Y455675D01*
Y457425D01*
G01Y460150D02*
X1206500D01*
X1208292Y458608D01*
Y460692D01*
G01X1209000Y436517D02*
X1206500D01*
Y437517D01*
X1206625Y437850D01*
X1206917Y438100D01*
X1207250Y438183D01*
X1207583Y438100D01*
X1207833Y437892D01*
X1207958Y437517D01*
Y436517D01*
G01X1206708Y441367D02*
X1206583Y441117D01*
X1206500Y440825D01*
Y440492D01*
X1206625Y440117D01*
X1206833Y439825D01*
X1207083Y439617D01*
X1207500Y439450D01*
X1207875Y439408D01*
X1208250Y439492D01*
X1208500Y439617D01*
X1208750Y439867D01*
X1208917Y440158D01*
X1209000Y440450D01*
Y440742D01*
X1208917Y441033D01*
X1208792Y441283D01*
X1208625Y441492D01*
G01X1208500Y442633D02*
X1208792Y442883D01*
X1208958Y443217D01*
X1209000Y443592D01*
X1208958Y443925D01*
X1208750Y444258D01*
X1208500Y444467D01*
X1208250Y444508D01*
X1207958Y444425D01*
X1207750Y444133D01*
X1207667Y443842D01*
Y443467D01*
G01Y443842D02*
X1207542Y444092D01*
X1207333Y444300D01*
X1207083Y444383D01*
X1206833Y444300D01*
X1206625Y444092D01*
X1206500Y443717D01*
X1206542Y443342D01*
X1206708Y442967D01*
G01X1208500Y445733D02*
X1208792Y445983D01*
X1208958Y446317D01*
X1209000Y446692D01*
X1208958Y447025D01*
X1208750Y447358D01*
X1208500Y447567D01*
X1208250Y447608D01*
X1207958Y447525D01*
X1207750Y447233D01*
X1207667Y446942D01*
Y446567D01*
G01Y446942D02*
X1207542Y447192D01*
X1207333Y447400D01*
X1207083Y447483D01*
X1206833Y447400D01*
X1206625Y447192D01*
X1206500Y446817D01*
X1206542Y446442D01*
X1206708Y446067D01*
G01X1213017Y456000D02*
Y458500D01*
X1214017D01*
X1214350Y458375D01*
X1214600Y458083D01*
X1214683Y457750D01*
X1214600Y457417D01*
X1214392Y457167D01*
X1214017Y457042D01*
X1213017D01*
G01X1216117Y456000D02*
Y458500D01*
X1217158D01*
X1217492Y458375D01*
X1217700Y458208D01*
X1217783Y457875D01*
X1217700Y457542D01*
X1217450Y457333D01*
X1217158Y457208D01*
X1216117D01*
G01X1217158D02*
X1217783Y456000D01*
G01X1219258Y458083D02*
X1219508Y458333D01*
X1219800Y458458D01*
X1220133Y458500D01*
X1220550Y458417D01*
X1220842Y458208D01*
X1220925Y457958D01*
X1220883Y457708D01*
X1220717Y457500D01*
X1219883Y457083D01*
X1219508Y456792D01*
X1219258Y456375D01*
X1219175Y456000D01*
X1220925D01*
G01X1223067D02*
X1223150Y456542D01*
X1223275Y457000D01*
X1223442Y457417D01*
X1223650Y457875D01*
X1223983Y458500D01*
X1222317D01*
G01X1212967Y561000D02*
Y563500D01*
X1214008D01*
X1214342Y563375D01*
X1214550Y563208D01*
X1214633Y562875D01*
X1214550Y562542D01*
X1214300Y562333D01*
X1214008Y562208D01*
X1212967D01*
G01X1214008D02*
X1214633Y561000D01*
G01X1216817D02*
X1216900Y561542D01*
X1217025Y562000D01*
X1217192Y562417D01*
X1217400Y562875D01*
X1217733Y563500D01*
X1216067D01*
G01X1219917Y561000D02*
X1220000Y561542D01*
X1220125Y562000D01*
X1220292Y562417D01*
X1220500Y562875D01*
X1220833Y563500D01*
X1219167D01*
G01X1223100Y561000D02*
X1223392Y561042D01*
X1223725Y561167D01*
X1223933Y561375D01*
X1224017Y561667D01*
X1223933Y561958D01*
X1223683Y562208D01*
X1223308Y562333D01*
X1222892D01*
X1222642Y562417D01*
X1222433Y562625D01*
X1222350Y562917D01*
X1222475Y563208D01*
X1222767Y563417D01*
X1223100Y563500D01*
X1223433Y563417D01*
X1223725Y563208D01*
X1223850Y562917D01*
X1223767Y562625D01*
X1223558Y562417D01*
X1223308Y562333D01*
X1222892D01*
X1222517Y562208D01*
X1222267Y561958D01*
X1222183Y561667D01*
X1222267Y561375D01*
X1222475Y561167D01*
X1222808Y561042D01*
X1223100Y561000D01*
G01X1225492Y561292D02*
X1225783Y561083D01*
X1226117Y561000D01*
X1226450Y561083D01*
X1226742Y561333D01*
X1226950Y561708D01*
X1227033Y562083D01*
Y562542D01*
X1226950Y562917D01*
X1226742Y563250D01*
X1226492Y563417D01*
X1226200Y563500D01*
X1225867Y563417D01*
X1225617Y563250D01*
X1225450Y563000D01*
X1225367Y562667D01*
X1225450Y562375D01*
X1225658Y562083D01*
X1225908Y561917D01*
X1226200Y561875D01*
X1226533Y561958D01*
X1226783Y562167D01*
X1227033Y562542D01*
G01X1203708Y557217D02*
X1203583Y556967D01*
X1203500Y556675D01*
Y556342D01*
X1203625Y555967D01*
X1203833Y555675D01*
X1204083Y555467D01*
X1204500Y555300D01*
X1204875Y555258D01*
X1205250Y555342D01*
X1205500Y555467D01*
X1205750Y555717D01*
X1205917Y556008D01*
X1206000Y556300D01*
Y556592D01*
X1205917Y556883D01*
X1205792Y557133D01*
X1205625Y557342D01*
G01X1206000Y559317D02*
X1205458Y559400D01*
X1205000Y559525D01*
X1204583Y559692D01*
X1204125Y559900D01*
X1203500Y560233D01*
Y558567D01*
G01X1206000Y562417D02*
X1205458Y562500D01*
X1205000Y562625D01*
X1204583Y562792D01*
X1204125Y563000D01*
X1203500Y563333D01*
Y561667D01*
G01X1206000Y565600D02*
X1205958Y565892D01*
X1205833Y566225D01*
X1205625Y566433D01*
X1205333Y566517D01*
X1205042Y566433D01*
X1204792Y566183D01*
X1204667Y565808D01*
Y565392D01*
X1204583Y565142D01*
X1204375Y564933D01*
X1204083Y564850D01*
X1203792Y564975D01*
X1203583Y565267D01*
X1203500Y565600D01*
X1203583Y565933D01*
X1203792Y566225D01*
X1204083Y566350D01*
X1204375Y566267D01*
X1204583Y566058D01*
X1204667Y565808D01*
Y565392D01*
X1204792Y565017D01*
X1205042Y564767D01*
X1205333Y564683D01*
X1205625Y564767D01*
X1205833Y564975D01*
X1205958Y565308D01*
X1206000Y565600D01*
G01Y568700D02*
X1205958Y568992D01*
X1205833Y569325D01*
X1205625Y569533D01*
X1205333Y569617D01*
X1205042Y569533D01*
X1204792Y569283D01*
X1204667Y568908D01*
Y568492D01*
X1204583Y568242D01*
X1204375Y568033D01*
X1204083Y567950D01*
X1203792Y568075D01*
X1203583Y568367D01*
X1203500Y568700D01*
X1203583Y569033D01*
X1203792Y569325D01*
X1204083Y569450D01*
X1204375Y569367D01*
X1204583Y569158D01*
X1204667Y568908D01*
Y568492D01*
X1204792Y568117D01*
X1205042Y567867D01*
X1205333Y567783D01*
X1205625Y567867D01*
X1205833Y568075D01*
X1205958Y568408D01*
X1206000Y568700D01*
G01X1218670Y566510D02*
Y570510D01*
X1211270D01*
G01X1214000Y615017D02*
X1211500D01*
Y616058D01*
X1211625Y616392D01*
X1211792Y616600D01*
X1212125Y616683D01*
X1212458Y616600D01*
X1212667Y616350D01*
X1212792Y616058D01*
Y615017D01*
G01Y616058D02*
X1214000Y616683D01*
G01Y619450D02*
X1211500D01*
X1213292Y617908D01*
Y619992D01*
G01X1214000Y621967D02*
X1213458Y622050D01*
X1213000Y622175D01*
X1212583Y622342D01*
X1212125Y622550D01*
X1211500Y622883D01*
Y621217D01*
G01Y625150D02*
X1211583Y624817D01*
X1211792Y624567D01*
X1212042Y624400D01*
X1212375Y624275D01*
X1212750Y624233D01*
X1213125Y624275D01*
X1213458Y624400D01*
X1213708Y624567D01*
X1213917Y624817D01*
X1214000Y625150D01*
X1213917Y625483D01*
X1213708Y625733D01*
X1213458Y625900D01*
X1213125Y626025D01*
X1212750Y626067D01*
X1212375Y626025D01*
X1212042Y625900D01*
X1211792Y625733D01*
X1211583Y625483D01*
X1211500Y625150D01*
G01X1210000Y615017D02*
X1207500D01*
Y616058D01*
X1207625Y616392D01*
X1207792Y616600D01*
X1208125Y616683D01*
X1208458Y616600D01*
X1208667Y616350D01*
X1208792Y616058D01*
Y615017D01*
G01Y616058D02*
X1210000Y616683D01*
G01Y619450D02*
X1207500D01*
X1209292Y617908D01*
Y619992D01*
G01X1210000Y621967D02*
X1209458Y622050D01*
X1209000Y622175D01*
X1208583Y622342D01*
X1208125Y622550D01*
X1207500Y622883D01*
Y621217D01*
G01X1210000Y625150D02*
X1207500D01*
X1208000Y624650D01*
G01X1210000D02*
Y625650D01*
G01X1206000Y615017D02*
X1203500D01*
Y616058D01*
X1203625Y616392D01*
X1203792Y616600D01*
X1204125Y616683D01*
X1204458Y616600D01*
X1204667Y616350D01*
X1204792Y616058D01*
Y615017D01*
G01Y616058D02*
X1206000Y616683D01*
G01Y618950D02*
X1205958Y619242D01*
X1205833Y619575D01*
X1205625Y619783D01*
X1205333Y619867D01*
X1205042Y619783D01*
X1204792Y619533D01*
X1204667Y619158D01*
Y618742D01*
X1204583Y618492D01*
X1204375Y618283D01*
X1204083Y618200D01*
X1203792Y618325D01*
X1203583Y618617D01*
X1203500Y618950D01*
X1203583Y619283D01*
X1203792Y619575D01*
X1204083Y619700D01*
X1204375Y619617D01*
X1204583Y619408D01*
X1204667Y619158D01*
Y618742D01*
X1204792Y618367D01*
X1205042Y618117D01*
X1205333Y618033D01*
X1205625Y618117D01*
X1205833Y618325D01*
X1205958Y618658D01*
X1206000Y618950D01*
G01X1203500Y622050D02*
X1203583Y621717D01*
X1203792Y621467D01*
X1204042Y621300D01*
X1204375Y621175D01*
X1204750Y621133D01*
X1205125Y621175D01*
X1205458Y621300D01*
X1205708Y621467D01*
X1205917Y621717D01*
X1206000Y622050D01*
X1205917Y622383D01*
X1205708Y622633D01*
X1205458Y622800D01*
X1205125Y622925D01*
X1204750Y622967D01*
X1204375Y622925D01*
X1204042Y622800D01*
X1203792Y622633D01*
X1203583Y622383D01*
X1203500Y622050D01*
G01X1204958Y624358D02*
X1204667Y624650D01*
X1204500Y624900D01*
X1204417Y625233D01*
X1204500Y625525D01*
X1204667Y625733D01*
X1204917Y625900D01*
X1205208Y625942D01*
X1205458Y625900D01*
X1205708Y625733D01*
X1205917Y625483D01*
X1206000Y625192D01*
X1205917Y624858D01*
X1205667Y624567D01*
X1205292Y624400D01*
X1204875Y624358D01*
X1204333Y624442D01*
X1204042Y624567D01*
X1203750Y624775D01*
X1203542Y625067D01*
X1203500Y625358D01*
X1203583Y625650D01*
X1203792Y625858D01*
G01X1218000Y615017D02*
X1215500D01*
Y616058D01*
X1215625Y616392D01*
X1215792Y616600D01*
X1216125Y616683D01*
X1216458Y616600D01*
X1216667Y616350D01*
X1216792Y616058D01*
Y615017D01*
G01Y616058D02*
X1218000Y616683D01*
G01X1215917Y618158D02*
X1215667Y618408D01*
X1215542Y618700D01*
X1215500Y619033D01*
X1215583Y619450D01*
X1215792Y619742D01*
X1216042Y619825D01*
X1216292Y619783D01*
X1216500Y619617D01*
X1216917Y618783D01*
X1217208Y618408D01*
X1217625Y618158D01*
X1218000Y618075D01*
Y619825D01*
G01X1216958Y621258D02*
X1216667Y621550D01*
X1216500Y621800D01*
X1216417Y622133D01*
X1216500Y622425D01*
X1216667Y622633D01*
X1216917Y622800D01*
X1217208Y622842D01*
X1217458Y622800D01*
X1217708Y622633D01*
X1217917Y622383D01*
X1218000Y622092D01*
X1217917Y621758D01*
X1217667Y621467D01*
X1217292Y621300D01*
X1216875Y621258D01*
X1216333Y621342D01*
X1216042Y621467D01*
X1215750Y621675D01*
X1215542Y621967D01*
X1215500Y622258D01*
X1215583Y622550D01*
X1215792Y622758D01*
G01X1215500Y625150D02*
X1215583Y624817D01*
X1215792Y624567D01*
X1216042Y624400D01*
X1216375Y624275D01*
X1216750Y624233D01*
X1217125Y624275D01*
X1217458Y624400D01*
X1217708Y624567D01*
X1217917Y624817D01*
X1218000Y625150D01*
X1217917Y625483D01*
X1217708Y625733D01*
X1217458Y625900D01*
X1217125Y626025D01*
X1216750Y626067D01*
X1216375Y626025D01*
X1216042Y625900D01*
X1215792Y625733D01*
X1215583Y625483D01*
X1215500Y625150D01*
G01X1208467Y605000D02*
Y607500D01*
X1209508D01*
X1209842Y607375D01*
X1210050Y607208D01*
X1210133Y606875D01*
X1210050Y606542D01*
X1209800Y606333D01*
X1209508Y606208D01*
X1208467D01*
G01X1209508D02*
X1210133Y605000D01*
G01X1212317D02*
X1212400Y605542D01*
X1212525Y606000D01*
X1212692Y606417D01*
X1212900Y606875D01*
X1213233Y607500D01*
X1211567D01*
G01X1215500Y605000D02*
X1215792Y605042D01*
X1216125Y605167D01*
X1216333Y605375D01*
X1216417Y605667D01*
X1216333Y605958D01*
X1216083Y606208D01*
X1215708Y606333D01*
X1215292D01*
X1215042Y606417D01*
X1214833Y606625D01*
X1214750Y606917D01*
X1214875Y607208D01*
X1215167Y607417D01*
X1215500Y607500D01*
X1215833Y607417D01*
X1216125Y607208D01*
X1216250Y606917D01*
X1216167Y606625D01*
X1215958Y606417D01*
X1215708Y606333D01*
X1215292D01*
X1214917Y606208D01*
X1214667Y605958D01*
X1214583Y605667D01*
X1214667Y605375D01*
X1214875Y605167D01*
X1215208Y605042D01*
X1215500Y605000D01*
G01X1218600D02*
X1218892Y605042D01*
X1219225Y605167D01*
X1219433Y605375D01*
X1219517Y605667D01*
X1219433Y605958D01*
X1219183Y606208D01*
X1218808Y606333D01*
X1218392D01*
X1218142Y606417D01*
X1217933Y606625D01*
X1217850Y606917D01*
X1217975Y607208D01*
X1218267Y607417D01*
X1218600Y607500D01*
X1218933Y607417D01*
X1219225Y607208D01*
X1219350Y606917D01*
X1219267Y606625D01*
X1219058Y606417D01*
X1218808Y606333D01*
X1218392D01*
X1218017Y606208D01*
X1217767Y605958D01*
X1217683Y605667D01*
X1217767Y605375D01*
X1217975Y605167D01*
X1218308Y605042D01*
X1218600Y605000D01*
G01X1221700D02*
X1221992Y605042D01*
X1222325Y605167D01*
X1222533Y605375D01*
X1222617Y605667D01*
X1222533Y605958D01*
X1222283Y606208D01*
X1221908Y606333D01*
X1221492D01*
X1221242Y606417D01*
X1221033Y606625D01*
X1220950Y606917D01*
X1221075Y607208D01*
X1221367Y607417D01*
X1221700Y607500D01*
X1222033Y607417D01*
X1222325Y607208D01*
X1222450Y606917D01*
X1222367Y606625D01*
X1222158Y606417D01*
X1221908Y606333D01*
X1221492D01*
X1221117Y606208D01*
X1220867Y605958D01*
X1220783Y605667D01*
X1220867Y605375D01*
X1221075Y605167D01*
X1221408Y605042D01*
X1221700Y605000D01*
G01X1215000Y636200D02*
X1211000D01*
Y628800D01*
G01Y636200D02*
X1207000D01*
Y628800D01*
G01Y636200D02*
X1203000D01*
Y628800D01*
G01X1215000D02*
X1219000D01*
Y636200D01*
G01X1223500Y673500D02*
X1214500D01*
Y662000D01*
X1207000D01*
Y650500D01*
X1213500D01*
Y645500D01*
G01X1215000Y640500D02*
Y639500D01*
X1222000D01*
Y627500D01*
X1266500D01*
Y664000D01*
X1270000D01*
Y670000D01*
G01X1215517Y647000D02*
Y649500D01*
X1216558D01*
X1216892Y649375D01*
X1217100Y649208D01*
X1217183Y648875D01*
X1217100Y648542D01*
X1216850Y648333D01*
X1216558Y648208D01*
X1215517D01*
G01X1216558D02*
X1217183Y647000D01*
G01X1218658Y649083D02*
X1218908Y649333D01*
X1219200Y649458D01*
X1219533Y649500D01*
X1219950Y649417D01*
X1220242Y649208D01*
X1220325Y648958D01*
X1220283Y648708D01*
X1220117Y648500D01*
X1219283Y648083D01*
X1218908Y647792D01*
X1218658Y647375D01*
X1218575Y647000D01*
X1220325D01*
G01X1223050D02*
Y649500D01*
X1221508Y647708D01*
X1223592D01*
G01X1224942Y647292D02*
X1225233Y647083D01*
X1225567Y647000D01*
X1225900Y647083D01*
X1226192Y647333D01*
X1226400Y647708D01*
X1226483Y648083D01*
Y648542D01*
X1226400Y648917D01*
X1226192Y649250D01*
X1225942Y649417D01*
X1225650Y649500D01*
X1225317Y649417D01*
X1225067Y649250D01*
X1224900Y649000D01*
X1224817Y648667D01*
X1224900Y648375D01*
X1225108Y648083D01*
X1225358Y647917D01*
X1225650Y647875D01*
X1225983Y647958D01*
X1226233Y648167D01*
X1226483Y648542D01*
G01X1216517Y642000D02*
Y644500D01*
X1217558D01*
X1217892Y644375D01*
X1218100Y644208D01*
X1218183Y643875D01*
X1218100Y643542D01*
X1217850Y643333D01*
X1217558Y643208D01*
X1216517D01*
G01X1217558D02*
X1218183Y642000D01*
G01X1219658Y644083D02*
X1219908Y644333D01*
X1220200Y644458D01*
X1220533Y644500D01*
X1220950Y644417D01*
X1221242Y644208D01*
X1221325Y643958D01*
X1221283Y643708D01*
X1221117Y643500D01*
X1220283Y643083D01*
X1219908Y642792D01*
X1219658Y642375D01*
X1219575Y642000D01*
X1221325D01*
G01X1222758Y643042D02*
X1223050Y643333D01*
X1223300Y643500D01*
X1223633Y643583D01*
X1223925Y643500D01*
X1224133Y643333D01*
X1224300Y643083D01*
X1224342Y642792D01*
X1224300Y642542D01*
X1224133Y642292D01*
X1223883Y642083D01*
X1223592Y642000D01*
X1223258Y642083D01*
X1222967Y642333D01*
X1222800Y642708D01*
X1222758Y643125D01*
X1222842Y643667D01*
X1222967Y643958D01*
X1223175Y644250D01*
X1223467Y644458D01*
X1223758Y644500D01*
X1224050Y644417D01*
X1224258Y644208D01*
G01X1225733Y642500D02*
X1225983Y642208D01*
X1226317Y642042D01*
X1226692Y642000D01*
X1227025Y642042D01*
X1227358Y642250D01*
X1227567Y642500D01*
X1227608Y642750D01*
X1227525Y643042D01*
X1227233Y643250D01*
X1226942Y643333D01*
X1226567D01*
G01X1226942D02*
X1227192Y643458D01*
X1227400Y643667D01*
X1227483Y643917D01*
X1227400Y644167D01*
X1227192Y644375D01*
X1226817Y644500D01*
X1226442Y644458D01*
X1226067Y644292D01*
G01X1202000Y650800D02*
X1204500D01*
G01X1202000Y649842D02*
Y651758D01*
G01X1204500Y653067D02*
X1202000D01*
Y654067D01*
X1202125Y654400D01*
X1202417Y654650D01*
X1202750Y654733D01*
X1203083Y654650D01*
X1203333Y654442D01*
X1203458Y654067D01*
Y653067D01*
G01X1204500Y657000D02*
X1202000D01*
X1202500Y656500D01*
G01X1204500D02*
Y657500D01*
G01X1204125Y659183D02*
X1204333Y659433D01*
X1204458Y659725D01*
X1204500Y660100D01*
X1204417Y660475D01*
X1204250Y660767D01*
X1203958Y660975D01*
X1203625Y661017D01*
X1203292Y660933D01*
X1203083Y660725D01*
X1202917Y660433D01*
X1202875Y660142D01*
X1202917Y659850D01*
X1203083Y659475D01*
X1202000Y659600D01*
Y660725D01*
G01X1204500Y663700D02*
X1202000D01*
X1203792Y662158D01*
Y664242D01*
G01X1208517Y652500D02*
Y655000D01*
X1209558D01*
X1209892Y654875D01*
X1210100Y654708D01*
X1210183Y654375D01*
X1210100Y654042D01*
X1209850Y653833D01*
X1209558Y653708D01*
X1208517D01*
G01X1209558D02*
X1210183Y652500D01*
G01X1211658Y654583D02*
X1211908Y654833D01*
X1212200Y654958D01*
X1212533Y655000D01*
X1212950Y654917D01*
X1213242Y654708D01*
X1213325Y654458D01*
X1213283Y654208D01*
X1213117Y654000D01*
X1212283Y653583D01*
X1211908Y653292D01*
X1211658Y652875D01*
X1211575Y652500D01*
X1213325D01*
G01X1214633Y652875D02*
X1214883Y652667D01*
X1215175Y652542D01*
X1215550Y652500D01*
X1215925Y652583D01*
X1216217Y652750D01*
X1216425Y653042D01*
X1216467Y653375D01*
X1216383Y653708D01*
X1216175Y653917D01*
X1215883Y654083D01*
X1215592Y654125D01*
X1215300Y654083D01*
X1214925Y653917D01*
X1215050Y655000D01*
X1216175D01*
G01X1218650Y652500D02*
Y655000D01*
X1218150Y654500D01*
G01Y652500D02*
X1219150D01*
G01X1208517Y657000D02*
Y659500D01*
X1209558D01*
X1209892Y659375D01*
X1210100Y659208D01*
X1210183Y658875D01*
X1210100Y658542D01*
X1209850Y658333D01*
X1209558Y658208D01*
X1208517D01*
G01X1209558D02*
X1210183Y657000D01*
G01X1212950D02*
Y659500D01*
X1211408Y657708D01*
X1213492D01*
G01X1214758Y658042D02*
X1215050Y658333D01*
X1215300Y658500D01*
X1215633Y658583D01*
X1215925Y658500D01*
X1216133Y658333D01*
X1216300Y658083D01*
X1216342Y657792D01*
X1216300Y657542D01*
X1216133Y657292D01*
X1215883Y657083D01*
X1215592Y657000D01*
X1215258Y657083D01*
X1214967Y657333D01*
X1214800Y657708D01*
X1214758Y658125D01*
X1214842Y658667D01*
X1214967Y658958D01*
X1215175Y659250D01*
X1215467Y659458D01*
X1215758Y659500D01*
X1216050Y659417D01*
X1216258Y659208D01*
G01X1218650Y659500D02*
X1218317Y659417D01*
X1218067Y659208D01*
X1217900Y658958D01*
X1217775Y658625D01*
X1217733Y658250D01*
X1217775Y657875D01*
X1217900Y657542D01*
X1218067Y657292D01*
X1218317Y657083D01*
X1218650Y657000D01*
X1218983Y657083D01*
X1219233Y657292D01*
X1219400Y657542D01*
X1219525Y657875D01*
X1219567Y658250D01*
X1219525Y658625D01*
X1219400Y658958D01*
X1219233Y659208D01*
X1218983Y659417D01*
X1218650Y659500D01*
G01X1209300Y679500D02*
Y677000D01*
G01X1208342Y679500D02*
X1210258D01*
G01X1211567Y677000D02*
Y679500D01*
X1212567D01*
X1212900Y679375D01*
X1213150Y679083D01*
X1213233Y678750D01*
X1213150Y678417D01*
X1212942Y678167D01*
X1212567Y678042D01*
X1211567D01*
G01X1215500Y677000D02*
Y679500D01*
X1215000Y679000D01*
G01Y677000D02*
X1216000D01*
G01X1218600Y679500D02*
X1218267Y679417D01*
X1218017Y679208D01*
X1217850Y678958D01*
X1217725Y678625D01*
X1217683Y678250D01*
X1217725Y677875D01*
X1217850Y677542D01*
X1218017Y677292D01*
X1218267Y677083D01*
X1218600Y677000D01*
X1218933Y677083D01*
X1219183Y677292D01*
X1219350Y677542D01*
X1219475Y677875D01*
X1219517Y678250D01*
X1219475Y678625D01*
X1219350Y678958D01*
X1219183Y679208D01*
X1218933Y679417D01*
X1218600Y679500D01*
G01X1220783Y677375D02*
X1221033Y677167D01*
X1221325Y677042D01*
X1221700Y677000D01*
X1222075Y677083D01*
X1222367Y677250D01*
X1222575Y677542D01*
X1222617Y677875D01*
X1222533Y678208D01*
X1222325Y678417D01*
X1222033Y678583D01*
X1221742Y678625D01*
X1221450Y678583D01*
X1221075Y678417D01*
X1221200Y679500D01*
X1222325D01*
G01X1214500Y689300D02*
X1217000D01*
G01X1214500Y688342D02*
Y690258D01*
G01X1217000Y691567D02*
X1214500D01*
Y692567D01*
X1214625Y692900D01*
X1214917Y693150D01*
X1215250Y693233D01*
X1215583Y693150D01*
X1215833Y692942D01*
X1215958Y692567D01*
Y691567D01*
G01X1217000Y695500D02*
X1214500D01*
X1215000Y695000D01*
G01X1217000D02*
Y696000D01*
G01X1214500Y698600D02*
X1214583Y698267D01*
X1214792Y698017D01*
X1215042Y697850D01*
X1215375Y697725D01*
X1215750Y697683D01*
X1216125Y697725D01*
X1216458Y697850D01*
X1216708Y698017D01*
X1216917Y698267D01*
X1217000Y698600D01*
X1216917Y698933D01*
X1216708Y699183D01*
X1216458Y699350D01*
X1216125Y699475D01*
X1215750Y699517D01*
X1215375Y699475D01*
X1215042Y699350D01*
X1214792Y699183D01*
X1214583Y698933D01*
X1214500Y698600D01*
G01X1214917Y700908D02*
X1214667Y701158D01*
X1214542Y701450D01*
X1214500Y701783D01*
X1214583Y702200D01*
X1214792Y702492D01*
X1215042Y702575D01*
X1215292Y702533D01*
X1215500Y702367D01*
X1215917Y701533D01*
X1216208Y701158D01*
X1216625Y700908D01*
X1217000Y700825D01*
Y702575D01*
G01X1201000Y683350D02*
X1203500D01*
G01X1201000Y682392D02*
Y684308D01*
G01X1203500Y685617D02*
X1201000D01*
Y686617D01*
X1201125Y686950D01*
X1201417Y687200D01*
X1201750Y687283D01*
X1202083Y687200D01*
X1202333Y686992D01*
X1202458Y686617D01*
Y685617D01*
G01X1203208Y688842D02*
X1203417Y689133D01*
X1203500Y689467D01*
X1203417Y689800D01*
X1203167Y690092D01*
X1202792Y690300D01*
X1202417Y690383D01*
X1201958D01*
X1201583Y690300D01*
X1201250Y690092D01*
X1201083Y689842D01*
X1201000Y689550D01*
X1201083Y689217D01*
X1201250Y688967D01*
X1201500Y688800D01*
X1201833Y688717D01*
X1202125Y688800D01*
X1202417Y689008D01*
X1202583Y689258D01*
X1202625Y689550D01*
X1202542Y689883D01*
X1202333Y690133D01*
X1201958Y690383D01*
G01X1201000Y692650D02*
X1201083Y692317D01*
X1201292Y692067D01*
X1201542Y691900D01*
X1201875Y691775D01*
X1202250Y691733D01*
X1202625Y691775D01*
X1202958Y691900D01*
X1203208Y692067D01*
X1203417Y692317D01*
X1203500Y692650D01*
X1203417Y692983D01*
X1203208Y693233D01*
X1202958Y693400D01*
X1202625Y693525D01*
X1202250Y693567D01*
X1201875Y693525D01*
X1201542Y693400D01*
X1201292Y693233D01*
X1201083Y692983D01*
X1201000Y692650D01*
G01X1205500Y683300D02*
X1208000D01*
G01X1205500Y682342D02*
Y684258D01*
G01X1208000Y685567D02*
X1205500D01*
Y686567D01*
X1205625Y686900D01*
X1205917Y687150D01*
X1206250Y687233D01*
X1206583Y687150D01*
X1206833Y686942D01*
X1206958Y686567D01*
Y685567D01*
G01X1208000Y689500D02*
X1205500D01*
X1206000Y689000D01*
G01X1208000D02*
Y690000D01*
G01Y692517D02*
X1207458Y692600D01*
X1207000Y692725D01*
X1206583Y692892D01*
X1206125Y693100D01*
X1205500Y693433D01*
Y691767D01*
G01X1207625Y694783D02*
X1207833Y695033D01*
X1207958Y695325D01*
X1208000Y695700D01*
X1207917Y696075D01*
X1207750Y696367D01*
X1207458Y696575D01*
X1207125Y696617D01*
X1206792Y696533D01*
X1206583Y696325D01*
X1206417Y696033D01*
X1206375Y695742D01*
X1206417Y695450D01*
X1206583Y695075D01*
X1205500Y695200D01*
Y696325D01*
G01X1210500Y715300D02*
X1213000D01*
G01X1210500Y714342D02*
Y716258D01*
G01X1213000Y717567D02*
X1210500D01*
Y718567D01*
X1210625Y718900D01*
X1210917Y719150D01*
X1211250Y719233D01*
X1211583Y719150D01*
X1211833Y718942D01*
X1211958Y718567D01*
Y717567D01*
G01X1213000Y721500D02*
X1210500D01*
X1211000Y721000D01*
G01X1213000D02*
Y722000D01*
G01Y724517D02*
X1212458Y724600D01*
X1212000Y724725D01*
X1211583Y724892D01*
X1211125Y725100D01*
X1210500Y725433D01*
Y723767D01*
G01X1213000Y728200D02*
X1210500D01*
X1212292Y726658D01*
Y728742D01*
G01X1220200Y733500D02*
Y737500D01*
X1212800D01*
G01X1210425Y744333D02*
X1210758Y744125D01*
X1211133Y744000D01*
X1211467D01*
X1211800Y744125D01*
X1212050Y744333D01*
X1212175Y744625D01*
X1212092Y744917D01*
X1211883Y745167D01*
X1211508Y745333D01*
X1211008Y745417D01*
X1210717Y745583D01*
X1210592Y745875D01*
X1210675Y746167D01*
X1210883Y746375D01*
X1211175Y746500D01*
X1211467D01*
X1211758Y746417D01*
X1212008Y746208D01*
G01X1213567Y744000D02*
Y746500D01*
X1214608D01*
X1214942Y746375D01*
X1215150Y746208D01*
X1215233Y745875D01*
X1215150Y745542D01*
X1214900Y745333D01*
X1214608Y745208D01*
X1213567D01*
G01X1214608D02*
X1215233Y744000D01*
G01X1217500D02*
X1217792Y744042D01*
X1218125Y744167D01*
X1218333Y744375D01*
X1218417Y744667D01*
X1218333Y744958D01*
X1218083Y745208D01*
X1217708Y745333D01*
X1217292D01*
X1217042Y745417D01*
X1216833Y745625D01*
X1216750Y745917D01*
X1216875Y746208D01*
X1217167Y746417D01*
X1217500Y746500D01*
X1217833Y746417D01*
X1218125Y746208D01*
X1218250Y745917D01*
X1218167Y745625D01*
X1217958Y745417D01*
X1217708Y745333D01*
X1217292D01*
X1216917Y745208D01*
X1216667Y744958D01*
X1216583Y744667D01*
X1216667Y744375D01*
X1216875Y744167D01*
X1217208Y744042D01*
X1217500Y744000D01*
G01X1221100D02*
Y746500D01*
X1219558Y744708D01*
X1221642D01*
G01X1222992Y744292D02*
X1223283Y744083D01*
X1223617Y744000D01*
X1223950Y744083D01*
X1224242Y744333D01*
X1224450Y744708D01*
X1224533Y745083D01*
Y745542D01*
X1224450Y745917D01*
X1224242Y746250D01*
X1223992Y746417D01*
X1223700Y746500D01*
X1223367Y746417D01*
X1223117Y746250D01*
X1222950Y746000D01*
X1222867Y745667D01*
X1222950Y745375D01*
X1223158Y745083D01*
X1223408Y744917D01*
X1223700Y744875D01*
X1224033Y744958D01*
X1224283Y745167D01*
X1224533Y745542D01*
G01X1220200Y729000D02*
Y733000D01*
X1212800D01*
G01X1210425Y748833D02*
X1210758Y748625D01*
X1211133Y748500D01*
X1211467D01*
X1211800Y748625D01*
X1212050Y748833D01*
X1212175Y749125D01*
X1212092Y749417D01*
X1211883Y749667D01*
X1211508Y749833D01*
X1211008Y749917D01*
X1210717Y750083D01*
X1210592Y750375D01*
X1210675Y750667D01*
X1210883Y750875D01*
X1211175Y751000D01*
X1211467D01*
X1211758Y750917D01*
X1212008Y750708D01*
G01X1213567Y748500D02*
Y751000D01*
X1214608D01*
X1214942Y750875D01*
X1215150Y750708D01*
X1215233Y750375D01*
X1215150Y750042D01*
X1214900Y749833D01*
X1214608Y749708D01*
X1213567D01*
G01X1214608D02*
X1215233Y748500D01*
G01X1217500D02*
X1217792Y748542D01*
X1218125Y748667D01*
X1218333Y748875D01*
X1218417Y749167D01*
X1218333Y749458D01*
X1218083Y749708D01*
X1217708Y749833D01*
X1217292D01*
X1217042Y749917D01*
X1216833Y750125D01*
X1216750Y750417D01*
X1216875Y750708D01*
X1217167Y750917D01*
X1217500Y751000D01*
X1217833Y750917D01*
X1218125Y750708D01*
X1218250Y750417D01*
X1218167Y750125D01*
X1217958Y749917D01*
X1217708Y749833D01*
X1217292D01*
X1216917Y749708D01*
X1216667Y749458D01*
X1216583Y749167D01*
X1216667Y748875D01*
X1216875Y748667D01*
X1217208Y748542D01*
X1217500Y748500D01*
G01X1221100D02*
Y751000D01*
X1219558Y749208D01*
X1221642D01*
G01X1223617Y748500D02*
X1223700Y749042D01*
X1223825Y749500D01*
X1223992Y749917D01*
X1224200Y750375D01*
X1224533Y751000D01*
X1222867D01*
G01X1200300D02*
Y747000D01*
X1207700D01*
G01X1205000Y759300D02*
X1209000D01*
Y766700D01*
G01X1210500Y759300D02*
X1214500D01*
Y766700D01*
G01X1203517Y755500D02*
Y758000D01*
X1204558D01*
X1204892Y757875D01*
X1205100Y757708D01*
X1205183Y757375D01*
X1205100Y757042D01*
X1204850Y756833D01*
X1204558Y756708D01*
X1203517D01*
G01X1204558D02*
X1205183Y755500D01*
G01X1207450D02*
Y758000D01*
X1206950Y757500D01*
G01Y755500D02*
X1207950D01*
G01X1209758Y756542D02*
X1210050Y756833D01*
X1210300Y757000D01*
X1210633Y757083D01*
X1210925Y757000D01*
X1211133Y756833D01*
X1211300Y756583D01*
X1211342Y756292D01*
X1211300Y756042D01*
X1211133Y755792D01*
X1210883Y755583D01*
X1210592Y755500D01*
X1210258Y755583D01*
X1209967Y755833D01*
X1209800Y756208D01*
X1209758Y756625D01*
X1209842Y757167D01*
X1209967Y757458D01*
X1210175Y757750D01*
X1210467Y757958D01*
X1210758Y758000D01*
X1211050Y757917D01*
X1211258Y757708D01*
G01X1212733Y756000D02*
X1212983Y755708D01*
X1213317Y755542D01*
X1213692Y755500D01*
X1214025Y755542D01*
X1214358Y755750D01*
X1214567Y756000D01*
X1214608Y756250D01*
X1214525Y756542D01*
X1214233Y756750D01*
X1213942Y756833D01*
X1213567D01*
G01X1213942D02*
X1214192Y756958D01*
X1214400Y757167D01*
X1214483Y757417D01*
X1214400Y757667D01*
X1214192Y757875D01*
X1213817Y758000D01*
X1213442Y757958D01*
X1213067Y757792D01*
G01X1213300Y780000D02*
X1201400D01*
G01X1213300Y788000D02*
Y780000D01*
G01X1201400Y788000D02*
X1213300D01*
G01X1201400Y780000D02*
Y788000D01*
G01X1203000Y784000D02*
X1201400Y785600D01*
G01X1203000Y784000D02*
X1201400Y782400D01*
G01X1217716Y811168D02*
X1213716D01*
Y803768D01*
G01X1213216Y811168D02*
X1209216D01*
Y803768D01*
G01X1209000Y811200D02*
X1205000D01*
Y803800D01*
G01X1216716Y813985D02*
X1214216D01*
Y815026D01*
X1214341Y815360D01*
X1214508Y815568D01*
X1214841Y815651D01*
X1215174Y815568D01*
X1215383Y815318D01*
X1215508Y815026D01*
Y813985D01*
G01Y815026D02*
X1216716Y815651D01*
G01Y817918D02*
X1214216D01*
X1214716Y817418D01*
G01X1216716D02*
Y818418D01*
G01X1215674Y820226D02*
X1215383Y820518D01*
X1215216Y820768D01*
X1215133Y821101D01*
X1215216Y821393D01*
X1215383Y821601D01*
X1215633Y821768D01*
X1215924Y821810D01*
X1216174Y821768D01*
X1216424Y821601D01*
X1216633Y821351D01*
X1216716Y821060D01*
X1216633Y820726D01*
X1216383Y820435D01*
X1216008Y820268D01*
X1215591Y820226D01*
X1215049Y820310D01*
X1214758Y820435D01*
X1214466Y820643D01*
X1214258Y820935D01*
X1214216Y821226D01*
X1214299Y821518D01*
X1214508Y821726D01*
G01X1216716Y824118D02*
X1216674Y824410D01*
X1216549Y824743D01*
X1216341Y824951D01*
X1216049Y825035D01*
X1215758Y824951D01*
X1215508Y824701D01*
X1215383Y824326D01*
Y823910D01*
X1215299Y823660D01*
X1215091Y823451D01*
X1214799Y823368D01*
X1214508Y823493D01*
X1214299Y823785D01*
X1214216Y824118D01*
X1214299Y824451D01*
X1214508Y824743D01*
X1214799Y824868D01*
X1215091Y824785D01*
X1215299Y824576D01*
X1215383Y824326D01*
Y823910D01*
X1215508Y823535D01*
X1215758Y823285D01*
X1216049Y823201D01*
X1216341Y823285D01*
X1216549Y823493D01*
X1216674Y823826D01*
X1216716Y824118D01*
G01X1212216Y813985D02*
X1209716D01*
Y815026D01*
X1209841Y815360D01*
X1210008Y815568D01*
X1210341Y815651D01*
X1210674Y815568D01*
X1210883Y815318D01*
X1211008Y815026D01*
Y813985D01*
G01Y815026D02*
X1212216Y815651D01*
G01Y817918D02*
X1209716D01*
X1210216Y817418D01*
G01X1212216D02*
Y818418D01*
G01X1211174Y820226D02*
X1210883Y820518D01*
X1210716Y820768D01*
X1210633Y821101D01*
X1210716Y821393D01*
X1210883Y821601D01*
X1211133Y821768D01*
X1211424Y821810D01*
X1211674Y821768D01*
X1211924Y821601D01*
X1212133Y821351D01*
X1212216Y821060D01*
X1212133Y820726D01*
X1211883Y820435D01*
X1211508Y820268D01*
X1211091Y820226D01*
X1210549Y820310D01*
X1210258Y820435D01*
X1209966Y820643D01*
X1209758Y820935D01*
X1209716Y821226D01*
X1209799Y821518D01*
X1210008Y821726D01*
G01X1211924Y823410D02*
X1212133Y823701D01*
X1212216Y824035D01*
X1212133Y824368D01*
X1211883Y824660D01*
X1211508Y824868D01*
X1211133Y824951D01*
X1210674D01*
X1210299Y824868D01*
X1209966Y824660D01*
X1209799Y824410D01*
X1209716Y824118D01*
X1209799Y823785D01*
X1209966Y823535D01*
X1210216Y823368D01*
X1210549Y823285D01*
X1210841Y823368D01*
X1211133Y823576D01*
X1211299Y823826D01*
X1211341Y824118D01*
X1211258Y824451D01*
X1211049Y824701D01*
X1210674Y824951D01*
G01X1207500Y813967D02*
X1205000D01*
Y815008D01*
X1205125Y815342D01*
X1205292Y815550D01*
X1205625Y815633D01*
X1205958Y815550D01*
X1206167Y815300D01*
X1206292Y815008D01*
Y813967D01*
G01Y815008D02*
X1207500Y815633D01*
G01X1207125Y816983D02*
X1207333Y817233D01*
X1207458Y817525D01*
X1207500Y817900D01*
X1207417Y818275D01*
X1207250Y818567D01*
X1206958Y818775D01*
X1206625Y818817D01*
X1206292Y818733D01*
X1206083Y818525D01*
X1205917Y818233D01*
X1205875Y817942D01*
X1205917Y817650D01*
X1206083Y817275D01*
X1205000Y817400D01*
Y818525D01*
G01X1207000Y820083D02*
X1207292Y820333D01*
X1207458Y820667D01*
X1207500Y821042D01*
X1207458Y821375D01*
X1207250Y821708D01*
X1207000Y821917D01*
X1206750Y821958D01*
X1206458Y821875D01*
X1206250Y821583D01*
X1206167Y821292D01*
Y820917D01*
G01Y821292D02*
X1206042Y821542D01*
X1205833Y821750D01*
X1205583Y821833D01*
X1205333Y821750D01*
X1205125Y821542D01*
X1205000Y821167D01*
X1205042Y820792D01*
X1205208Y820417D01*
G01X1205000Y824100D02*
X1205083Y823767D01*
X1205292Y823517D01*
X1205542Y823350D01*
X1205875Y823225D01*
X1206250Y823183D01*
X1206625Y823225D01*
X1206958Y823350D01*
X1207208Y823517D01*
X1207417Y823767D01*
X1207500Y824100D01*
X1207417Y824433D01*
X1207208Y824683D01*
X1206958Y824850D01*
X1206625Y824975D01*
X1206250Y825017D01*
X1205875Y824975D01*
X1205542Y824850D01*
X1205292Y824683D01*
X1205083Y824433D01*
X1205000Y824100D01*
G01Y827200D02*
X1205083Y826867D01*
X1205292Y826617D01*
X1205542Y826450D01*
X1205875Y826325D01*
X1206250Y826283D01*
X1206625Y826325D01*
X1206958Y826450D01*
X1207208Y826617D01*
X1207417Y826867D01*
X1207500Y827200D01*
X1207417Y827533D01*
X1207208Y827783D01*
X1206958Y827950D01*
X1206625Y828075D01*
X1206250Y828117D01*
X1205875Y828075D01*
X1205542Y827950D01*
X1205292Y827783D01*
X1205083Y827533D01*
X1205000Y827200D01*
G01X1211000Y836517D02*
X1208500D01*
Y837558D01*
X1208625Y837892D01*
X1208792Y838100D01*
X1209125Y838183D01*
X1209458Y838100D01*
X1209667Y837850D01*
X1209792Y837558D01*
Y836517D01*
G01Y837558D02*
X1211000Y838183D01*
G01X1209958Y839658D02*
X1209667Y839950D01*
X1209500Y840200D01*
X1209417Y840533D01*
X1209500Y840825D01*
X1209667Y841033D01*
X1209917Y841200D01*
X1210208Y841242D01*
X1210458Y841200D01*
X1210708Y841033D01*
X1210917Y840783D01*
X1211000Y840492D01*
X1210917Y840158D01*
X1210667Y839867D01*
X1210292Y839700D01*
X1209875Y839658D01*
X1209333Y839742D01*
X1209042Y839867D01*
X1208750Y840075D01*
X1208542Y840367D01*
X1208500Y840658D01*
X1208583Y840950D01*
X1208792Y841158D01*
G01X1210625Y842633D02*
X1210833Y842883D01*
X1210958Y843175D01*
X1211000Y843550D01*
X1210917Y843925D01*
X1210750Y844217D01*
X1210458Y844425D01*
X1210125Y844467D01*
X1209792Y844383D01*
X1209583Y844175D01*
X1209417Y843883D01*
X1209375Y843592D01*
X1209417Y843300D01*
X1209583Y842925D01*
X1208500Y843050D01*
Y844175D01*
G01X1211000Y846567D02*
X1210458Y846650D01*
X1210000Y846775D01*
X1209583Y846942D01*
X1209125Y847150D01*
X1208500Y847483D01*
Y845817D01*
G01X1215500Y836517D02*
X1213000D01*
Y837558D01*
X1213125Y837892D01*
X1213292Y838100D01*
X1213625Y838183D01*
X1213958Y838100D01*
X1214167Y837850D01*
X1214292Y837558D01*
Y836517D01*
G01Y837558D02*
X1215500Y838183D01*
G01X1214458Y839658D02*
X1214167Y839950D01*
X1214000Y840200D01*
X1213917Y840533D01*
X1214000Y840825D01*
X1214167Y841033D01*
X1214417Y841200D01*
X1214708Y841242D01*
X1214958Y841200D01*
X1215208Y841033D01*
X1215417Y840783D01*
X1215500Y840492D01*
X1215417Y840158D01*
X1215167Y839867D01*
X1214792Y839700D01*
X1214375Y839658D01*
X1213833Y839742D01*
X1213542Y839867D01*
X1213250Y840075D01*
X1213042Y840367D01*
X1213000Y840658D01*
X1213083Y840950D01*
X1213292Y841158D01*
G01X1215125Y842633D02*
X1215333Y842883D01*
X1215458Y843175D01*
X1215500Y843550D01*
X1215417Y843925D01*
X1215250Y844217D01*
X1214958Y844425D01*
X1214625Y844467D01*
X1214292Y844383D01*
X1214083Y844175D01*
X1213917Y843883D01*
X1213875Y843592D01*
X1213917Y843300D01*
X1214083Y842925D01*
X1213000Y843050D01*
Y844175D01*
G01X1215500Y846650D02*
X1215458Y846942D01*
X1215333Y847275D01*
X1215125Y847483D01*
X1214833Y847567D01*
X1214542Y847483D01*
X1214292Y847233D01*
X1214167Y846858D01*
Y846442D01*
X1214083Y846192D01*
X1213875Y845983D01*
X1213583Y845900D01*
X1213292Y846025D01*
X1213083Y846317D01*
X1213000Y846650D01*
X1213083Y846983D01*
X1213292Y847275D01*
X1213583Y847400D01*
X1213875Y847317D01*
X1214083Y847108D01*
X1214167Y846858D01*
Y846442D01*
X1214292Y846067D01*
X1214542Y845817D01*
X1214833Y845733D01*
X1215125Y845817D01*
X1215333Y846025D01*
X1215458Y846358D01*
X1215500Y846650D01*
G01X1206017Y830500D02*
Y833000D01*
X1207058D01*
X1207392Y832875D01*
X1207600Y832708D01*
X1207683Y832375D01*
X1207600Y832042D01*
X1207350Y831833D01*
X1207058Y831708D01*
X1206017D01*
G01X1207058D02*
X1207683Y830500D01*
G01X1209033Y830875D02*
X1209283Y830667D01*
X1209575Y830542D01*
X1209950Y830500D01*
X1210325Y830583D01*
X1210617Y830750D01*
X1210825Y831042D01*
X1210867Y831375D01*
X1210783Y831708D01*
X1210575Y831917D01*
X1210283Y832083D01*
X1209992Y832125D01*
X1209700Y832083D01*
X1209325Y831917D01*
X1209450Y833000D01*
X1210575D01*
G01X1212967Y830500D02*
X1213050Y831042D01*
X1213175Y831500D01*
X1213342Y831917D01*
X1213550Y832375D01*
X1213883Y833000D01*
X1212217D01*
G01X1215233Y830875D02*
X1215483Y830667D01*
X1215775Y830542D01*
X1216150Y830500D01*
X1216525Y830583D01*
X1216817Y830750D01*
X1217025Y831042D01*
X1217067Y831375D01*
X1216983Y831708D01*
X1216775Y831917D01*
X1216483Y832083D01*
X1216192Y832125D01*
X1215900Y832083D01*
X1215525Y831917D01*
X1215650Y833000D01*
X1216775D01*
G01X1206500Y858800D02*
Y872200D01*
G01X1216500Y858800D02*
X1206500D01*
G01X1203500Y872200D02*
Y858800D01*
G01X1209000Y849800D02*
X1213000D01*
Y857200D01*
G01X1217500D02*
X1213500D01*
Y849800D01*
G01X1206500Y872200D02*
X1216500D01*
G01X1205767Y886292D02*
X1205517Y886417D01*
X1205225Y886500D01*
X1204892D01*
X1204517Y886375D01*
X1204225Y886167D01*
X1204017Y885917D01*
X1203850Y885500D01*
X1203808Y885125D01*
X1203892Y884750D01*
X1204017Y884500D01*
X1204267Y884250D01*
X1204558Y884083D01*
X1204850Y884000D01*
X1205142D01*
X1205433Y884083D01*
X1205683Y884208D01*
X1205892Y884375D01*
G01X1207033Y884500D02*
X1207283Y884208D01*
X1207617Y884042D01*
X1207992Y884000D01*
X1208325Y884042D01*
X1208658Y884250D01*
X1208867Y884500D01*
X1208908Y884750D01*
X1208825Y885042D01*
X1208533Y885250D01*
X1208242Y885333D01*
X1207867D01*
G01X1208242D02*
X1208492Y885458D01*
X1208700Y885667D01*
X1208783Y885917D01*
X1208700Y886167D01*
X1208492Y886375D01*
X1208117Y886500D01*
X1207742Y886458D01*
X1207367Y886292D01*
G01X1210133Y884500D02*
X1210383Y884208D01*
X1210717Y884042D01*
X1211092Y884000D01*
X1211425Y884042D01*
X1211758Y884250D01*
X1211967Y884500D01*
X1212008Y884750D01*
X1211925Y885042D01*
X1211633Y885250D01*
X1211342Y885333D01*
X1210967D01*
G01X1211342D02*
X1211592Y885458D01*
X1211800Y885667D01*
X1211883Y885917D01*
X1211800Y886167D01*
X1211592Y886375D01*
X1211217Y886500D01*
X1210842Y886458D01*
X1210467Y886292D01*
G01X1214150Y884000D02*
Y886500D01*
X1213650Y886000D01*
G01Y884000D02*
X1214650D01*
G01X1220500Y430300D02*
X1224500D01*
Y437700D01*
G01X1220000Y438300D02*
X1224000D01*
Y445700D01*
G01X1228500D02*
X1224500D01*
Y438300D01*
G01X1222017Y466500D02*
Y469000D01*
X1223017D01*
X1223350Y468875D01*
X1223600Y468583D01*
X1223683Y468250D01*
X1223600Y467917D01*
X1223392Y467667D01*
X1223017Y467542D01*
X1222017D01*
G01X1225117Y466500D02*
Y469000D01*
X1226158D01*
X1226492Y468875D01*
X1226700Y468708D01*
X1226783Y468375D01*
X1226700Y468042D01*
X1226450Y467833D01*
X1226158Y467708D01*
X1225117D01*
G01X1226158D02*
X1226783Y466500D01*
G01X1228133Y467000D02*
X1228383Y466708D01*
X1228717Y466542D01*
X1229092Y466500D01*
X1229425Y466542D01*
X1229758Y466750D01*
X1229967Y467000D01*
X1230008Y467250D01*
X1229925Y467542D01*
X1229633Y467750D01*
X1229342Y467833D01*
X1228967D01*
G01X1229342D02*
X1229592Y467958D01*
X1229800Y468167D01*
X1229883Y468417D01*
X1229800Y468667D01*
X1229592Y468875D01*
X1229217Y469000D01*
X1228842Y468958D01*
X1228467Y468792D01*
G01X1231358Y468583D02*
X1231608Y468833D01*
X1231900Y468958D01*
X1232233Y469000D01*
X1232650Y468917D01*
X1232942Y468708D01*
X1233025Y468458D01*
X1232983Y468208D01*
X1232817Y468000D01*
X1231983Y467583D01*
X1231608Y467292D01*
X1231358Y466875D01*
X1231275Y466500D01*
X1233025D01*
G01X1222017Y462000D02*
Y464500D01*
X1223017D01*
X1223350Y464375D01*
X1223600Y464083D01*
X1223683Y463750D01*
X1223600Y463417D01*
X1223392Y463167D01*
X1223017Y463042D01*
X1222017D01*
G01X1225117Y462000D02*
Y464500D01*
X1226158D01*
X1226492Y464375D01*
X1226700Y464208D01*
X1226783Y463875D01*
X1226700Y463542D01*
X1226450Y463333D01*
X1226158Y463208D01*
X1225117D01*
G01X1226158D02*
X1226783Y462000D01*
G01X1228133Y462500D02*
X1228383Y462208D01*
X1228717Y462042D01*
X1229092Y462000D01*
X1229425Y462042D01*
X1229758Y462250D01*
X1229967Y462500D01*
X1230008Y462750D01*
X1229925Y463042D01*
X1229633Y463250D01*
X1229342Y463333D01*
X1228967D01*
G01X1229342D02*
X1229592Y463458D01*
X1229800Y463667D01*
X1229883Y463917D01*
X1229800Y464167D01*
X1229592Y464375D01*
X1229217Y464500D01*
X1228842Y464458D01*
X1228467Y464292D01*
G01X1231233Y462375D02*
X1231483Y462167D01*
X1231775Y462042D01*
X1232150Y462000D01*
X1232525Y462083D01*
X1232817Y462250D01*
X1233025Y462542D01*
X1233067Y462875D01*
X1232983Y463208D01*
X1232775Y463417D01*
X1232483Y463583D01*
X1232192Y463625D01*
X1231900Y463583D01*
X1231525Y463417D01*
X1231650Y464500D01*
X1232775D01*
G01X1225300Y601640D02*
Y572040D01*
G01X1231467Y603000D02*
Y605500D01*
X1232508D01*
X1232842Y605375D01*
X1233050Y605208D01*
X1233133Y604875D01*
X1233050Y604542D01*
X1232800Y604333D01*
X1232508Y604208D01*
X1231467D01*
G01X1232508D02*
X1233133Y603000D01*
G01X1234483Y603375D02*
X1234733Y603167D01*
X1235025Y603042D01*
X1235400Y603000D01*
X1235775Y603083D01*
X1236067Y603250D01*
X1236275Y603542D01*
X1236317Y603875D01*
X1236233Y604208D01*
X1236025Y604417D01*
X1235733Y604583D01*
X1235442Y604625D01*
X1235150Y604583D01*
X1234775Y604417D01*
X1234900Y605500D01*
X1236025D01*
G01X1237708Y605083D02*
X1237958Y605333D01*
X1238250Y605458D01*
X1238583Y605500D01*
X1239000Y605417D01*
X1239292Y605208D01*
X1239375Y604958D01*
X1239333Y604708D01*
X1239167Y604500D01*
X1238333Y604083D01*
X1237958Y603792D01*
X1237708Y603375D01*
X1237625Y603000D01*
X1239375D01*
G01X1241600Y605500D02*
X1241267Y605417D01*
X1241017Y605208D01*
X1240850Y604958D01*
X1240725Y604625D01*
X1240683Y604250D01*
X1240725Y603875D01*
X1240850Y603542D01*
X1241017Y603292D01*
X1241267Y603083D01*
X1241600Y603000D01*
X1241933Y603083D01*
X1242183Y603292D01*
X1242350Y603542D01*
X1242475Y603875D01*
X1242517Y604250D01*
X1242475Y604625D01*
X1242350Y604958D01*
X1242183Y605208D01*
X1241933Y605417D01*
X1241600Y605500D01*
G01X1244700D02*
X1244367Y605417D01*
X1244117Y605208D01*
X1243950Y604958D01*
X1243825Y604625D01*
X1243783Y604250D01*
X1243825Y603875D01*
X1243950Y603542D01*
X1244117Y603292D01*
X1244367Y603083D01*
X1244700Y603000D01*
X1245033Y603083D01*
X1245283Y603292D01*
X1245450Y603542D01*
X1245575Y603875D01*
X1245617Y604250D01*
X1245575Y604625D01*
X1245450Y604958D01*
X1245283Y605208D01*
X1245033Y605417D01*
X1244700Y605500D01*
G01X1231467Y608000D02*
Y610500D01*
X1232508D01*
X1232842Y610375D01*
X1233050Y610208D01*
X1233133Y609875D01*
X1233050Y609542D01*
X1232800Y609333D01*
X1232508Y609208D01*
X1231467D01*
G01X1232508D02*
X1233133Y608000D01*
G01X1234483Y608375D02*
X1234733Y608167D01*
X1235025Y608042D01*
X1235400Y608000D01*
X1235775Y608083D01*
X1236067Y608250D01*
X1236275Y608542D01*
X1236317Y608875D01*
X1236233Y609208D01*
X1236025Y609417D01*
X1235733Y609583D01*
X1235442Y609625D01*
X1235150Y609583D01*
X1234775Y609417D01*
X1234900Y610500D01*
X1236025D01*
G01X1237708Y610083D02*
X1237958Y610333D01*
X1238250Y610458D01*
X1238583Y610500D01*
X1239000Y610417D01*
X1239292Y610208D01*
X1239375Y609958D01*
X1239333Y609708D01*
X1239167Y609500D01*
X1238333Y609083D01*
X1237958Y608792D01*
X1237708Y608375D01*
X1237625Y608000D01*
X1239375D01*
G01X1241600Y610500D02*
X1241267Y610417D01*
X1241017Y610208D01*
X1240850Y609958D01*
X1240725Y609625D01*
X1240683Y609250D01*
X1240725Y608875D01*
X1240850Y608542D01*
X1241017Y608292D01*
X1241267Y608083D01*
X1241600Y608000D01*
X1241933Y608083D01*
X1242183Y608292D01*
X1242350Y608542D01*
X1242475Y608875D01*
X1242517Y609250D01*
X1242475Y609625D01*
X1242350Y609958D01*
X1242183Y610208D01*
X1241933Y610417D01*
X1241600Y610500D01*
G01X1244700Y608000D02*
Y610500D01*
X1244200Y610000D01*
G01Y608000D02*
X1245200D01*
G01X1224517Y658000D02*
Y660500D01*
X1225558D01*
X1225892Y660375D01*
X1226100Y660208D01*
X1226183Y659875D01*
X1226100Y659542D01*
X1225850Y659333D01*
X1225558Y659208D01*
X1224517D01*
G01X1225558D02*
X1226183Y658000D01*
G01X1228950D02*
Y660500D01*
X1227408Y658708D01*
X1229492D01*
G01X1232050Y658000D02*
Y660500D01*
X1230508Y658708D01*
X1232592D01*
G01X1234650Y660500D02*
X1234317Y660417D01*
X1234067Y660208D01*
X1233900Y659958D01*
X1233775Y659625D01*
X1233733Y659250D01*
X1233775Y658875D01*
X1233900Y658542D01*
X1234067Y658292D01*
X1234317Y658083D01*
X1234650Y658000D01*
X1234983Y658083D01*
X1235233Y658292D01*
X1235400Y658542D01*
X1235525Y658875D01*
X1235567Y659250D01*
X1235525Y659625D01*
X1235400Y659958D01*
X1235233Y660208D01*
X1234983Y660417D01*
X1234650Y660500D01*
G01X1224517Y653500D02*
Y656000D01*
X1225558D01*
X1225892Y655875D01*
X1226100Y655708D01*
X1226183Y655375D01*
X1226100Y655042D01*
X1225850Y654833D01*
X1225558Y654708D01*
X1224517D01*
G01X1225558D02*
X1226183Y653500D01*
G01X1228950D02*
Y656000D01*
X1227408Y654208D01*
X1229492D01*
G01X1231467Y653500D02*
X1231550Y654042D01*
X1231675Y654500D01*
X1231842Y654917D01*
X1232050Y655375D01*
X1232383Y656000D01*
X1230717D01*
G01X1233733Y653875D02*
X1233983Y653667D01*
X1234275Y653542D01*
X1234650Y653500D01*
X1235025Y653583D01*
X1235317Y653750D01*
X1235525Y654042D01*
X1235567Y654375D01*
X1235483Y654708D01*
X1235275Y654917D01*
X1234983Y655083D01*
X1234692Y655125D01*
X1234400Y655083D01*
X1234025Y654917D01*
X1234150Y656000D01*
X1235275D01*
G01X1247000Y704000D02*
Y707000D01*
X1231000D01*
Y695500D01*
X1228000D01*
Y677000D01*
G01X1218500Y687800D02*
X1221000D01*
G01X1218500Y686842D02*
Y688758D01*
G01X1221000Y690067D02*
X1218500D01*
Y691067D01*
X1218625Y691400D01*
X1218917Y691650D01*
X1219250Y691733D01*
X1219583Y691650D01*
X1219833Y691442D01*
X1219958Y691067D01*
Y690067D01*
G01X1221000Y694000D02*
X1218500D01*
X1219000Y693500D01*
G01X1221000D02*
Y694500D01*
G01X1218500Y697100D02*
X1218583Y696767D01*
X1218792Y696517D01*
X1219042Y696350D01*
X1219375Y696225D01*
X1219750Y696183D01*
X1220125Y696225D01*
X1220458Y696350D01*
X1220708Y696517D01*
X1220917Y696767D01*
X1221000Y697100D01*
X1220917Y697433D01*
X1220708Y697683D01*
X1220458Y697850D01*
X1220125Y697975D01*
X1219750Y698017D01*
X1219375Y697975D01*
X1219042Y697850D01*
X1218792Y697683D01*
X1218583Y697433D01*
X1218500Y697100D01*
G01Y700200D02*
X1218583Y699867D01*
X1218792Y699617D01*
X1219042Y699450D01*
X1219375Y699325D01*
X1219750Y699283D01*
X1220125Y699325D01*
X1220458Y699450D01*
X1220708Y699617D01*
X1220917Y699867D01*
X1221000Y700200D01*
X1220917Y700533D01*
X1220708Y700783D01*
X1220458Y700950D01*
X1220125Y701075D01*
X1219750Y701117D01*
X1219375Y701075D01*
X1219042Y700950D01*
X1218792Y700783D01*
X1218583Y700533D01*
X1218500Y700200D01*
G01X1229800Y689500D02*
Y687000D01*
G01X1228842Y689500D02*
X1230758D01*
G01X1232067Y687000D02*
Y689500D01*
X1233067D01*
X1233400Y689375D01*
X1233650Y689083D01*
X1233733Y688750D01*
X1233650Y688417D01*
X1233442Y688167D01*
X1233067Y688042D01*
X1232067D01*
G01X1236000Y687000D02*
Y689500D01*
X1235500Y689000D01*
G01Y687000D02*
X1236500D01*
G01X1239017D02*
X1239100Y687542D01*
X1239225Y688000D01*
X1239392Y688417D01*
X1239600Y688875D01*
X1239933Y689500D01*
X1238267D01*
G01X1241283Y687500D02*
X1241533Y687208D01*
X1241867Y687042D01*
X1242242Y687000D01*
X1242575Y687042D01*
X1242908Y687250D01*
X1243117Y687500D01*
X1243158Y687750D01*
X1243075Y688042D01*
X1242783Y688250D01*
X1242492Y688333D01*
X1242117D01*
G01X1242492D02*
X1242742Y688458D01*
X1242950Y688667D01*
X1243033Y688917D01*
X1242950Y689167D01*
X1242742Y689375D01*
X1242367Y689500D01*
X1241992Y689458D01*
X1241617Y689292D01*
G01X1217000Y705800D02*
X1219500D01*
G01X1217000Y704842D02*
Y706758D01*
G01X1219500Y708067D02*
X1217000D01*
Y709067D01*
X1217125Y709400D01*
X1217417Y709650D01*
X1217750Y709733D01*
X1218083Y709650D01*
X1218333Y709442D01*
X1218458Y709067D01*
Y708067D01*
G01X1219500Y712000D02*
X1217000D01*
X1217500Y711500D01*
G01X1219500D02*
Y712500D01*
G01Y715100D02*
X1217000D01*
X1217500Y714600D01*
G01X1219500D02*
Y715600D01*
G01X1217000Y718200D02*
X1217083Y717867D01*
X1217292Y717617D01*
X1217542Y717450D01*
X1217875Y717325D01*
X1218250Y717283D01*
X1218625Y717325D01*
X1218958Y717450D01*
X1219208Y717617D01*
X1219417Y717867D01*
X1219500Y718200D01*
X1219417Y718533D01*
X1219208Y718783D01*
X1218958Y718950D01*
X1218625Y719075D01*
X1218250Y719117D01*
X1217875Y719075D01*
X1217542Y718950D01*
X1217292Y718783D01*
X1217083Y718533D01*
X1217000Y718200D01*
G01X1230017Y716500D02*
Y719000D01*
X1231058D01*
X1231392Y718875D01*
X1231600Y718708D01*
X1231683Y718375D01*
X1231600Y718042D01*
X1231350Y717833D01*
X1231058Y717708D01*
X1230017D01*
G01X1231058D02*
X1231683Y716500D01*
G01X1233033Y717000D02*
X1233283Y716708D01*
X1233617Y716542D01*
X1233992Y716500D01*
X1234325Y716542D01*
X1234658Y716750D01*
X1234867Y717000D01*
X1234908Y717250D01*
X1234825Y717542D01*
X1234533Y717750D01*
X1234242Y717833D01*
X1233867D01*
G01X1234242D02*
X1234492Y717958D01*
X1234700Y718167D01*
X1234783Y718417D01*
X1234700Y718667D01*
X1234492Y718875D01*
X1234117Y719000D01*
X1233742Y718958D01*
X1233367Y718792D01*
G01X1237050Y719000D02*
X1236717Y718917D01*
X1236467Y718708D01*
X1236300Y718458D01*
X1236175Y718125D01*
X1236133Y717750D01*
X1236175Y717375D01*
X1236300Y717042D01*
X1236467Y716792D01*
X1236717Y716583D01*
X1237050Y716500D01*
X1237383Y716583D01*
X1237633Y716792D01*
X1237800Y717042D01*
X1237925Y717375D01*
X1237967Y717750D01*
X1237925Y718125D01*
X1237800Y718458D01*
X1237633Y718708D01*
X1237383Y718917D01*
X1237050Y719000D01*
G01X1240150Y716500D02*
X1240442Y716542D01*
X1240775Y716667D01*
X1240983Y716875D01*
X1241067Y717167D01*
X1240983Y717458D01*
X1240733Y717708D01*
X1240358Y717833D01*
X1239942D01*
X1239692Y717917D01*
X1239483Y718125D01*
X1239400Y718417D01*
X1239525Y718708D01*
X1239817Y718917D01*
X1240150Y719000D01*
X1240483Y718917D01*
X1240775Y718708D01*
X1240900Y718417D01*
X1240817Y718125D01*
X1240608Y717917D01*
X1240358Y717833D01*
X1239942D01*
X1239567Y717708D01*
X1239317Y717458D01*
X1239233Y717167D01*
X1239317Y716875D01*
X1239525Y716667D01*
X1239858Y716542D01*
X1240150Y716500D01*
G01X1227700D02*
Y720500D01*
X1220300D01*
G01X1230017D02*
Y723000D01*
X1231058D01*
X1231392Y722875D01*
X1231600Y722708D01*
X1231683Y722375D01*
X1231600Y722042D01*
X1231350Y721833D01*
X1231058Y721708D01*
X1230017D01*
G01X1231058D02*
X1231683Y720500D01*
G01X1233950D02*
X1234242Y720542D01*
X1234575Y720667D01*
X1234783Y720875D01*
X1234867Y721167D01*
X1234783Y721458D01*
X1234533Y721708D01*
X1234158Y721833D01*
X1233742D01*
X1233492Y721917D01*
X1233283Y722125D01*
X1233200Y722417D01*
X1233325Y722708D01*
X1233617Y722917D01*
X1233950Y723000D01*
X1234283Y722917D01*
X1234575Y722708D01*
X1234700Y722417D01*
X1234617Y722125D01*
X1234408Y721917D01*
X1234158Y721833D01*
X1233742D01*
X1233367Y721708D01*
X1233117Y721458D01*
X1233033Y721167D01*
X1233117Y720875D01*
X1233325Y720667D01*
X1233658Y720542D01*
X1233950Y720500D01*
G01X1237050Y723000D02*
X1236717Y722917D01*
X1236467Y722708D01*
X1236300Y722458D01*
X1236175Y722125D01*
X1236133Y721750D01*
X1236175Y721375D01*
X1236300Y721042D01*
X1236467Y720792D01*
X1236717Y720583D01*
X1237050Y720500D01*
X1237383Y720583D01*
X1237633Y720792D01*
X1237800Y721042D01*
X1237925Y721375D01*
X1237967Y721750D01*
X1237925Y722125D01*
X1237800Y722458D01*
X1237633Y722708D01*
X1237383Y722917D01*
X1237050Y723000D01*
G01X1240150D02*
X1239817Y722917D01*
X1239567Y722708D01*
X1239400Y722458D01*
X1239275Y722125D01*
X1239233Y721750D01*
X1239275Y721375D01*
X1239400Y721042D01*
X1239567Y720792D01*
X1239817Y720583D01*
X1240150Y720500D01*
X1240483Y720583D01*
X1240733Y720792D01*
X1240900Y721042D01*
X1241025Y721375D01*
X1241067Y721750D01*
X1241025Y722125D01*
X1240900Y722458D01*
X1240733Y722708D01*
X1240483Y722917D01*
X1240150Y723000D01*
G01X1220300Y724500D02*
Y720500D01*
X1227700D01*
G01Y729000D02*
Y733000D01*
X1220300D01*
G01X1230517Y743000D02*
Y745500D01*
X1231558D01*
X1231892Y745375D01*
X1232100Y745208D01*
X1232183Y744875D01*
X1232100Y744542D01*
X1231850Y744333D01*
X1231558Y744208D01*
X1230517D01*
G01X1231558D02*
X1232183Y743000D01*
G01X1233533Y743500D02*
X1233783Y743208D01*
X1234117Y743042D01*
X1234492Y743000D01*
X1234825Y743042D01*
X1235158Y743250D01*
X1235367Y743500D01*
X1235408Y743750D01*
X1235325Y744042D01*
X1235033Y744250D01*
X1234742Y744333D01*
X1234367D01*
G01X1234742D02*
X1234992Y744458D01*
X1235200Y744667D01*
X1235283Y744917D01*
X1235200Y745167D01*
X1234992Y745375D01*
X1234617Y745500D01*
X1234242Y745458D01*
X1233867Y745292D01*
G01X1237550Y745500D02*
X1237217Y745417D01*
X1236967Y745208D01*
X1236800Y744958D01*
X1236675Y744625D01*
X1236633Y744250D01*
X1236675Y743875D01*
X1236800Y743542D01*
X1236967Y743292D01*
X1237217Y743083D01*
X1237550Y743000D01*
X1237883Y743083D01*
X1238133Y743292D01*
X1238300Y743542D01*
X1238425Y743875D01*
X1238467Y744250D01*
X1238425Y744625D01*
X1238300Y744958D01*
X1238133Y745208D01*
X1237883Y745417D01*
X1237550Y745500D01*
G01X1241150Y743000D02*
Y745500D01*
X1239608Y743708D01*
X1241692D01*
G01X1220300Y742500D02*
Y738500D01*
X1227700D01*
G01X1228925Y738333D02*
X1229258Y738125D01*
X1229633Y738000D01*
X1229967D01*
X1230300Y738125D01*
X1230550Y738333D01*
X1230675Y738625D01*
X1230592Y738917D01*
X1230383Y739167D01*
X1230008Y739333D01*
X1229508Y739417D01*
X1229217Y739583D01*
X1229092Y739875D01*
X1229175Y740167D01*
X1229383Y740375D01*
X1229675Y740500D01*
X1229967D01*
X1230258Y740417D01*
X1230508Y740208D01*
G01X1232067Y738000D02*
Y740500D01*
X1233108D01*
X1233442Y740375D01*
X1233650Y740208D01*
X1233733Y739875D01*
X1233650Y739542D01*
X1233400Y739333D01*
X1233108Y739208D01*
X1232067D01*
G01X1233108D02*
X1233733Y738000D01*
G01X1236000D02*
X1236292Y738042D01*
X1236625Y738167D01*
X1236833Y738375D01*
X1236917Y738667D01*
X1236833Y738958D01*
X1236583Y739208D01*
X1236208Y739333D01*
X1235792D01*
X1235542Y739417D01*
X1235333Y739625D01*
X1235250Y739917D01*
X1235375Y740208D01*
X1235667Y740417D01*
X1236000Y740500D01*
X1236333Y740417D01*
X1236625Y740208D01*
X1236750Y739917D01*
X1236667Y739625D01*
X1236458Y739417D01*
X1236208Y739333D01*
X1235792D01*
X1235417Y739208D01*
X1235167Y738958D01*
X1235083Y738667D01*
X1235167Y738375D01*
X1235375Y738167D01*
X1235708Y738042D01*
X1236000Y738000D01*
G01X1238183Y738375D02*
X1238433Y738167D01*
X1238725Y738042D01*
X1239100Y738000D01*
X1239475Y738083D01*
X1239767Y738250D01*
X1239975Y738542D01*
X1240017Y738875D01*
X1239933Y739208D01*
X1239725Y739417D01*
X1239433Y739583D01*
X1239142Y739625D01*
X1238850Y739583D01*
X1238475Y739417D01*
X1238600Y740500D01*
X1239725D01*
G01X1241283Y738500D02*
X1241533Y738208D01*
X1241867Y738042D01*
X1242242Y738000D01*
X1242575Y738042D01*
X1242908Y738250D01*
X1243117Y738500D01*
X1243158Y738750D01*
X1243075Y739042D01*
X1242783Y739250D01*
X1242492Y739333D01*
X1242117D01*
G01X1242492D02*
X1242742Y739458D01*
X1242950Y739667D01*
X1243033Y739917D01*
X1242950Y740167D01*
X1242742Y740375D01*
X1242367Y740500D01*
X1241992Y740458D01*
X1241617Y740292D01*
G01X1227700Y733500D02*
Y737500D01*
X1220300D01*
G01X1228925Y733833D02*
X1229258Y733625D01*
X1229633Y733500D01*
X1229967D01*
X1230300Y733625D01*
X1230550Y733833D01*
X1230675Y734125D01*
X1230592Y734417D01*
X1230383Y734667D01*
X1230008Y734833D01*
X1229508Y734917D01*
X1229217Y735083D01*
X1229092Y735375D01*
X1229175Y735667D01*
X1229383Y735875D01*
X1229675Y736000D01*
X1229967D01*
X1230258Y735917D01*
X1230508Y735708D01*
G01X1232067Y733500D02*
Y736000D01*
X1233108D01*
X1233442Y735875D01*
X1233650Y735708D01*
X1233733Y735375D01*
X1233650Y735042D01*
X1233400Y734833D01*
X1233108Y734708D01*
X1232067D01*
G01X1233108D02*
X1233733Y733500D01*
G01X1235292Y733792D02*
X1235583Y733583D01*
X1235917Y733500D01*
X1236250Y733583D01*
X1236542Y733833D01*
X1236750Y734208D01*
X1236833Y734583D01*
Y735042D01*
X1236750Y735417D01*
X1236542Y735750D01*
X1236292Y735917D01*
X1236000Y736000D01*
X1235667Y735917D01*
X1235417Y735750D01*
X1235250Y735500D01*
X1235167Y735167D01*
X1235250Y734875D01*
X1235458Y734583D01*
X1235708Y734417D01*
X1236000Y734375D01*
X1236333Y734458D01*
X1236583Y734667D01*
X1236833Y735042D01*
G01X1239600Y733500D02*
Y736000D01*
X1238058Y734208D01*
X1240142D01*
G01X1241283Y734000D02*
X1241533Y733708D01*
X1241867Y733542D01*
X1242242Y733500D01*
X1242575Y733542D01*
X1242908Y733750D01*
X1243117Y734000D01*
X1243158Y734250D01*
X1243075Y734542D01*
X1242783Y734750D01*
X1242492Y734833D01*
X1242117D01*
G01X1242492D02*
X1242742Y734958D01*
X1242950Y735167D01*
X1243033Y735417D01*
X1242950Y735667D01*
X1242742Y735875D01*
X1242367Y736000D01*
X1241992Y735958D01*
X1241617Y735792D01*
G01X1220000Y753517D02*
X1217500D01*
Y754558D01*
X1217625Y754892D01*
X1217792Y755100D01*
X1218125Y755183D01*
X1218458Y755100D01*
X1218667Y754850D01*
X1218792Y754558D01*
Y753517D01*
G01Y754558D02*
X1220000Y755183D01*
G01Y757450D02*
X1217500D01*
X1218000Y756950D01*
G01X1220000D02*
Y757950D01*
G01Y760467D02*
X1219458Y760550D01*
X1219000Y760675D01*
X1218583Y760842D01*
X1218125Y761050D01*
X1217500Y761383D01*
Y759717D01*
G01Y763650D02*
X1217583Y763317D01*
X1217792Y763067D01*
X1218042Y762900D01*
X1218375Y762775D01*
X1218750Y762733D01*
X1219125Y762775D01*
X1219458Y762900D01*
X1219708Y763067D01*
X1219917Y763317D01*
X1220000Y763650D01*
X1219917Y763983D01*
X1219708Y764233D01*
X1219458Y764400D01*
X1219125Y764525D01*
X1218750Y764567D01*
X1218375Y764525D01*
X1218042Y764400D01*
X1217792Y764233D01*
X1217583Y763983D01*
X1217500Y763650D01*
G01X1224000Y753517D02*
X1221500D01*
Y754558D01*
X1221625Y754892D01*
X1221792Y755100D01*
X1222125Y755183D01*
X1222458Y755100D01*
X1222667Y754850D01*
X1222792Y754558D01*
Y753517D01*
G01Y754558D02*
X1224000Y755183D01*
G01Y757450D02*
X1221500D01*
X1222000Y756950D01*
G01X1224000D02*
Y757950D01*
G01Y760467D02*
X1223458Y760550D01*
X1223000Y760675D01*
X1222583Y760842D01*
X1222125Y761050D01*
X1221500Y761383D01*
Y759717D01*
G01X1224000Y763650D02*
X1221500D01*
X1222000Y763150D01*
G01X1224000D02*
Y764150D01*
G01X1226800Y764000D02*
Y760000D01*
X1234200D01*
G01X1226800Y759500D02*
Y755500D01*
X1234200D01*
G01X1226800Y755000D02*
Y751000D01*
X1234200D01*
G01X1220500Y768300D02*
X1223000D01*
G01X1220500Y767342D02*
Y769258D01*
G01X1223000Y770567D02*
X1220500D01*
Y771567D01*
X1220625Y771900D01*
X1220917Y772150D01*
X1221250Y772233D01*
X1221583Y772150D01*
X1221833Y771942D01*
X1221958Y771567D01*
Y770567D01*
G01X1223000Y774500D02*
X1220500D01*
X1221000Y774000D01*
G01X1223000D02*
Y775000D01*
G01Y777517D02*
X1222458Y777600D01*
X1222000Y777725D01*
X1221583Y777892D01*
X1221125Y778100D01*
X1220500Y778433D01*
Y776767D01*
G01X1220917Y779908D02*
X1220667Y780158D01*
X1220542Y780450D01*
X1220500Y780783D01*
X1220583Y781200D01*
X1220792Y781492D01*
X1221042Y781575D01*
X1221292Y781533D01*
X1221500Y781367D01*
X1221917Y780533D01*
X1222208Y780158D01*
X1222625Y779908D01*
X1223000Y779825D01*
Y781575D01*
G01X1229150Y781400D02*
Y786400D01*
X1234150D01*
G01X1234500Y789517D02*
X1232000D01*
Y790558D01*
X1232125Y790892D01*
X1232292Y791100D01*
X1232625Y791183D01*
X1232958Y791100D01*
X1233167Y790850D01*
X1233292Y790558D01*
Y789517D01*
G01Y790558D02*
X1234500Y791183D01*
G01Y793450D02*
X1232000D01*
X1232500Y792950D01*
G01X1234500D02*
Y793950D01*
G01Y796467D02*
X1233958Y796550D01*
X1233500Y796675D01*
X1233083Y796842D01*
X1232625Y797050D01*
X1232000Y797383D01*
Y795717D01*
G01X1232417Y798858D02*
X1232167Y799108D01*
X1232042Y799400D01*
X1232000Y799733D01*
X1232083Y800150D01*
X1232292Y800442D01*
X1232542Y800525D01*
X1232792Y800483D01*
X1233000Y800317D01*
X1233417Y799483D01*
X1233708Y799108D01*
X1234125Y798858D01*
X1234500Y798775D01*
Y800525D01*
G01X1227500Y795200D02*
X1223500D01*
Y787800D01*
G01X1219350Y800500D02*
Y798000D01*
G01X1218392Y800500D02*
X1220308D01*
G01X1221617Y798000D02*
Y800500D01*
X1222617D01*
X1222950Y800375D01*
X1223200Y800083D01*
X1223283Y799750D01*
X1223200Y799417D01*
X1222992Y799167D01*
X1222617Y799042D01*
X1221617D01*
G01X1225550Y798000D02*
X1225842Y798042D01*
X1226175Y798167D01*
X1226383Y798375D01*
X1226467Y798667D01*
X1226383Y798958D01*
X1226133Y799208D01*
X1225758Y799333D01*
X1225342D01*
X1225092Y799417D01*
X1224883Y799625D01*
X1224800Y799917D01*
X1224925Y800208D01*
X1225217Y800417D01*
X1225550Y800500D01*
X1225883Y800417D01*
X1226175Y800208D01*
X1226300Y799917D01*
X1226217Y799625D01*
X1226008Y799417D01*
X1225758Y799333D01*
X1225342D01*
X1224967Y799208D01*
X1224717Y798958D01*
X1224633Y798667D01*
X1224717Y798375D01*
X1224925Y798167D01*
X1225258Y798042D01*
X1225550Y798000D01*
G01X1227733Y798500D02*
X1227983Y798208D01*
X1228317Y798042D01*
X1228692Y798000D01*
X1229025Y798042D01*
X1229358Y798250D01*
X1229567Y798500D01*
X1229608Y798750D01*
X1229525Y799042D01*
X1229233Y799250D01*
X1228942Y799333D01*
X1228567D01*
G01X1228942D02*
X1229192Y799458D01*
X1229400Y799667D01*
X1229483Y799917D01*
X1229400Y800167D01*
X1229192Y800375D01*
X1228817Y800500D01*
X1228442Y800458D01*
X1228067Y800292D01*
G01X1222000Y811200D02*
X1218000D01*
Y803800D01*
G01X1221500Y813967D02*
X1219000D01*
Y815008D01*
X1219125Y815342D01*
X1219292Y815550D01*
X1219625Y815633D01*
X1219958Y815550D01*
X1220167Y815300D01*
X1220292Y815008D01*
Y813967D01*
G01Y815008D02*
X1221500Y815633D01*
G01X1221125Y816983D02*
X1221333Y817233D01*
X1221458Y817525D01*
X1221500Y817900D01*
X1221417Y818275D01*
X1221250Y818567D01*
X1220958Y818775D01*
X1220625Y818817D01*
X1220292Y818733D01*
X1220083Y818525D01*
X1219917Y818233D01*
X1219875Y817942D01*
X1219917Y817650D01*
X1220083Y817275D01*
X1219000Y817400D01*
Y818525D01*
G01X1221000Y820083D02*
X1221292Y820333D01*
X1221458Y820667D01*
X1221500Y821042D01*
X1221458Y821375D01*
X1221250Y821708D01*
X1221000Y821917D01*
X1220750Y821958D01*
X1220458Y821875D01*
X1220250Y821583D01*
X1220167Y821292D01*
Y820917D01*
G01Y821292D02*
X1220042Y821542D01*
X1219833Y821750D01*
X1219583Y821833D01*
X1219333Y821750D01*
X1219125Y821542D01*
X1219000Y821167D01*
X1219042Y820792D01*
X1219208Y820417D01*
G01X1219000Y824100D02*
X1219083Y823767D01*
X1219292Y823517D01*
X1219542Y823350D01*
X1219875Y823225D01*
X1220250Y823183D01*
X1220625Y823225D01*
X1220958Y823350D01*
X1221208Y823517D01*
X1221417Y823767D01*
X1221500Y824100D01*
X1221417Y824433D01*
X1221208Y824683D01*
X1220958Y824850D01*
X1220625Y824975D01*
X1220250Y825017D01*
X1219875Y824975D01*
X1219542Y824850D01*
X1219292Y824683D01*
X1219083Y824433D01*
X1219000Y824100D01*
G01X1221500Y827200D02*
X1219000D01*
X1219500Y826700D01*
G01X1221500D02*
Y827700D01*
G01X1231817Y825292D02*
X1231567Y825417D01*
X1231275Y825500D01*
X1230942D01*
X1230567Y825375D01*
X1230275Y825167D01*
X1230067Y824917D01*
X1229900Y824500D01*
X1229858Y824125D01*
X1229942Y823750D01*
X1230067Y823500D01*
X1230317Y823250D01*
X1230608Y823083D01*
X1230900Y823000D01*
X1231192D01*
X1231483Y823083D01*
X1231733Y823208D01*
X1231942Y823375D01*
G01X1233292Y823292D02*
X1233583Y823083D01*
X1233917Y823000D01*
X1234250Y823083D01*
X1234542Y823333D01*
X1234750Y823708D01*
X1234833Y824083D01*
Y824542D01*
X1234750Y824917D01*
X1234542Y825250D01*
X1234292Y825417D01*
X1234000Y825500D01*
X1233667Y825417D01*
X1233417Y825250D01*
X1233250Y825000D01*
X1233167Y824667D01*
X1233250Y824375D01*
X1233458Y824083D01*
X1233708Y823917D01*
X1234000Y823875D01*
X1234333Y823958D01*
X1234583Y824167D01*
X1234833Y824542D01*
G01X1237100Y825500D02*
X1236767Y825417D01*
X1236517Y825208D01*
X1236350Y824958D01*
X1236225Y824625D01*
X1236183Y824250D01*
X1236225Y823875D01*
X1236350Y823542D01*
X1236517Y823292D01*
X1236767Y823083D01*
X1237100Y823000D01*
X1237433Y823083D01*
X1237683Y823292D01*
X1237850Y823542D01*
X1237975Y823875D01*
X1238017Y824250D01*
X1237975Y824625D01*
X1237850Y824958D01*
X1237683Y825208D01*
X1237433Y825417D01*
X1237100Y825500D01*
G01X1227500Y840933D02*
X1229292D01*
X1229667Y841100D01*
X1229917Y841433D01*
X1230000Y841850D01*
X1229917Y842267D01*
X1229667Y842600D01*
X1229292Y842767D01*
X1227500D01*
G01X1230000Y844950D02*
X1227500D01*
X1228000Y844450D01*
G01X1230000D02*
Y845450D01*
G01Y847967D02*
X1229458Y848050D01*
X1229000Y848175D01*
X1228583Y848342D01*
X1228125Y848550D01*
X1227500Y848883D01*
Y847217D01*
G01X1229708Y850442D02*
X1229917Y850733D01*
X1230000Y851067D01*
X1229917Y851400D01*
X1229667Y851692D01*
X1229292Y851900D01*
X1228917Y851983D01*
X1228458D01*
X1228083Y851900D01*
X1227750Y851692D01*
X1227583Y851442D01*
X1227500Y851150D01*
X1227583Y850817D01*
X1227750Y850567D01*
X1228000Y850400D01*
X1228333Y850317D01*
X1228625Y850400D01*
X1228917Y850608D01*
X1229083Y850858D01*
X1229125Y851150D01*
X1229042Y851483D01*
X1228833Y851733D01*
X1228458Y851983D01*
G01X1227200Y829500D02*
Y833500D01*
X1219800D01*
G01X1216500Y872200D02*
Y858800D01*
G01X1219000Y861983D02*
X1220792D01*
X1221167Y862150D01*
X1221417Y862483D01*
X1221500Y862900D01*
X1221417Y863317D01*
X1221167Y863650D01*
X1220792Y863817D01*
X1219000D01*
G01X1221500Y866500D02*
X1219000D01*
X1220792Y864958D01*
Y867042D01*
G01X1221500Y869600D02*
X1219000D01*
X1220792Y868058D01*
Y870142D01*
G01X1232869Y863524D02*
Y866024D01*
X1233910D01*
X1234244Y865899D01*
X1234452Y865732D01*
X1234535Y865399D01*
X1234452Y865066D01*
X1234202Y864857D01*
X1233910Y864732D01*
X1232869D01*
G01X1233910D02*
X1234535Y863524D01*
G01X1235885Y863899D02*
X1236135Y863691D01*
X1236427Y863566D01*
X1236802Y863524D01*
X1237177Y863607D01*
X1237469Y863774D01*
X1237677Y864066D01*
X1237719Y864399D01*
X1237635Y864732D01*
X1237427Y864941D01*
X1237135Y865107D01*
X1236844Y865149D01*
X1236552Y865107D01*
X1236177Y864941D01*
X1236302Y866024D01*
X1237427D01*
G01X1239819Y863524D02*
X1239902Y864066D01*
X1240027Y864524D01*
X1240194Y864941D01*
X1240402Y865399D01*
X1240735Y866024D01*
X1239069D01*
G01X1243502Y863524D02*
Y866024D01*
X1241960Y864232D01*
X1244044D01*
G01X1250500Y182200D02*
X1244300D01*
Y169800D01*
X1250500D01*
G01Y195200D02*
X1244300D01*
Y182800D01*
X1250500D01*
G01X1252877Y239500D02*
Y243500D01*
X1245477D01*
G01X1252877D02*
Y247500D01*
X1245477D01*
G01X1241977Y257000D02*
Y253000D01*
X1249377D01*
G01X1241977Y261500D02*
Y257500D01*
X1249377D01*
G01X1249700Y270500D02*
Y274500D01*
X1242300D01*
G01X1249700Y266500D02*
Y270500D01*
X1242300D01*
G01X1251904Y329331D02*
X1248904D01*
G01X1247167Y381683D02*
X1247042Y381850D01*
X1246833Y381975D01*
X1246542Y382058D01*
X1246292Y381975D01*
X1246125Y381808D01*
X1246000Y381517D01*
Y380392D01*
X1248500D01*
Y381767D01*
X1248333Y382058D01*
X1248083Y382225D01*
X1247792Y382308D01*
X1247500Y382225D01*
X1247250Y381975D01*
X1247167Y381683D01*
Y380392D01*
G01X1248500Y383408D02*
X1246000Y384450D01*
X1248500Y385492D01*
G01X1247625Y385117D02*
Y383783D01*
G01X1246000Y387550D02*
X1248500D01*
G01X1246000Y386592D02*
Y388508D01*
G01X1248500Y390650D02*
X1246000D01*
X1246500Y390150D01*
G01X1248500D02*
Y391150D01*
G01X1251904Y368701D02*
X1248904D01*
G01X1245017Y416000D02*
Y418500D01*
X1246017D01*
X1246350Y418375D01*
X1246600Y418083D01*
X1246683Y417750D01*
X1246600Y417417D01*
X1246392Y417167D01*
X1246017Y417042D01*
X1245017D01*
G01X1248117Y416000D02*
Y418500D01*
X1249158D01*
X1249492Y418375D01*
X1249700Y418208D01*
X1249783Y417875D01*
X1249700Y417542D01*
X1249450Y417333D01*
X1249158Y417208D01*
X1248117D01*
G01X1249158D02*
X1249783Y416000D01*
G01X1251133Y416500D02*
X1251383Y416208D01*
X1251717Y416042D01*
X1252092Y416000D01*
X1252425Y416042D01*
X1252758Y416250D01*
X1252967Y416500D01*
X1253008Y416750D01*
X1252925Y417042D01*
X1252633Y417250D01*
X1252342Y417333D01*
X1251967D01*
G01X1252342D02*
X1252592Y417458D01*
X1252800Y417667D01*
X1252883Y417917D01*
X1252800Y418167D01*
X1252592Y418375D01*
X1252217Y418500D01*
X1251842Y418458D01*
X1251467Y418292D01*
G01X1255067Y416000D02*
X1255150Y416542D01*
X1255275Y417000D01*
X1255442Y417417D01*
X1255650Y417875D01*
X1255983Y418500D01*
X1254317D01*
G01X1245017Y412000D02*
Y414500D01*
X1246017D01*
X1246350Y414375D01*
X1246600Y414083D01*
X1246683Y413750D01*
X1246600Y413417D01*
X1246392Y413167D01*
X1246017Y413042D01*
X1245017D01*
G01X1248117Y412000D02*
Y414500D01*
X1249158D01*
X1249492Y414375D01*
X1249700Y414208D01*
X1249783Y413875D01*
X1249700Y413542D01*
X1249450Y413333D01*
X1249158Y413208D01*
X1248117D01*
G01X1249158D02*
X1249783Y412000D01*
G01X1251133Y412500D02*
X1251383Y412208D01*
X1251717Y412042D01*
X1252092Y412000D01*
X1252425Y412042D01*
X1252758Y412250D01*
X1252967Y412500D01*
X1253008Y412750D01*
X1252925Y413042D01*
X1252633Y413250D01*
X1252342Y413333D01*
X1251967D01*
G01X1252342D02*
X1252592Y413458D01*
X1252800Y413667D01*
X1252883Y413917D01*
X1252800Y414167D01*
X1252592Y414375D01*
X1252217Y414500D01*
X1251842Y414458D01*
X1251467Y414292D01*
G01X1254233Y412500D02*
X1254483Y412208D01*
X1254817Y412042D01*
X1255192Y412000D01*
X1255525Y412042D01*
X1255858Y412250D01*
X1256067Y412500D01*
X1256108Y412750D01*
X1256025Y413042D01*
X1255733Y413250D01*
X1255442Y413333D01*
X1255067D01*
G01X1255442D02*
X1255692Y413458D01*
X1255900Y413667D01*
X1255983Y413917D01*
X1255900Y414167D01*
X1255692Y414375D01*
X1255317Y414500D01*
X1254942Y414458D01*
X1254567Y414292D01*
G01X1253700Y429500D02*
Y433500D01*
X1246300D01*
G01X1253700Y425500D02*
Y429500D01*
X1246300D01*
G01X1245017Y420000D02*
Y422500D01*
X1246017D01*
X1246350Y422375D01*
X1246600Y422083D01*
X1246683Y421750D01*
X1246600Y421417D01*
X1246392Y421167D01*
X1246017Y421042D01*
X1245017D01*
G01X1249867Y422292D02*
X1249617Y422417D01*
X1249325Y422500D01*
X1248992D01*
X1248617Y422375D01*
X1248325Y422167D01*
X1248117Y421917D01*
X1247950Y421500D01*
X1247908Y421125D01*
X1247992Y420750D01*
X1248117Y420500D01*
X1248367Y420250D01*
X1248658Y420083D01*
X1248950Y420000D01*
X1249242D01*
X1249533Y420083D01*
X1249783Y420208D01*
X1249992Y420375D01*
G01X1251133Y420500D02*
X1251383Y420208D01*
X1251717Y420042D01*
X1252092Y420000D01*
X1252425Y420042D01*
X1252758Y420250D01*
X1252967Y420500D01*
X1253008Y420750D01*
X1252925Y421042D01*
X1252633Y421250D01*
X1252342Y421333D01*
X1251967D01*
G01X1252342D02*
X1252592Y421458D01*
X1252800Y421667D01*
X1252883Y421917D01*
X1252800Y422167D01*
X1252592Y422375D01*
X1252217Y422500D01*
X1251842Y422458D01*
X1251467Y422292D01*
G01X1255150Y420000D02*
Y422500D01*
X1254650Y422000D01*
G01Y420000D02*
X1255650D01*
G01X1237067Y440000D02*
Y442500D01*
X1238067D01*
X1238400Y442375D01*
X1238650Y442083D01*
X1238733Y441750D01*
X1238650Y441417D01*
X1238442Y441167D01*
X1238067Y441042D01*
X1237067D01*
G01X1240083Y442500D02*
Y440708D01*
X1240250Y440333D01*
X1240583Y440083D01*
X1241000Y440000D01*
X1241417Y440083D01*
X1241750Y440333D01*
X1241917Y440708D01*
Y442500D01*
G01X1243308Y442083D02*
X1243558Y442333D01*
X1243850Y442458D01*
X1244183Y442500D01*
X1244600Y442417D01*
X1244892Y442208D01*
X1244975Y441958D01*
X1244933Y441708D01*
X1244767Y441500D01*
X1243933Y441083D01*
X1243558Y440792D01*
X1243308Y440375D01*
X1243225Y440000D01*
X1244975D01*
G01X1237067Y444000D02*
Y446500D01*
X1238067D01*
X1238400Y446375D01*
X1238650Y446083D01*
X1238733Y445750D01*
X1238650Y445417D01*
X1238442Y445167D01*
X1238067Y445042D01*
X1237067D01*
G01X1241250Y445250D02*
X1242083D01*
Y444500D01*
X1241833Y444250D01*
X1241542Y444083D01*
X1241125Y444000D01*
X1240708Y444083D01*
X1240417Y444250D01*
X1240167Y444500D01*
X1240000Y444792D01*
X1239917Y445125D01*
Y445417D01*
X1240000Y445667D01*
X1240167Y445958D01*
X1240417Y446208D01*
X1240667Y446375D01*
X1241000Y446500D01*
X1241292D01*
X1241625Y446417D01*
X1241875Y446250D01*
G01X1243183Y444500D02*
X1243433Y444208D01*
X1243767Y444042D01*
X1244142Y444000D01*
X1244475Y444042D01*
X1244808Y444250D01*
X1245017Y444500D01*
X1245058Y444750D01*
X1244975Y445042D01*
X1244683Y445250D01*
X1244392Y445333D01*
X1244017D01*
G01X1244392D02*
X1244642Y445458D01*
X1244850Y445667D01*
X1244933Y445917D01*
X1244850Y446167D01*
X1244642Y446375D01*
X1244267Y446500D01*
X1243892Y446458D01*
X1243517Y446292D01*
G01X1242800Y453500D02*
Y449500D01*
X1250200D01*
G01X1249000Y463300D02*
X1253000D01*
Y470700D01*
G01X1248500D02*
X1244500D01*
Y463300D01*
G01X1244000Y470700D02*
X1240000D01*
Y463300D01*
G01X1242800Y458000D02*
Y454000D01*
X1250200D01*
G01X1249000Y470800D02*
X1253000D01*
Y478200D01*
G01X1247000Y473017D02*
X1244500D01*
Y474017D01*
X1244625Y474350D01*
X1244917Y474600D01*
X1245250Y474683D01*
X1245583Y474600D01*
X1245833Y474392D01*
X1245958Y474017D01*
Y473017D01*
G01X1247000Y476117D02*
X1244500D01*
Y477158D01*
X1244625Y477492D01*
X1244792Y477700D01*
X1245125Y477783D01*
X1245458Y477700D01*
X1245667Y477450D01*
X1245792Y477158D01*
Y476117D01*
G01Y477158D02*
X1247000Y477783D01*
G01X1246500Y479133D02*
X1246792Y479383D01*
X1246958Y479717D01*
X1247000Y480092D01*
X1246958Y480425D01*
X1246750Y480758D01*
X1246500Y480967D01*
X1246250Y481008D01*
X1245958Y480925D01*
X1245750Y480633D01*
X1245667Y480342D01*
Y479967D01*
G01Y480342D02*
X1245542Y480592D01*
X1245333Y480800D01*
X1245083Y480883D01*
X1244833Y480800D01*
X1244625Y480592D01*
X1244500Y480217D01*
X1244542Y479842D01*
X1244708Y479467D01*
G01X1244500Y483150D02*
X1244583Y482817D01*
X1244792Y482567D01*
X1245042Y482400D01*
X1245375Y482275D01*
X1245750Y482233D01*
X1246125Y482275D01*
X1246458Y482400D01*
X1246708Y482567D01*
X1246917Y482817D01*
X1247000Y483150D01*
X1246917Y483483D01*
X1246708Y483733D01*
X1246458Y483900D01*
X1246125Y484025D01*
X1245750Y484067D01*
X1245375Y484025D01*
X1245042Y483900D01*
X1244792Y483733D01*
X1244583Y483483D01*
X1244500Y483150D01*
G01X1242500Y473017D02*
X1240000D01*
Y474017D01*
X1240125Y474350D01*
X1240417Y474600D01*
X1240750Y474683D01*
X1241083Y474600D01*
X1241333Y474392D01*
X1241458Y474017D01*
Y473017D01*
G01X1242500Y476117D02*
X1240000D01*
Y477158D01*
X1240125Y477492D01*
X1240292Y477700D01*
X1240625Y477783D01*
X1240958Y477700D01*
X1241167Y477450D01*
X1241292Y477158D01*
Y476117D01*
G01Y477158D02*
X1242500Y477783D01*
G01X1242000Y479133D02*
X1242292Y479383D01*
X1242458Y479717D01*
X1242500Y480092D01*
X1242458Y480425D01*
X1242250Y480758D01*
X1242000Y480967D01*
X1241750Y481008D01*
X1241458Y480925D01*
X1241250Y480633D01*
X1241167Y480342D01*
Y479967D01*
G01Y480342D02*
X1241042Y480592D01*
X1240833Y480800D01*
X1240583Y480883D01*
X1240333Y480800D01*
X1240125Y480592D01*
X1240000Y480217D01*
X1240042Y479842D01*
X1240208Y479467D01*
G01X1242500Y483150D02*
X1240000D01*
X1240500Y482650D01*
G01X1242500D02*
Y483650D01*
G01X1243017Y489000D02*
Y491500D01*
X1244017D01*
X1244350Y491375D01*
X1244600Y491083D01*
X1244683Y490750D01*
X1244600Y490417D01*
X1244392Y490167D01*
X1244017Y490042D01*
X1243017D01*
G01X1246117Y489000D02*
Y491500D01*
X1247158D01*
X1247492Y491375D01*
X1247700Y491208D01*
X1247783Y490875D01*
X1247700Y490542D01*
X1247450Y490333D01*
X1247158Y490208D01*
X1246117D01*
G01X1247158D02*
X1247783Y489000D01*
G01X1249258Y491083D02*
X1249508Y491333D01*
X1249800Y491458D01*
X1250133Y491500D01*
X1250550Y491417D01*
X1250842Y491208D01*
X1250925Y490958D01*
X1250883Y490708D01*
X1250717Y490500D01*
X1249883Y490083D01*
X1249508Y489792D01*
X1249258Y489375D01*
X1249175Y489000D01*
X1250925D01*
G01X1252233Y489375D02*
X1252483Y489167D01*
X1252775Y489042D01*
X1253150Y489000D01*
X1253525Y489083D01*
X1253817Y489250D01*
X1254025Y489542D01*
X1254067Y489875D01*
X1253983Y490208D01*
X1253775Y490417D01*
X1253483Y490583D01*
X1253192Y490625D01*
X1252900Y490583D01*
X1252525Y490417D01*
X1252650Y491500D01*
X1253775D01*
G01X1243017Y485500D02*
Y488000D01*
X1244017D01*
X1244350Y487875D01*
X1244600Y487583D01*
X1244683Y487250D01*
X1244600Y486917D01*
X1244392Y486667D01*
X1244017Y486542D01*
X1243017D01*
G01X1246117Y485500D02*
Y488000D01*
X1247158D01*
X1247492Y487875D01*
X1247700Y487708D01*
X1247783Y487375D01*
X1247700Y487042D01*
X1247450Y486833D01*
X1247158Y486708D01*
X1246117D01*
G01X1247158D02*
X1247783Y485500D01*
G01X1249258Y487583D02*
X1249508Y487833D01*
X1249800Y487958D01*
X1250133Y488000D01*
X1250550Y487917D01*
X1250842Y487708D01*
X1250925Y487458D01*
X1250883Y487208D01*
X1250717Y487000D01*
X1249883Y486583D01*
X1249508Y486292D01*
X1249258Y485875D01*
X1249175Y485500D01*
X1250925D01*
G01X1252442Y485792D02*
X1252733Y485583D01*
X1253067Y485500D01*
X1253400Y485583D01*
X1253692Y485833D01*
X1253900Y486208D01*
X1253983Y486583D01*
Y487042D01*
X1253900Y487417D01*
X1253692Y487750D01*
X1253442Y487917D01*
X1253150Y488000D01*
X1252817Y487917D01*
X1252567Y487750D01*
X1252400Y487500D01*
X1252317Y487167D01*
X1252400Y486875D01*
X1252608Y486583D01*
X1252858Y486417D01*
X1253150Y486375D01*
X1253483Y486458D01*
X1253733Y486667D01*
X1253983Y487042D01*
G01X1240483Y557500D02*
Y560000D01*
X1241317D01*
X1241650Y559875D01*
X1241900Y559708D01*
X1242108Y559458D01*
X1242275Y559167D01*
X1242317Y558750D01*
X1242275Y558333D01*
X1242108Y558042D01*
X1241900Y557792D01*
X1241650Y557625D01*
X1241317Y557500D01*
X1240483D01*
G01X1244500D02*
Y560000D01*
X1244000Y559500D01*
G01Y557500D02*
X1245000D01*
G01X1246683Y558000D02*
X1246933Y557708D01*
X1247267Y557542D01*
X1247642Y557500D01*
X1247975Y557542D01*
X1248308Y557750D01*
X1248517Y558000D01*
X1248558Y558250D01*
X1248475Y558542D01*
X1248183Y558750D01*
X1247892Y558833D01*
X1247517D01*
G01X1247892D02*
X1248142Y558958D01*
X1248350Y559167D01*
X1248433Y559417D01*
X1248350Y559667D01*
X1248142Y559875D01*
X1247767Y560000D01*
X1247392Y559958D01*
X1247017Y559792D01*
G01X1235717Y570792D02*
X1235467Y570917D01*
X1235175Y571000D01*
X1234842D01*
X1234467Y570875D01*
X1234175Y570667D01*
X1233967Y570417D01*
X1233800Y570000D01*
X1233758Y569625D01*
X1233842Y569250D01*
X1233967Y569000D01*
X1234217Y568750D01*
X1234508Y568583D01*
X1234800Y568500D01*
X1235092D01*
X1235383Y568583D01*
X1235633Y568708D01*
X1235842Y568875D01*
G01X1237900Y568500D02*
Y571000D01*
X1237400Y570500D01*
G01Y568500D02*
X1238400D01*
G01X1240208Y569542D02*
X1240500Y569833D01*
X1240750Y570000D01*
X1241083Y570083D01*
X1241375Y570000D01*
X1241583Y569833D01*
X1241750Y569583D01*
X1241792Y569292D01*
X1241750Y569042D01*
X1241583Y568792D01*
X1241333Y568583D01*
X1241042Y568500D01*
X1240708Y568583D01*
X1240417Y568833D01*
X1240250Y569208D01*
X1240208Y569625D01*
X1240292Y570167D01*
X1240417Y570458D01*
X1240625Y570750D01*
X1240917Y570958D01*
X1241208Y571000D01*
X1241500Y570917D01*
X1241708Y570708D01*
G01X1243392Y568792D02*
X1243683Y568583D01*
X1244017Y568500D01*
X1244350Y568583D01*
X1244642Y568833D01*
X1244850Y569208D01*
X1244933Y569583D01*
Y570042D01*
X1244850Y570417D01*
X1244642Y570750D01*
X1244392Y570917D01*
X1244100Y571000D01*
X1243767Y570917D01*
X1243517Y570750D01*
X1243350Y570500D01*
X1243267Y570167D01*
X1243350Y569875D01*
X1243558Y569583D01*
X1243808Y569417D01*
X1244100Y569375D01*
X1244433Y569458D01*
X1244683Y569667D01*
X1244933Y570042D01*
G01X1247200Y568500D02*
X1247492Y568542D01*
X1247825Y568667D01*
X1248033Y568875D01*
X1248117Y569167D01*
X1248033Y569458D01*
X1247783Y569708D01*
X1247408Y569833D01*
X1246992D01*
X1246742Y569917D01*
X1246533Y570125D01*
X1246450Y570417D01*
X1246575Y570708D01*
X1246867Y570917D01*
X1247200Y571000D01*
X1247533Y570917D01*
X1247825Y570708D01*
X1247950Y570417D01*
X1247867Y570125D01*
X1247658Y569917D01*
X1247408Y569833D01*
X1246992D01*
X1246617Y569708D01*
X1246367Y569458D01*
X1246283Y569167D01*
X1246367Y568875D01*
X1246575Y568667D01*
X1246908Y568542D01*
X1247200Y568500D01*
G01X1233500Y583300D02*
X1236000D01*
G01X1233500Y582342D02*
Y584258D01*
G01X1236000Y585567D02*
X1233500D01*
Y586567D01*
X1233625Y586900D01*
X1233917Y587150D01*
X1234250Y587233D01*
X1234583Y587150D01*
X1234833Y586942D01*
X1234958Y586567D01*
Y585567D01*
G01X1236000Y589500D02*
X1235958Y589792D01*
X1235833Y590125D01*
X1235625Y590333D01*
X1235333Y590417D01*
X1235042Y590333D01*
X1234792Y590083D01*
X1234667Y589708D01*
Y589292D01*
X1234583Y589042D01*
X1234375Y588833D01*
X1234083Y588750D01*
X1233792Y588875D01*
X1233583Y589167D01*
X1233500Y589500D01*
X1233583Y589833D01*
X1233792Y590125D01*
X1234083Y590250D01*
X1234375Y590167D01*
X1234583Y589958D01*
X1234667Y589708D01*
Y589292D01*
X1234792Y588917D01*
X1235042Y588667D01*
X1235333Y588583D01*
X1235625Y588667D01*
X1235833Y588875D01*
X1235958Y589208D01*
X1236000Y589500D01*
G01X1233500Y592600D02*
X1233583Y592267D01*
X1233792Y592017D01*
X1234042Y591850D01*
X1234375Y591725D01*
X1234750Y591683D01*
X1235125Y591725D01*
X1235458Y591850D01*
X1235708Y592017D01*
X1235917Y592267D01*
X1236000Y592600D01*
X1235917Y592933D01*
X1235708Y593183D01*
X1235458Y593350D01*
X1235125Y593475D01*
X1234750Y593517D01*
X1234375Y593475D01*
X1234042Y593350D01*
X1233792Y593183D01*
X1233583Y592933D01*
X1233500Y592600D01*
G01Y595700D02*
X1233583Y595367D01*
X1233792Y595117D01*
X1234042Y594950D01*
X1234375Y594825D01*
X1234750Y594783D01*
X1235125Y594825D01*
X1235458Y594950D01*
X1235708Y595117D01*
X1235917Y595367D01*
X1236000Y595700D01*
X1235917Y596033D01*
X1235708Y596283D01*
X1235458Y596450D01*
X1235125Y596575D01*
X1234750Y596617D01*
X1234375Y596575D01*
X1234042Y596450D01*
X1233792Y596283D01*
X1233583Y596033D01*
X1233500Y595700D01*
G01X1237517Y575000D02*
Y577500D01*
X1238558D01*
X1238892Y577375D01*
X1239100Y577208D01*
X1239183Y576875D01*
X1239100Y576542D01*
X1238850Y576333D01*
X1238558Y576208D01*
X1237517D01*
G01X1238558D02*
X1239183Y575000D01*
G01X1240658Y576042D02*
X1240950Y576333D01*
X1241200Y576500D01*
X1241533Y576583D01*
X1241825Y576500D01*
X1242033Y576333D01*
X1242200Y576083D01*
X1242242Y575792D01*
X1242200Y575542D01*
X1242033Y575292D01*
X1241783Y575083D01*
X1241492Y575000D01*
X1241158Y575083D01*
X1240867Y575333D01*
X1240700Y575708D01*
X1240658Y576125D01*
X1240742Y576667D01*
X1240867Y576958D01*
X1241075Y577250D01*
X1241367Y577458D01*
X1241658Y577500D01*
X1241950Y577417D01*
X1242158Y577208D01*
G01X1243633Y575375D02*
X1243883Y575167D01*
X1244175Y575042D01*
X1244550Y575000D01*
X1244925Y575083D01*
X1245217Y575250D01*
X1245425Y575542D01*
X1245467Y575875D01*
X1245383Y576208D01*
X1245175Y576417D01*
X1244883Y576583D01*
X1244592Y576625D01*
X1244300Y576583D01*
X1243925Y576417D01*
X1244050Y577500D01*
X1245175D01*
G01X1246733Y575375D02*
X1246983Y575167D01*
X1247275Y575042D01*
X1247650Y575000D01*
X1248025Y575083D01*
X1248317Y575250D01*
X1248525Y575542D01*
X1248567Y575875D01*
X1248483Y576208D01*
X1248275Y576417D01*
X1247983Y576583D01*
X1247692Y576625D01*
X1247400Y576583D01*
X1247025Y576417D01*
X1247150Y577500D01*
X1248275D01*
G01X1245700Y591000D02*
Y595000D01*
X1238300D01*
G01X1245700Y596000D02*
Y600000D01*
X1238300D01*
G01X1234017Y629000D02*
Y631500D01*
X1235058D01*
X1235392Y631375D01*
X1235600Y631208D01*
X1235683Y630875D01*
X1235600Y630542D01*
X1235350Y630333D01*
X1235058Y630208D01*
X1234017D01*
G01X1235058D02*
X1235683Y629000D01*
G01X1237033Y629500D02*
X1237283Y629208D01*
X1237617Y629042D01*
X1237992Y629000D01*
X1238325Y629042D01*
X1238658Y629250D01*
X1238867Y629500D01*
X1238908Y629750D01*
X1238825Y630042D01*
X1238533Y630250D01*
X1238242Y630333D01*
X1237867D01*
G01X1238242D02*
X1238492Y630458D01*
X1238700Y630667D01*
X1238783Y630917D01*
X1238700Y631167D01*
X1238492Y631375D01*
X1238117Y631500D01*
X1237742Y631458D01*
X1237367Y631292D01*
G01X1241050Y629000D02*
Y631500D01*
X1240550Y631000D01*
G01Y629000D02*
X1241550D01*
G01X1244150Y631500D02*
X1243817Y631417D01*
X1243567Y631208D01*
X1243400Y630958D01*
X1243275Y630625D01*
X1243233Y630250D01*
X1243275Y629875D01*
X1243400Y629542D01*
X1243567Y629292D01*
X1243817Y629083D01*
X1244150Y629000D01*
X1244483Y629083D01*
X1244733Y629292D01*
X1244900Y629542D01*
X1245025Y629875D01*
X1245067Y630250D01*
X1245025Y630625D01*
X1244900Y630958D01*
X1244733Y631208D01*
X1244483Y631417D01*
X1244150Y631500D01*
G01X1234017Y637000D02*
Y639500D01*
X1235058D01*
X1235392Y639375D01*
X1235600Y639208D01*
X1235683Y638875D01*
X1235600Y638542D01*
X1235350Y638333D01*
X1235058Y638208D01*
X1234017D01*
G01X1235058D02*
X1235683Y637000D01*
G01X1237158Y639083D02*
X1237408Y639333D01*
X1237700Y639458D01*
X1238033Y639500D01*
X1238450Y639417D01*
X1238742Y639208D01*
X1238825Y638958D01*
X1238783Y638708D01*
X1238617Y638500D01*
X1237783Y638083D01*
X1237408Y637792D01*
X1237158Y637375D01*
X1237075Y637000D01*
X1238825D01*
G01X1240258Y638042D02*
X1240550Y638333D01*
X1240800Y638500D01*
X1241133Y638583D01*
X1241425Y638500D01*
X1241633Y638333D01*
X1241800Y638083D01*
X1241842Y637792D01*
X1241800Y637542D01*
X1241633Y637292D01*
X1241383Y637083D01*
X1241092Y637000D01*
X1240758Y637083D01*
X1240467Y637333D01*
X1240300Y637708D01*
X1240258Y638125D01*
X1240342Y638667D01*
X1240467Y638958D01*
X1240675Y639250D01*
X1240967Y639458D01*
X1241258Y639500D01*
X1241550Y639417D01*
X1241758Y639208D01*
G01X1243358Y639083D02*
X1243608Y639333D01*
X1243900Y639458D01*
X1244233Y639500D01*
X1244650Y639417D01*
X1244942Y639208D01*
X1245025Y638958D01*
X1244983Y638708D01*
X1244817Y638500D01*
X1243983Y638083D01*
X1243608Y637792D01*
X1243358Y637375D01*
X1243275Y637000D01*
X1245025D01*
G01X1255700Y641000D02*
Y645000D01*
X1248300D01*
G01X1234017Y633000D02*
Y635500D01*
X1235058D01*
X1235392Y635375D01*
X1235600Y635208D01*
X1235683Y634875D01*
X1235600Y634542D01*
X1235350Y634333D01*
X1235058Y634208D01*
X1234017D01*
G01X1235058D02*
X1235683Y633000D01*
G01X1237033Y633500D02*
X1237283Y633208D01*
X1237617Y633042D01*
X1237992Y633000D01*
X1238325Y633042D01*
X1238658Y633250D01*
X1238867Y633500D01*
X1238908Y633750D01*
X1238825Y634042D01*
X1238533Y634250D01*
X1238242Y634333D01*
X1237867D01*
G01X1238242D02*
X1238492Y634458D01*
X1238700Y634667D01*
X1238783Y634917D01*
X1238700Y635167D01*
X1238492Y635375D01*
X1238117Y635500D01*
X1237742Y635458D01*
X1237367Y635292D01*
G01X1241050Y635500D02*
X1240717Y635417D01*
X1240467Y635208D01*
X1240300Y634958D01*
X1240175Y634625D01*
X1240133Y634250D01*
X1240175Y633875D01*
X1240300Y633542D01*
X1240467Y633292D01*
X1240717Y633083D01*
X1241050Y633000D01*
X1241383Y633083D01*
X1241633Y633292D01*
X1241800Y633542D01*
X1241925Y633875D01*
X1241967Y634250D01*
X1241925Y634625D01*
X1241800Y634958D01*
X1241633Y635208D01*
X1241383Y635417D01*
X1241050Y635500D01*
G01X1244067Y633000D02*
X1244150Y633542D01*
X1244275Y634000D01*
X1244442Y634417D01*
X1244650Y634875D01*
X1244983Y635500D01*
X1243317D01*
G01X1255700Y637000D02*
Y641000D01*
X1248300D01*
G01X1255700Y633000D02*
Y637000D01*
X1248300D01*
G01X1255700Y649000D02*
Y653000D01*
X1248300D01*
G01X1255700Y655000D02*
Y659000D01*
X1248300D01*
G01X1251200D02*
Y663000D01*
X1243800D01*
G01X1255700Y645000D02*
Y649000D01*
X1248300D01*
G01X1244500Y664517D02*
X1242000D01*
Y665558D01*
X1242125Y665892D01*
X1242292Y666100D01*
X1242625Y666183D01*
X1242958Y666100D01*
X1243167Y665850D01*
X1243292Y665558D01*
Y664517D01*
G01Y665558D02*
X1244500Y666183D01*
G01Y668950D02*
X1242000D01*
X1243792Y667408D01*
Y669492D01*
G01X1244500Y672050D02*
X1242000D01*
X1243792Y670508D01*
Y672592D01*
G01X1244500Y674650D02*
X1242000D01*
X1242500Y674150D01*
G01X1244500D02*
Y675150D01*
G01X1248300Y673000D02*
Y669000D01*
X1255700D01*
G01X1236000Y665017D02*
X1233500D01*
Y666058D01*
X1233625Y666392D01*
X1233792Y666600D01*
X1234125Y666683D01*
X1234458Y666600D01*
X1234667Y666350D01*
X1234792Y666058D01*
Y665017D01*
G01Y666058D02*
X1236000Y666683D01*
G01Y669450D02*
X1233500D01*
X1235292Y667908D01*
Y669992D01*
G01X1234958Y671258D02*
X1234667Y671550D01*
X1234500Y671800D01*
X1234417Y672133D01*
X1234500Y672425D01*
X1234667Y672633D01*
X1234917Y672800D01*
X1235208Y672842D01*
X1235458Y672800D01*
X1235708Y672633D01*
X1235917Y672383D01*
X1236000Y672092D01*
X1235917Y671758D01*
X1235667Y671467D01*
X1235292Y671300D01*
X1234875Y671258D01*
X1234333Y671342D01*
X1234042Y671467D01*
X1233750Y671675D01*
X1233542Y671967D01*
X1233500Y672258D01*
X1233583Y672550D01*
X1233792Y672758D01*
G01X1236000Y675150D02*
X1233500D01*
X1234000Y674650D01*
G01X1236000D02*
Y675650D01*
G01X1255700Y665000D02*
Y669000D01*
X1248300D01*
G01Y686000D02*
Y682000D01*
X1255700D01*
G01Y686000D02*
Y690000D01*
X1248300D01*
G01X1255700Y678000D02*
Y682000D01*
X1248300D01*
G01X1255700Y705500D02*
Y709500D01*
X1248300D01*
G01X1255700Y701500D02*
Y705500D01*
X1248300D01*
G01X1243517Y729000D02*
Y731500D01*
X1244558D01*
X1244892Y731375D01*
X1245100Y731208D01*
X1245183Y730875D01*
X1245100Y730542D01*
X1244850Y730333D01*
X1244558Y730208D01*
X1243517D01*
G01X1244558D02*
X1245183Y729000D01*
G01X1246533Y729500D02*
X1246783Y729208D01*
X1247117Y729042D01*
X1247492Y729000D01*
X1247825Y729042D01*
X1248158Y729250D01*
X1248367Y729500D01*
X1248408Y729750D01*
X1248325Y730042D01*
X1248033Y730250D01*
X1247742Y730333D01*
X1247367D01*
G01X1247742D02*
X1247992Y730458D01*
X1248200Y730667D01*
X1248283Y730917D01*
X1248200Y731167D01*
X1247992Y731375D01*
X1247617Y731500D01*
X1247242Y731458D01*
X1246867Y731292D01*
G01X1250550Y729000D02*
Y731500D01*
X1250050Y731000D01*
G01Y729000D02*
X1251050D01*
G01X1253650D02*
Y731500D01*
X1253150Y731000D01*
G01Y729000D02*
X1254150D01*
G01X1235300Y731500D02*
Y727500D01*
X1242700D01*
G01X1255700Y709500D02*
Y713500D01*
X1248300D01*
G01X1245017Y745000D02*
Y747500D01*
X1246058D01*
X1246392Y747375D01*
X1246600Y747208D01*
X1246683Y746875D01*
X1246600Y746542D01*
X1246350Y746333D01*
X1246058Y746208D01*
X1245017D01*
G01X1246058D02*
X1246683Y745000D01*
G01X1248950D02*
X1249242Y745042D01*
X1249575Y745167D01*
X1249783Y745375D01*
X1249867Y745667D01*
X1249783Y745958D01*
X1249533Y746208D01*
X1249158Y746333D01*
X1248742D01*
X1248492Y746417D01*
X1248283Y746625D01*
X1248200Y746917D01*
X1248325Y747208D01*
X1248617Y747417D01*
X1248950Y747500D01*
X1249283Y747417D01*
X1249575Y747208D01*
X1249700Y746917D01*
X1249617Y746625D01*
X1249408Y746417D01*
X1249158Y746333D01*
X1248742D01*
X1248367Y746208D01*
X1248117Y745958D01*
X1248033Y745667D01*
X1248117Y745375D01*
X1248325Y745167D01*
X1248658Y745042D01*
X1248950Y745000D01*
G01X1252050Y747500D02*
X1251717Y747417D01*
X1251467Y747208D01*
X1251300Y746958D01*
X1251175Y746625D01*
X1251133Y746250D01*
X1251175Y745875D01*
X1251300Y745542D01*
X1251467Y745292D01*
X1251717Y745083D01*
X1252050Y745000D01*
X1252383Y745083D01*
X1252633Y745292D01*
X1252800Y745542D01*
X1252925Y745875D01*
X1252967Y746250D01*
X1252925Y746625D01*
X1252800Y746958D01*
X1252633Y747208D01*
X1252383Y747417D01*
X1252050Y747500D01*
G01X1255650Y745000D02*
Y747500D01*
X1254108Y745708D01*
X1256192D01*
G01X1245017Y754000D02*
Y756500D01*
X1246058D01*
X1246392Y756375D01*
X1246600Y756208D01*
X1246683Y755875D01*
X1246600Y755542D01*
X1246350Y755333D01*
X1246058Y755208D01*
X1245017D01*
G01X1246058D02*
X1246683Y754000D01*
G01X1248950D02*
X1249242Y754042D01*
X1249575Y754167D01*
X1249783Y754375D01*
X1249867Y754667D01*
X1249783Y754958D01*
X1249533Y755208D01*
X1249158Y755333D01*
X1248742D01*
X1248492Y755417D01*
X1248283Y755625D01*
X1248200Y755917D01*
X1248325Y756208D01*
X1248617Y756417D01*
X1248950Y756500D01*
X1249283Y756417D01*
X1249575Y756208D01*
X1249700Y755917D01*
X1249617Y755625D01*
X1249408Y755417D01*
X1249158Y755333D01*
X1248742D01*
X1248367Y755208D01*
X1248117Y754958D01*
X1248033Y754667D01*
X1248117Y754375D01*
X1248325Y754167D01*
X1248658Y754042D01*
X1248950Y754000D01*
G01X1252050Y756500D02*
X1251717Y756417D01*
X1251467Y756208D01*
X1251300Y755958D01*
X1251175Y755625D01*
X1251133Y755250D01*
X1251175Y754875D01*
X1251300Y754542D01*
X1251467Y754292D01*
X1251717Y754083D01*
X1252050Y754000D01*
X1252383Y754083D01*
X1252633Y754292D01*
X1252800Y754542D01*
X1252925Y754875D01*
X1252967Y755250D01*
X1252925Y755625D01*
X1252800Y755958D01*
X1252633Y756208D01*
X1252383Y756417D01*
X1252050Y756500D01*
G01X1255150Y754000D02*
Y756500D01*
X1254650Y756000D01*
G01Y754000D02*
X1255650D01*
G01X1245017Y749500D02*
Y752000D01*
X1246058D01*
X1246392Y751875D01*
X1246600Y751708D01*
X1246683Y751375D01*
X1246600Y751042D01*
X1246350Y750833D01*
X1246058Y750708D01*
X1245017D01*
G01X1246058D02*
X1246683Y749500D01*
G01X1248950D02*
X1249242Y749542D01*
X1249575Y749667D01*
X1249783Y749875D01*
X1249867Y750167D01*
X1249783Y750458D01*
X1249533Y750708D01*
X1249158Y750833D01*
X1248742D01*
X1248492Y750917D01*
X1248283Y751125D01*
X1248200Y751417D01*
X1248325Y751708D01*
X1248617Y751917D01*
X1248950Y752000D01*
X1249283Y751917D01*
X1249575Y751708D01*
X1249700Y751417D01*
X1249617Y751125D01*
X1249408Y750917D01*
X1249158Y750833D01*
X1248742D01*
X1248367Y750708D01*
X1248117Y750458D01*
X1248033Y750167D01*
X1248117Y749875D01*
X1248325Y749667D01*
X1248658Y749542D01*
X1248950Y749500D01*
G01X1252050Y752000D02*
X1251717Y751917D01*
X1251467Y751708D01*
X1251300Y751458D01*
X1251175Y751125D01*
X1251133Y750750D01*
X1251175Y750375D01*
X1251300Y750042D01*
X1251467Y749792D01*
X1251717Y749583D01*
X1252050Y749500D01*
X1252383Y749583D01*
X1252633Y749792D01*
X1252800Y750042D01*
X1252925Y750375D01*
X1252967Y750750D01*
X1252925Y751125D01*
X1252800Y751458D01*
X1252633Y751708D01*
X1252383Y751917D01*
X1252050Y752000D01*
G01X1254233Y750000D02*
X1254483Y749708D01*
X1254817Y749542D01*
X1255192Y749500D01*
X1255525Y749542D01*
X1255858Y749750D01*
X1256067Y750000D01*
X1256108Y750250D01*
X1256025Y750542D01*
X1255733Y750750D01*
X1255442Y750833D01*
X1255067D01*
G01X1255442D02*
X1255692Y750958D01*
X1255900Y751167D01*
X1255983Y751417D01*
X1255900Y751667D01*
X1255692Y751875D01*
X1255317Y752000D01*
X1254942Y751958D01*
X1254567Y751792D01*
G01X1252850Y769600D02*
Y764600D01*
X1247850D01*
G01X1241984Y765500D02*
Y763500D01*
G01X1249700Y760000D02*
Y764000D01*
X1242300D01*
G01X1244500Y791433D02*
X1246292D01*
X1246667Y791600D01*
X1246917Y791933D01*
X1247000Y792350D01*
X1246917Y792767D01*
X1246667Y793100D01*
X1246292Y793267D01*
X1244500D01*
G01X1247000Y795450D02*
X1244500D01*
X1245000Y794950D01*
G01X1247000D02*
Y795950D01*
G01Y798550D02*
X1246958Y798842D01*
X1246833Y799175D01*
X1246625Y799383D01*
X1246333Y799467D01*
X1246042Y799383D01*
X1245792Y799133D01*
X1245667Y798758D01*
Y798342D01*
X1245583Y798092D01*
X1245375Y797883D01*
X1245083Y797800D01*
X1244792Y797925D01*
X1244583Y798217D01*
X1244500Y798550D01*
X1244583Y798883D01*
X1244792Y799175D01*
X1245083Y799300D01*
X1245375Y799217D01*
X1245583Y799008D01*
X1245667Y798758D01*
Y798342D01*
X1245792Y797967D01*
X1246042Y797717D01*
X1246333Y797633D01*
X1246625Y797717D01*
X1246833Y797925D01*
X1246958Y798258D01*
X1247000Y798550D01*
G01Y801650D02*
X1244500D01*
X1245000Y801150D01*
G01X1247000D02*
Y802150D01*
G01X1252850Y781400D02*
Y786400D01*
X1247850D01*
G01X1236079Y785500D02*
Y787500D01*
G01X1245921Y785500D02*
Y788500D01*
G01X1233100Y830900D02*
Y844300D01*
G01X1243100Y830900D02*
X1233100D01*
G01X1243100Y844300D02*
Y830900D01*
G01X1233100Y844300D02*
X1243100D01*
G01X1251500Y843517D02*
X1249000D01*
Y844558D01*
X1249125Y844892D01*
X1249292Y845100D01*
X1249625Y845183D01*
X1249958Y845100D01*
X1250167Y844850D01*
X1250292Y844558D01*
Y843517D01*
G01Y844558D02*
X1251500Y845183D01*
G01X1251125Y846533D02*
X1251333Y846783D01*
X1251458Y847075D01*
X1251500Y847450D01*
X1251417Y847825D01*
X1251250Y848117D01*
X1250958Y848325D01*
X1250625Y848367D01*
X1250292Y848283D01*
X1250083Y848075D01*
X1249917Y847783D01*
X1249875Y847492D01*
X1249917Y847200D01*
X1250083Y846825D01*
X1249000Y846950D01*
Y848075D01*
G01X1251500Y850467D02*
X1250958Y850550D01*
X1250500Y850675D01*
X1250083Y850842D01*
X1249625Y851050D01*
X1249000Y851383D01*
Y849717D01*
G01X1251000Y852733D02*
X1251292Y852983D01*
X1251458Y853317D01*
X1251500Y853692D01*
X1251458Y854025D01*
X1251250Y854358D01*
X1251000Y854567D01*
X1250750Y854608D01*
X1250458Y854525D01*
X1250250Y854233D01*
X1250167Y853942D01*
Y853567D01*
G01Y853942D02*
X1250042Y854192D01*
X1249833Y854400D01*
X1249583Y854483D01*
X1249333Y854400D01*
X1249125Y854192D01*
X1249000Y853817D01*
X1249042Y853442D01*
X1249208Y853067D01*
G01X1248600Y833400D02*
X1252600D01*
Y840800D01*
G01X1240100Y859300D02*
X1236100D01*
Y851900D01*
G01X1260128Y3975D02*
X1260336Y4308D01*
X1260461Y4683D01*
Y5017D01*
X1260336Y5350D01*
X1260128Y5600D01*
X1259836Y5725D01*
X1259544Y5642D01*
X1259294Y5433D01*
X1259128Y5058D01*
X1259044Y4558D01*
X1258878Y4267D01*
X1258586Y4142D01*
X1258294Y4225D01*
X1258086Y4433D01*
X1257961Y4725D01*
Y5017D01*
X1258044Y5308D01*
X1258253Y5558D01*
G01X1257961Y6700D02*
X1260461Y7283D01*
X1257961Y7950D01*
X1260461Y8617D01*
X1257961Y9200D01*
G01X1258378Y10258D02*
X1258128Y10508D01*
X1258003Y10800D01*
X1257961Y11133D01*
X1258044Y11550D01*
X1258253Y11842D01*
X1258503Y11925D01*
X1258753Y11883D01*
X1258961Y11717D01*
X1259378Y10883D01*
X1259669Y10508D01*
X1260086Y10258D01*
X1260461Y10175D01*
Y11925D01*
G01X1257961Y14150D02*
X1258044Y13817D01*
X1258253Y13567D01*
X1258503Y13400D01*
X1258836Y13275D01*
X1259211Y13233D01*
X1259586Y13275D01*
X1259919Y13400D01*
X1260169Y13567D01*
X1260378Y13817D01*
X1260461Y14150D01*
X1260378Y14483D01*
X1260169Y14733D01*
X1259919Y14900D01*
X1259586Y15025D01*
X1259211Y15067D01*
X1258836Y15025D01*
X1258503Y14900D01*
X1258253Y14733D01*
X1258044Y14483D01*
X1257961Y14150D01*
G01X1255517Y22500D02*
Y25000D01*
X1256558D01*
X1256892Y24875D01*
X1257100Y24708D01*
X1257183Y24375D01*
X1257100Y24042D01*
X1256850Y23833D01*
X1256558Y23708D01*
X1255517D01*
G01X1256558D02*
X1257183Y22500D01*
G01X1259950D02*
Y25000D01*
X1258408Y23208D01*
X1260492D01*
G01X1261633Y23000D02*
X1261883Y22708D01*
X1262217Y22542D01*
X1262592Y22500D01*
X1262925Y22542D01*
X1263258Y22750D01*
X1263467Y23000D01*
X1263508Y23250D01*
X1263425Y23542D01*
X1263133Y23750D01*
X1262842Y23833D01*
X1262467D01*
G01X1262842D02*
X1263092Y23958D01*
X1263300Y24167D01*
X1263383Y24417D01*
X1263300Y24667D01*
X1263092Y24875D01*
X1262717Y25000D01*
X1262342Y24958D01*
X1261967Y24792D01*
G01X1264733Y23000D02*
X1264983Y22708D01*
X1265317Y22542D01*
X1265692Y22500D01*
X1266025Y22542D01*
X1266358Y22750D01*
X1266567Y23000D01*
X1266608Y23250D01*
X1266525Y23542D01*
X1266233Y23750D01*
X1265942Y23833D01*
X1265567D01*
G01X1265942D02*
X1266192Y23958D01*
X1266400Y24167D01*
X1266483Y24417D01*
X1266400Y24667D01*
X1266192Y24875D01*
X1265817Y25000D01*
X1265442Y24958D01*
X1265067Y24792D01*
G01X1265166Y43033D02*
Y34133D01*
G01D02*
X1282866D01*
G01X1258800Y32000D02*
Y28000D01*
X1266200D01*
G01X1259000Y41700D02*
X1255000D01*
Y34300D01*
G01X1282866Y43033D02*
X1265166D01*
G01X1259500Y46517D02*
X1257000D01*
Y47558D01*
X1257125Y47892D01*
X1257292Y48100D01*
X1257625Y48183D01*
X1257958Y48100D01*
X1258167Y47850D01*
X1258292Y47558D01*
Y46517D01*
G01Y47558D02*
X1259500Y48183D01*
G01X1259125Y49533D02*
X1259333Y49783D01*
X1259458Y50075D01*
X1259500Y50450D01*
X1259417Y50825D01*
X1259250Y51117D01*
X1258958Y51325D01*
X1258625Y51367D01*
X1258292Y51283D01*
X1258083Y51075D01*
X1257917Y50783D01*
X1257875Y50492D01*
X1257917Y50200D01*
X1258083Y49825D01*
X1257000Y49950D01*
Y51075D01*
G01X1259000Y52633D02*
X1259292Y52883D01*
X1259458Y53217D01*
X1259500Y53592D01*
X1259458Y53925D01*
X1259250Y54258D01*
X1259000Y54467D01*
X1258750Y54508D01*
X1258458Y54425D01*
X1258250Y54133D01*
X1258167Y53842D01*
Y53467D01*
G01Y53842D02*
X1258042Y54092D01*
X1257833Y54300D01*
X1257583Y54383D01*
X1257333Y54300D01*
X1257125Y54092D01*
X1257000Y53717D01*
X1257042Y53342D01*
X1257208Y52967D01*
G01X1259500Y56650D02*
X1257000D01*
X1257500Y56150D01*
G01X1259500D02*
Y57150D01*
G01X1256500Y169800D02*
X1262700D01*
Y182200D01*
X1256500D01*
G01Y182800D02*
X1262700D01*
Y195200D01*
X1256500D01*
G01X1261267Y198792D02*
X1261017Y198917D01*
X1260725Y199000D01*
X1260392D01*
X1260017Y198875D01*
X1259725Y198667D01*
X1259517Y198417D01*
X1259350Y198000D01*
X1259308Y197625D01*
X1259392Y197250D01*
X1259517Y197000D01*
X1259767Y196750D01*
X1260058Y196583D01*
X1260350Y196500D01*
X1260642D01*
X1260933Y196583D01*
X1261183Y196708D01*
X1261392Y196875D01*
G01X1262658Y198583D02*
X1262908Y198833D01*
X1263200Y198958D01*
X1263533Y199000D01*
X1263950Y198917D01*
X1264242Y198708D01*
X1264325Y198458D01*
X1264283Y198208D01*
X1264117Y198000D01*
X1263283Y197583D01*
X1262908Y197292D01*
X1262658Y196875D01*
X1262575Y196500D01*
X1264325D01*
G01X1267050D02*
Y199000D01*
X1265508Y197208D01*
X1267592D01*
G01X1268942Y196792D02*
X1269233Y196583D01*
X1269567Y196500D01*
X1269900Y196583D01*
X1270192Y196833D01*
X1270400Y197208D01*
X1270483Y197583D01*
Y198042D01*
X1270400Y198417D01*
X1270192Y198750D01*
X1269942Y198917D01*
X1269650Y199000D01*
X1269317Y198917D01*
X1269067Y198750D01*
X1268900Y198500D01*
X1268817Y198167D01*
X1268900Y197875D01*
X1269108Y197583D01*
X1269358Y197417D01*
X1269650Y197375D01*
X1269983Y197458D01*
X1270233Y197667D01*
X1270483Y198042D01*
G01X1261267Y206792D02*
X1261017Y206917D01*
X1260725Y207000D01*
X1260392D01*
X1260017Y206875D01*
X1259725Y206667D01*
X1259517Y206417D01*
X1259350Y206000D01*
X1259308Y205625D01*
X1259392Y205250D01*
X1259517Y205000D01*
X1259767Y204750D01*
X1260058Y204583D01*
X1260350Y204500D01*
X1260642D01*
X1260933Y204583D01*
X1261183Y204708D01*
X1261392Y204875D01*
G01X1262658Y206583D02*
X1262908Y206833D01*
X1263200Y206958D01*
X1263533Y207000D01*
X1263950Y206917D01*
X1264242Y206708D01*
X1264325Y206458D01*
X1264283Y206208D01*
X1264117Y206000D01*
X1263283Y205583D01*
X1262908Y205292D01*
X1262658Y204875D01*
X1262575Y204500D01*
X1264325D01*
G01X1266550D02*
X1266842Y204542D01*
X1267175Y204667D01*
X1267383Y204875D01*
X1267467Y205167D01*
X1267383Y205458D01*
X1267133Y205708D01*
X1266758Y205833D01*
X1266342D01*
X1266092Y205917D01*
X1265883Y206125D01*
X1265800Y206417D01*
X1265925Y206708D01*
X1266217Y206917D01*
X1266550Y207000D01*
X1266883Y206917D01*
X1267175Y206708D01*
X1267300Y206417D01*
X1267217Y206125D01*
X1267008Y205917D01*
X1266758Y205833D01*
X1266342D01*
X1265967Y205708D01*
X1265717Y205458D01*
X1265633Y205167D01*
X1265717Y204875D01*
X1265925Y204667D01*
X1266258Y204542D01*
X1266550Y204500D01*
G01X1269650Y207000D02*
X1269317Y206917D01*
X1269067Y206708D01*
X1268900Y206458D01*
X1268775Y206125D01*
X1268733Y205750D01*
X1268775Y205375D01*
X1268900Y205042D01*
X1269067Y204792D01*
X1269317Y204583D01*
X1269650Y204500D01*
X1269983Y204583D01*
X1270233Y204792D01*
X1270400Y205042D01*
X1270525Y205375D01*
X1270567Y205750D01*
X1270525Y206125D01*
X1270400Y206458D01*
X1270233Y206708D01*
X1269983Y206917D01*
X1269650Y207000D01*
G01X1261267Y202792D02*
X1261017Y202917D01*
X1260725Y203000D01*
X1260392D01*
X1260017Y202875D01*
X1259725Y202667D01*
X1259517Y202417D01*
X1259350Y202000D01*
X1259308Y201625D01*
X1259392Y201250D01*
X1259517Y201000D01*
X1259767Y200750D01*
X1260058Y200583D01*
X1260350Y200500D01*
X1260642D01*
X1260933Y200583D01*
X1261183Y200708D01*
X1261392Y200875D01*
G01X1262658Y202583D02*
X1262908Y202833D01*
X1263200Y202958D01*
X1263533Y203000D01*
X1263950Y202917D01*
X1264242Y202708D01*
X1264325Y202458D01*
X1264283Y202208D01*
X1264117Y202000D01*
X1263283Y201583D01*
X1262908Y201292D01*
X1262658Y200875D01*
X1262575Y200500D01*
X1264325D01*
G01X1266550D02*
X1266842Y200542D01*
X1267175Y200667D01*
X1267383Y200875D01*
X1267467Y201167D01*
X1267383Y201458D01*
X1267133Y201708D01*
X1266758Y201833D01*
X1266342D01*
X1266092Y201917D01*
X1265883Y202125D01*
X1265800Y202417D01*
X1265925Y202708D01*
X1266217Y202917D01*
X1266550Y203000D01*
X1266883Y202917D01*
X1267175Y202708D01*
X1267300Y202417D01*
X1267217Y202125D01*
X1267008Y201917D01*
X1266758Y201833D01*
X1266342D01*
X1265967Y201708D01*
X1265717Y201458D01*
X1265633Y201167D01*
X1265717Y200875D01*
X1265925Y200667D01*
X1266258Y200542D01*
X1266550Y200500D01*
G01X1268858Y202583D02*
X1269108Y202833D01*
X1269400Y202958D01*
X1269733Y203000D01*
X1270150Y202917D01*
X1270442Y202708D01*
X1270525Y202458D01*
X1270483Y202208D01*
X1270317Y202000D01*
X1269483Y201583D01*
X1269108Y201292D01*
X1268858Y200875D01*
X1268775Y200500D01*
X1270525D01*
G01X1259188Y219500D02*
Y223500D01*
X1251788D01*
G01X1260967Y210992D02*
X1260717Y211117D01*
X1260425Y211200D01*
X1260092D01*
X1259717Y211075D01*
X1259425Y210867D01*
X1259217Y210617D01*
X1259050Y210200D01*
X1259008Y209825D01*
X1259092Y209450D01*
X1259217Y209200D01*
X1259467Y208950D01*
X1259758Y208783D01*
X1260050Y208700D01*
X1260342D01*
X1260633Y208783D01*
X1260883Y208908D01*
X1261092Y209075D01*
G01X1262358Y210783D02*
X1262608Y211033D01*
X1262900Y211158D01*
X1263233Y211200D01*
X1263650Y211117D01*
X1263942Y210908D01*
X1264025Y210658D01*
X1263983Y210408D01*
X1263817Y210200D01*
X1262983Y209783D01*
X1262608Y209492D01*
X1262358Y209075D01*
X1262275Y208700D01*
X1264025D01*
G01X1266250D02*
X1266542Y208742D01*
X1266875Y208867D01*
X1267083Y209075D01*
X1267167Y209367D01*
X1267083Y209658D01*
X1266833Y209908D01*
X1266458Y210033D01*
X1266042D01*
X1265792Y210117D01*
X1265583Y210325D01*
X1265500Y210617D01*
X1265625Y210908D01*
X1265917Y211117D01*
X1266250Y211200D01*
X1266583Y211117D01*
X1266875Y210908D01*
X1267000Y210617D01*
X1266917Y210325D01*
X1266708Y210117D01*
X1266458Y210033D01*
X1266042D01*
X1265667Y209908D01*
X1265417Y209658D01*
X1265333Y209367D01*
X1265417Y209075D01*
X1265625Y208867D01*
X1265958Y208742D01*
X1266250Y208700D01*
G01X1269350D02*
Y211200D01*
X1268850Y210700D01*
G01Y208700D02*
X1269850D01*
G01X1259188Y224000D02*
Y228000D01*
X1251788D01*
G01X1259188Y228500D02*
Y232500D01*
X1251788D01*
G01Y237000D02*
Y233000D01*
X1259188D01*
G01X1255694Y257500D02*
Y260000D01*
X1256735D01*
X1257069Y259875D01*
X1257277Y259708D01*
X1257360Y259375D01*
X1257277Y259042D01*
X1257027Y258833D01*
X1256735Y258708D01*
X1255694D01*
G01X1256735D02*
X1257360Y257500D01*
G01X1258835Y259583D02*
X1259085Y259833D01*
X1259377Y259958D01*
X1259710Y260000D01*
X1260127Y259917D01*
X1260419Y259708D01*
X1260502Y259458D01*
X1260460Y259208D01*
X1260294Y259000D01*
X1259460Y258583D01*
X1259085Y258292D01*
X1258835Y257875D01*
X1258752Y257500D01*
X1260502D01*
G01X1261935Y259583D02*
X1262185Y259833D01*
X1262477Y259958D01*
X1262810Y260000D01*
X1263227Y259917D01*
X1263519Y259708D01*
X1263602Y259458D01*
X1263560Y259208D01*
X1263394Y259000D01*
X1262560Y258583D01*
X1262185Y258292D01*
X1261935Y257875D01*
X1261852Y257500D01*
X1263602D01*
G01X1266327D02*
Y260000D01*
X1264785Y258208D01*
X1266869D01*
G01X1255694Y262000D02*
Y264500D01*
X1256735D01*
X1257069Y264375D01*
X1257277Y264208D01*
X1257360Y263875D01*
X1257277Y263542D01*
X1257027Y263333D01*
X1256735Y263208D01*
X1255694D01*
G01X1256735D02*
X1257360Y262000D01*
G01X1258835Y264083D02*
X1259085Y264333D01*
X1259377Y264458D01*
X1259710Y264500D01*
X1260127Y264417D01*
X1260419Y264208D01*
X1260502Y263958D01*
X1260460Y263708D01*
X1260294Y263500D01*
X1259460Y263083D01*
X1259085Y262792D01*
X1258835Y262375D01*
X1258752Y262000D01*
X1260502D01*
G01X1261935Y264083D02*
X1262185Y264333D01*
X1262477Y264458D01*
X1262810Y264500D01*
X1263227Y264417D01*
X1263519Y264208D01*
X1263602Y263958D01*
X1263560Y263708D01*
X1263394Y263500D01*
X1262560Y263083D01*
X1262185Y262792D01*
X1261935Y262375D01*
X1261852Y262000D01*
X1263602D01*
G01X1264910Y262375D02*
X1265160Y262167D01*
X1265452Y262042D01*
X1265827Y262000D01*
X1266202Y262083D01*
X1266494Y262250D01*
X1266702Y262542D01*
X1266744Y262875D01*
X1266660Y263208D01*
X1266452Y263417D01*
X1266160Y263583D01*
X1265869Y263625D01*
X1265577Y263583D01*
X1265202Y263417D01*
X1265327Y264500D01*
X1266452D01*
G01X1252517Y267000D02*
Y269500D01*
X1253558D01*
X1253892Y269375D01*
X1254100Y269208D01*
X1254183Y268875D01*
X1254100Y268542D01*
X1253850Y268333D01*
X1253558Y268208D01*
X1252517D01*
G01X1253558D02*
X1254183Y267000D01*
G01X1255658Y269083D02*
X1255908Y269333D01*
X1256200Y269458D01*
X1256533Y269500D01*
X1256950Y269417D01*
X1257242Y269208D01*
X1257325Y268958D01*
X1257283Y268708D01*
X1257117Y268500D01*
X1256283Y268083D01*
X1255908Y267792D01*
X1255658Y267375D01*
X1255575Y267000D01*
X1257325D01*
G01X1259467D02*
X1259550Y267542D01*
X1259675Y268000D01*
X1259842Y268417D01*
X1260050Y268875D01*
X1260383Y269500D01*
X1258717D01*
G01X1261733Y267500D02*
X1261983Y267208D01*
X1262317Y267042D01*
X1262692Y267000D01*
X1263025Y267042D01*
X1263358Y267250D01*
X1263567Y267500D01*
X1263608Y267750D01*
X1263525Y268042D01*
X1263233Y268250D01*
X1262942Y268333D01*
X1262567D01*
G01X1262942D02*
X1263192Y268458D01*
X1263400Y268667D01*
X1263483Y268917D01*
X1263400Y269167D01*
X1263192Y269375D01*
X1262817Y269500D01*
X1262442Y269458D01*
X1262067Y269292D01*
G01X1252517Y272000D02*
Y274500D01*
X1253558D01*
X1253892Y274375D01*
X1254100Y274208D01*
X1254183Y273875D01*
X1254100Y273542D01*
X1253850Y273333D01*
X1253558Y273208D01*
X1252517D01*
G01X1253558D02*
X1254183Y272000D01*
G01X1255658Y274083D02*
X1255908Y274333D01*
X1256200Y274458D01*
X1256533Y274500D01*
X1256950Y274417D01*
X1257242Y274208D01*
X1257325Y273958D01*
X1257283Y273708D01*
X1257117Y273500D01*
X1256283Y273083D01*
X1255908Y272792D01*
X1255658Y272375D01*
X1255575Y272000D01*
X1257325D01*
G01X1259467D02*
X1259550Y272542D01*
X1259675Y273000D01*
X1259842Y273417D01*
X1260050Y273875D01*
X1260383Y274500D01*
X1258717D01*
G01X1261858Y274083D02*
X1262108Y274333D01*
X1262400Y274458D01*
X1262733Y274500D01*
X1263150Y274417D01*
X1263442Y274208D01*
X1263525Y273958D01*
X1263483Y273708D01*
X1263317Y273500D01*
X1262483Y273083D01*
X1262108Y272792D01*
X1261858Y272375D01*
X1261775Y272000D01*
X1263525D01*
G01X1253204Y395866D02*
X1278004D01*
Y302166D01*
X1253204D01*
Y395866D01*
G01X1250404Y330831D02*
Y327831D01*
G01Y370201D02*
Y367201D01*
G01X1260668Y458134D02*
X1255668D01*
Y453134D01*
G01X1263562Y457127D02*
Y460127D01*
G01X1264200Y478717D02*
X1261700D01*
Y479717D01*
X1261825Y480050D01*
X1262117Y480300D01*
X1262450Y480383D01*
X1262783Y480300D01*
X1263033Y480092D01*
X1263158Y479717D01*
Y478717D01*
G01X1264200Y481817D02*
X1261700D01*
Y482858D01*
X1261825Y483192D01*
X1261992Y483400D01*
X1262325Y483483D01*
X1262658Y483400D01*
X1262867Y483150D01*
X1262992Y482858D01*
Y481817D01*
G01Y482858D02*
X1264200Y483483D01*
G01Y485750D02*
X1261700D01*
X1262200Y485250D01*
G01X1264200D02*
Y486250D01*
G01X1263908Y488142D02*
X1264117Y488433D01*
X1264200Y488767D01*
X1264117Y489100D01*
X1263867Y489392D01*
X1263492Y489600D01*
X1263117Y489683D01*
X1262658D01*
X1262283Y489600D01*
X1261950Y489392D01*
X1261783Y489142D01*
X1261700Y488850D01*
X1261783Y488517D01*
X1261950Y488267D01*
X1262200Y488100D01*
X1262533Y488017D01*
X1262825Y488100D01*
X1263117Y488308D01*
X1263283Y488558D01*
X1263325Y488850D01*
X1263242Y489183D01*
X1263033Y489433D01*
X1262658Y489683D01*
G01X1258500Y479017D02*
X1256000D01*
Y480017D01*
X1256125Y480350D01*
X1256417Y480600D01*
X1256750Y480683D01*
X1257083Y480600D01*
X1257333Y480392D01*
X1257458Y480017D01*
Y479017D01*
G01X1256208Y483867D02*
X1256083Y483617D01*
X1256000Y483325D01*
Y482992D01*
X1256125Y482617D01*
X1256333Y482325D01*
X1256583Y482117D01*
X1257000Y481950D01*
X1257375Y481908D01*
X1257750Y481992D01*
X1258000Y482117D01*
X1258250Y482367D01*
X1258417Y482658D01*
X1258500Y482950D01*
Y483242D01*
X1258417Y483533D01*
X1258292Y483783D01*
X1258125Y483992D01*
G01X1256417Y485258D02*
X1256167Y485508D01*
X1256042Y485800D01*
X1256000Y486133D01*
X1256083Y486550D01*
X1256292Y486842D01*
X1256542Y486925D01*
X1256792Y486883D01*
X1257000Y486717D01*
X1257417Y485883D01*
X1257708Y485508D01*
X1258125Y485258D01*
X1258500Y485175D01*
Y486925D01*
G01X1257458Y488358D02*
X1257167Y488650D01*
X1257000Y488900D01*
X1256917Y489233D01*
X1257000Y489525D01*
X1257167Y489733D01*
X1257417Y489900D01*
X1257708Y489942D01*
X1257958Y489900D01*
X1258208Y489733D01*
X1258417Y489483D01*
X1258500Y489192D01*
X1258417Y488858D01*
X1258167Y488567D01*
X1257792Y488400D01*
X1257375Y488358D01*
X1256833Y488442D01*
X1256542Y488567D01*
X1256250Y488775D01*
X1256042Y489067D01*
X1256000Y489358D01*
X1256083Y489650D01*
X1256292Y489858D01*
G01X1267000Y552300D02*
X1256450D01*
Y556500D01*
X1253000D01*
Y561500D01*
X1256450D01*
Y565700D01*
X1267000D01*
Y552300D01*
G01X1263000Y579800D02*
X1264800Y581900D01*
X1267000Y579800D01*
G01X1270600Y579700D02*
Y598900D01*
X1259400D01*
Y579700D01*
X1270600D01*
Y580100D01*
G01X1255800Y579000D02*
Y575000D01*
X1263200D01*
G01X1258983Y607500D02*
Y605708D01*
X1259150Y605333D01*
X1259483Y605083D01*
X1259900Y605000D01*
X1260317Y605083D01*
X1260650Y605333D01*
X1260817Y605708D01*
Y607500D01*
G01X1263500Y605000D02*
Y607500D01*
X1261958Y605708D01*
X1264042D01*
G01X1265183Y605500D02*
X1265433Y605208D01*
X1265767Y605042D01*
X1266142Y605000D01*
X1266475Y605042D01*
X1266808Y605250D01*
X1267017Y605500D01*
X1267058Y605750D01*
X1266975Y606042D01*
X1266683Y606250D01*
X1266392Y606333D01*
X1266017D01*
G01X1266392D02*
X1266642Y606458D01*
X1266850Y606667D01*
X1266933Y606917D01*
X1266850Y607167D01*
X1266642Y607375D01*
X1266267Y607500D01*
X1265892Y607458D01*
X1265517Y607292D01*
G01X1262000Y636017D02*
X1259500D01*
Y637058D01*
X1259625Y637392D01*
X1259792Y637600D01*
X1260125Y637683D01*
X1260458Y637600D01*
X1260667Y637350D01*
X1260792Y637058D01*
Y636017D01*
G01Y637058D02*
X1262000Y637683D01*
G01Y640450D02*
X1259500D01*
X1261292Y638908D01*
Y640992D01*
G01X1261708Y642342D02*
X1261917Y642633D01*
X1262000Y642967D01*
X1261917Y643300D01*
X1261667Y643592D01*
X1261292Y643800D01*
X1260917Y643883D01*
X1260458D01*
X1260083Y643800D01*
X1259750Y643592D01*
X1259583Y643342D01*
X1259500Y643050D01*
X1259583Y642717D01*
X1259750Y642467D01*
X1260000Y642300D01*
X1260333Y642217D01*
X1260625Y642300D01*
X1260917Y642508D01*
X1261083Y642758D01*
X1261125Y643050D01*
X1261042Y643383D01*
X1260833Y643633D01*
X1260458Y643883D01*
G01X1259917Y645358D02*
X1259667Y645608D01*
X1259542Y645900D01*
X1259500Y646233D01*
X1259583Y646650D01*
X1259792Y646942D01*
X1260042Y647025D01*
X1260292Y646983D01*
X1260500Y646817D01*
X1260917Y645983D01*
X1261208Y645608D01*
X1261625Y645358D01*
X1262000Y645275D01*
Y647025D01*
G01X1263200Y659000D02*
Y663000D01*
X1255800D01*
G01X1263200Y655000D02*
Y659000D01*
X1255800D01*
G01X1263200Y649000D02*
Y653000D01*
X1255800D01*
G01X1258517Y671500D02*
Y674000D01*
X1259558D01*
X1259892Y673875D01*
X1260100Y673708D01*
X1260183Y673375D01*
X1260100Y673042D01*
X1259850Y672833D01*
X1259558Y672708D01*
X1258517D01*
G01X1259558D02*
X1260183Y671500D01*
G01X1261533Y672000D02*
X1261783Y671708D01*
X1262117Y671542D01*
X1262492Y671500D01*
X1262825Y671542D01*
X1263158Y671750D01*
X1263367Y672000D01*
X1263408Y672250D01*
X1263325Y672542D01*
X1263033Y672750D01*
X1262742Y672833D01*
X1262367D01*
G01X1262742D02*
X1262992Y672958D01*
X1263200Y673167D01*
X1263283Y673417D01*
X1263200Y673667D01*
X1262992Y673875D01*
X1262617Y674000D01*
X1262242Y673958D01*
X1261867Y673792D01*
G01X1264633Y672000D02*
X1264883Y671708D01*
X1265217Y671542D01*
X1265592Y671500D01*
X1265925Y671542D01*
X1266258Y671750D01*
X1266467Y672000D01*
X1266508Y672250D01*
X1266425Y672542D01*
X1266133Y672750D01*
X1265842Y672833D01*
X1265467D01*
G01X1265842D02*
X1266092Y672958D01*
X1266300Y673167D01*
X1266383Y673417D01*
X1266300Y673667D01*
X1266092Y673875D01*
X1265717Y674000D01*
X1265342Y673958D01*
X1264967Y673792D01*
G01X1267858Y672542D02*
X1268150Y672833D01*
X1268400Y673000D01*
X1268733Y673083D01*
X1269025Y673000D01*
X1269233Y672833D01*
X1269400Y672583D01*
X1269442Y672292D01*
X1269400Y672042D01*
X1269233Y671792D01*
X1268983Y671583D01*
X1268692Y671500D01*
X1268358Y671583D01*
X1268067Y671833D01*
X1267900Y672208D01*
X1267858Y672625D01*
X1267942Y673167D01*
X1268067Y673458D01*
X1268275Y673750D01*
X1268567Y673958D01*
X1268858Y674000D01*
X1269150Y673917D01*
X1269358Y673708D01*
G01X1263200Y665500D02*
Y669500D01*
X1255800D01*
G01X1258517Y679000D02*
Y681500D01*
X1259558D01*
X1259892Y681375D01*
X1260100Y681208D01*
X1260183Y680875D01*
X1260100Y680542D01*
X1259850Y680333D01*
X1259558Y680208D01*
X1258517D01*
G01X1259558D02*
X1260183Y679000D01*
G01X1262450D02*
X1262742Y679042D01*
X1263075Y679167D01*
X1263283Y679375D01*
X1263367Y679667D01*
X1263283Y679958D01*
X1263033Y680208D01*
X1262658Y680333D01*
X1262242D01*
X1261992Y680417D01*
X1261783Y680625D01*
X1261700Y680917D01*
X1261825Y681208D01*
X1262117Y681417D01*
X1262450Y681500D01*
X1262783Y681417D01*
X1263075Y681208D01*
X1263200Y680917D01*
X1263117Y680625D01*
X1262908Y680417D01*
X1262658Y680333D01*
X1262242D01*
X1261867Y680208D01*
X1261617Y679958D01*
X1261533Y679667D01*
X1261617Y679375D01*
X1261825Y679167D01*
X1262158Y679042D01*
X1262450Y679000D01*
G01X1265550Y681500D02*
X1265217Y681417D01*
X1264967Y681208D01*
X1264800Y680958D01*
X1264675Y680625D01*
X1264633Y680250D01*
X1264675Y679875D01*
X1264800Y679542D01*
X1264967Y679292D01*
X1265217Y679083D01*
X1265550Y679000D01*
X1265883Y679083D01*
X1266133Y679292D01*
X1266300Y679542D01*
X1266425Y679875D01*
X1266467Y680250D01*
X1266425Y680625D01*
X1266300Y680958D01*
X1266133Y681208D01*
X1265883Y681417D01*
X1265550Y681500D01*
G01X1267858Y681083D02*
X1268108Y681333D01*
X1268400Y681458D01*
X1268733Y681500D01*
X1269150Y681417D01*
X1269442Y681208D01*
X1269525Y680958D01*
X1269483Y680708D01*
X1269317Y680500D01*
X1268483Y680083D01*
X1268108Y679792D01*
X1267858Y679375D01*
X1267775Y679000D01*
X1269525D01*
G01X1260267Y677792D02*
X1260017Y677917D01*
X1259725Y678000D01*
X1259392D01*
X1259017Y677875D01*
X1258725Y677667D01*
X1258517Y677417D01*
X1258350Y677000D01*
X1258308Y676625D01*
X1258392Y676250D01*
X1258517Y676000D01*
X1258767Y675750D01*
X1259058Y675583D01*
X1259350Y675500D01*
X1259642D01*
X1259933Y675583D01*
X1260183Y675708D01*
X1260392Y675875D01*
G01X1262450Y675500D02*
Y678000D01*
X1261950Y677500D01*
G01Y675500D02*
X1262950D01*
G01X1265550D02*
X1265842Y675542D01*
X1266175Y675667D01*
X1266383Y675875D01*
X1266467Y676167D01*
X1266383Y676458D01*
X1266133Y676708D01*
X1265758Y676833D01*
X1265342D01*
X1265092Y676917D01*
X1264883Y677125D01*
X1264800Y677417D01*
X1264925Y677708D01*
X1265217Y677917D01*
X1265550Y678000D01*
X1265883Y677917D01*
X1266175Y677708D01*
X1266300Y677417D01*
X1266217Y677125D01*
X1266008Y676917D01*
X1265758Y676833D01*
X1265342D01*
X1264967Y676708D01*
X1264717Y676458D01*
X1264633Y676167D01*
X1264717Y675875D01*
X1264925Y675667D01*
X1265258Y675542D01*
X1265550Y675500D01*
G01X1268650D02*
X1268942Y675542D01*
X1269275Y675667D01*
X1269483Y675875D01*
X1269567Y676167D01*
X1269483Y676458D01*
X1269233Y676708D01*
X1268858Y676833D01*
X1268442D01*
X1268192Y676917D01*
X1267983Y677125D01*
X1267900Y677417D01*
X1268025Y677708D01*
X1268317Y677917D01*
X1268650Y678000D01*
X1268983Y677917D01*
X1269275Y677708D01*
X1269400Y677417D01*
X1269317Y677125D01*
X1269108Y676917D01*
X1268858Y676833D01*
X1268442D01*
X1268067Y676708D01*
X1267817Y676458D01*
X1267733Y676167D01*
X1267817Y675875D01*
X1268025Y675667D01*
X1268358Y675542D01*
X1268650Y675500D01*
G01X1270000Y683500D02*
Y695000D01*
X1256000D01*
Y693000D01*
G01X1257517Y686500D02*
Y689000D01*
X1258558D01*
X1258892Y688875D01*
X1259100Y688708D01*
X1259183Y688375D01*
X1259100Y688042D01*
X1258850Y687833D01*
X1258558Y687708D01*
X1257517D01*
G01X1258558D02*
X1259183Y686500D01*
G01X1260658Y688583D02*
X1260908Y688833D01*
X1261200Y688958D01*
X1261533Y689000D01*
X1261950Y688917D01*
X1262242Y688708D01*
X1262325Y688458D01*
X1262283Y688208D01*
X1262117Y688000D01*
X1261283Y687583D01*
X1260908Y687292D01*
X1260658Y686875D01*
X1260575Y686500D01*
X1262325D01*
G01X1264467D02*
X1264550Y687042D01*
X1264675Y687500D01*
X1264842Y687917D01*
X1265050Y688375D01*
X1265383Y689000D01*
X1263717D01*
G01X1266942Y686792D02*
X1267233Y686583D01*
X1267567Y686500D01*
X1267900Y686583D01*
X1268192Y686833D01*
X1268400Y687208D01*
X1268483Y687583D01*
Y688042D01*
X1268400Y688417D01*
X1268192Y688750D01*
X1267942Y688917D01*
X1267650Y689000D01*
X1267317Y688917D01*
X1267067Y688750D01*
X1266900Y688500D01*
X1266817Y688167D01*
X1266900Y687875D01*
X1267108Y687583D01*
X1267358Y687417D01*
X1267650Y687375D01*
X1267983Y687458D01*
X1268233Y687667D01*
X1268483Y688042D01*
G01X1257517Y690500D02*
Y693000D01*
X1258558D01*
X1258892Y692875D01*
X1259100Y692708D01*
X1259183Y692375D01*
X1259100Y692042D01*
X1258850Y691833D01*
X1258558Y691708D01*
X1257517D01*
G01X1258558D02*
X1259183Y690500D01*
G01X1260533Y690875D02*
X1260783Y690667D01*
X1261075Y690542D01*
X1261450Y690500D01*
X1261825Y690583D01*
X1262117Y690750D01*
X1262325Y691042D01*
X1262367Y691375D01*
X1262283Y691708D01*
X1262075Y691917D01*
X1261783Y692083D01*
X1261492Y692125D01*
X1261200Y692083D01*
X1260825Y691917D01*
X1260950Y693000D01*
X1262075D01*
G01X1264550Y690500D02*
X1264842Y690542D01*
X1265175Y690667D01*
X1265383Y690875D01*
X1265467Y691167D01*
X1265383Y691458D01*
X1265133Y691708D01*
X1264758Y691833D01*
X1264342D01*
X1264092Y691917D01*
X1263883Y692125D01*
X1263800Y692417D01*
X1263925Y692708D01*
X1264217Y692917D01*
X1264550Y693000D01*
X1264883Y692917D01*
X1265175Y692708D01*
X1265300Y692417D01*
X1265217Y692125D01*
X1265008Y691917D01*
X1264758Y691833D01*
X1264342D01*
X1263967Y691708D01*
X1263717Y691458D01*
X1263633Y691167D01*
X1263717Y690875D01*
X1263925Y690667D01*
X1264258Y690542D01*
X1264550Y690500D01*
G01X1266858Y692583D02*
X1267108Y692833D01*
X1267400Y692958D01*
X1267733Y693000D01*
X1268150Y692917D01*
X1268442Y692708D01*
X1268525Y692458D01*
X1268483Y692208D01*
X1268317Y692000D01*
X1267483Y691583D01*
X1267108Y691292D01*
X1266858Y690875D01*
X1266775Y690500D01*
X1268525D01*
G01X1264208Y698767D02*
X1264083Y698517D01*
X1264000Y698225D01*
Y697892D01*
X1264125Y697517D01*
X1264333Y697225D01*
X1264583Y697017D01*
X1265000Y696850D01*
X1265375Y696808D01*
X1265750Y696892D01*
X1266000Y697017D01*
X1266250Y697267D01*
X1266417Y697558D01*
X1266500Y697850D01*
Y698142D01*
X1266417Y698433D01*
X1266292Y698683D01*
X1266125Y698892D01*
G01X1266500Y700950D02*
X1264000D01*
X1264500Y700450D01*
G01X1266500D02*
Y701450D01*
G01Y704050D02*
X1266458Y704342D01*
X1266333Y704675D01*
X1266125Y704883D01*
X1265833Y704967D01*
X1265542Y704883D01*
X1265292Y704633D01*
X1265167Y704258D01*
Y703842D01*
X1265083Y703592D01*
X1264875Y703383D01*
X1264583Y703300D01*
X1264292Y703425D01*
X1264083Y703717D01*
X1264000Y704050D01*
X1264083Y704383D01*
X1264292Y704675D01*
X1264583Y704800D01*
X1264875Y704717D01*
X1265083Y704508D01*
X1265167Y704258D01*
Y703842D01*
X1265292Y703467D01*
X1265542Y703217D01*
X1265833Y703133D01*
X1266125Y703217D01*
X1266333Y703425D01*
X1266458Y703758D01*
X1266500Y704050D01*
G01X1266208Y706442D02*
X1266417Y706733D01*
X1266500Y707067D01*
X1266417Y707400D01*
X1266167Y707692D01*
X1265792Y707900D01*
X1265417Y707983D01*
X1264958D01*
X1264583Y707900D01*
X1264250Y707692D01*
X1264083Y707442D01*
X1264000Y707150D01*
X1264083Y706817D01*
X1264250Y706567D01*
X1264500Y706400D01*
X1264833Y706317D01*
X1265125Y706400D01*
X1265417Y706608D01*
X1265583Y706858D01*
X1265625Y707150D01*
X1265542Y707483D01*
X1265333Y707733D01*
X1264958Y707983D01*
G01X1259708Y698767D02*
X1259583Y698517D01*
X1259500Y698225D01*
Y697892D01*
X1259625Y697517D01*
X1259833Y697225D01*
X1260083Y697017D01*
X1260500Y696850D01*
X1260875Y696808D01*
X1261250Y696892D01*
X1261500Y697017D01*
X1261750Y697267D01*
X1261917Y697558D01*
X1262000Y697850D01*
Y698142D01*
X1261917Y698433D01*
X1261792Y698683D01*
X1261625Y698892D01*
G01X1262000Y700950D02*
X1259500D01*
X1260000Y700450D01*
G01X1262000D02*
Y701450D01*
G01X1261708Y703342D02*
X1261917Y703633D01*
X1262000Y703967D01*
X1261917Y704300D01*
X1261667Y704592D01*
X1261292Y704800D01*
X1260917Y704883D01*
X1260458D01*
X1260083Y704800D01*
X1259750Y704592D01*
X1259583Y704342D01*
X1259500Y704050D01*
X1259583Y703717D01*
X1259750Y703467D01*
X1260000Y703300D01*
X1260333Y703217D01*
X1260625Y703300D01*
X1260917Y703508D01*
X1261083Y703758D01*
X1261125Y704050D01*
X1261042Y704383D01*
X1260833Y704633D01*
X1260458Y704883D01*
G01X1262000Y707150D02*
X1259500D01*
X1260000Y706650D01*
G01X1262000D02*
Y707650D01*
G01X1258517Y714000D02*
Y716500D01*
X1259558D01*
X1259892Y716375D01*
X1260100Y716208D01*
X1260183Y715875D01*
X1260100Y715542D01*
X1259850Y715333D01*
X1259558Y715208D01*
X1258517D01*
G01X1259558D02*
X1260183Y714000D01*
G01X1261533Y714500D02*
X1261783Y714208D01*
X1262117Y714042D01*
X1262492Y714000D01*
X1262825Y714042D01*
X1263158Y714250D01*
X1263367Y714500D01*
X1263408Y714750D01*
X1263325Y715042D01*
X1263033Y715250D01*
X1262742Y715333D01*
X1262367D01*
G01X1262742D02*
X1262992Y715458D01*
X1263200Y715667D01*
X1263283Y715917D01*
X1263200Y716167D01*
X1262992Y716375D01*
X1262617Y716500D01*
X1262242Y716458D01*
X1261867Y716292D01*
G01X1264758Y716083D02*
X1265008Y716333D01*
X1265300Y716458D01*
X1265633Y716500D01*
X1266050Y716417D01*
X1266342Y716208D01*
X1266425Y715958D01*
X1266383Y715708D01*
X1266217Y715500D01*
X1265383Y715083D01*
X1265008Y714792D01*
X1264758Y714375D01*
X1264675Y714000D01*
X1266425D01*
G01X1268650Y716500D02*
X1268317Y716417D01*
X1268067Y716208D01*
X1267900Y715958D01*
X1267775Y715625D01*
X1267733Y715250D01*
X1267775Y714875D01*
X1267900Y714542D01*
X1268067Y714292D01*
X1268317Y714083D01*
X1268650Y714000D01*
X1268983Y714083D01*
X1269233Y714292D01*
X1269400Y714542D01*
X1269525Y714875D01*
X1269567Y715250D01*
X1269525Y715625D01*
X1269400Y715958D01*
X1269233Y716208D01*
X1268983Y716417D01*
X1268650Y716500D01*
G01X1260267Y712292D02*
X1260017Y712417D01*
X1259725Y712500D01*
X1259392D01*
X1259017Y712375D01*
X1258725Y712167D01*
X1258517Y711917D01*
X1258350Y711500D01*
X1258308Y711125D01*
X1258392Y710750D01*
X1258517Y710500D01*
X1258767Y710250D01*
X1259058Y710083D01*
X1259350Y710000D01*
X1259642D01*
X1259933Y710083D01*
X1260183Y710208D01*
X1260392Y710375D01*
G01X1262450Y710000D02*
Y712500D01*
X1261950Y712000D01*
G01Y710000D02*
X1262950D01*
G01X1264842Y710292D02*
X1265133Y710083D01*
X1265467Y710000D01*
X1265800Y710083D01*
X1266092Y710333D01*
X1266300Y710708D01*
X1266383Y711083D01*
Y711542D01*
X1266300Y711917D01*
X1266092Y712250D01*
X1265842Y712417D01*
X1265550Y712500D01*
X1265217Y712417D01*
X1264967Y712250D01*
X1264800Y712000D01*
X1264717Y711667D01*
X1264800Y711375D01*
X1265008Y711083D01*
X1265258Y710917D01*
X1265550Y710875D01*
X1265883Y710958D01*
X1266133Y711167D01*
X1266383Y711542D01*
G01X1268650Y712500D02*
X1268317Y712417D01*
X1268067Y712208D01*
X1267900Y711958D01*
X1267775Y711625D01*
X1267733Y711250D01*
X1267775Y710875D01*
X1267900Y710542D01*
X1268067Y710292D01*
X1268317Y710083D01*
X1268650Y710000D01*
X1268983Y710083D01*
X1269233Y710292D01*
X1269400Y710542D01*
X1269525Y710875D01*
X1269567Y711250D01*
X1269525Y711625D01*
X1269400Y711958D01*
X1269233Y712208D01*
X1268983Y712417D01*
X1268650Y712500D01*
G01X1258517Y726500D02*
Y729000D01*
X1259558D01*
X1259892Y728875D01*
X1260100Y728708D01*
X1260183Y728375D01*
X1260100Y728042D01*
X1259850Y727833D01*
X1259558Y727708D01*
X1258517D01*
G01X1259558D02*
X1260183Y726500D01*
G01X1261533Y727000D02*
X1261783Y726708D01*
X1262117Y726542D01*
X1262492Y726500D01*
X1262825Y726542D01*
X1263158Y726750D01*
X1263367Y727000D01*
X1263408Y727250D01*
X1263325Y727542D01*
X1263033Y727750D01*
X1262742Y727833D01*
X1262367D01*
G01X1262742D02*
X1262992Y727958D01*
X1263200Y728167D01*
X1263283Y728417D01*
X1263200Y728667D01*
X1262992Y728875D01*
X1262617Y729000D01*
X1262242Y728958D01*
X1261867Y728792D01*
G01X1264633Y727000D02*
X1264883Y726708D01*
X1265217Y726542D01*
X1265592Y726500D01*
X1265925Y726542D01*
X1266258Y726750D01*
X1266467Y727000D01*
X1266508Y727250D01*
X1266425Y727542D01*
X1266133Y727750D01*
X1265842Y727833D01*
X1265467D01*
G01X1265842D02*
X1266092Y727958D01*
X1266300Y728167D01*
X1266383Y728417D01*
X1266300Y728667D01*
X1266092Y728875D01*
X1265717Y729000D01*
X1265342Y728958D01*
X1264967Y728792D01*
G01X1268650Y726500D02*
X1268942Y726542D01*
X1269275Y726667D01*
X1269483Y726875D01*
X1269567Y727167D01*
X1269483Y727458D01*
X1269233Y727708D01*
X1268858Y727833D01*
X1268442D01*
X1268192Y727917D01*
X1267983Y728125D01*
X1267900Y728417D01*
X1268025Y728708D01*
X1268317Y728917D01*
X1268650Y729000D01*
X1268983Y728917D01*
X1269275Y728708D01*
X1269400Y728417D01*
X1269317Y728125D01*
X1269108Y727917D01*
X1268858Y727833D01*
X1268442D01*
X1268067Y727708D01*
X1267817Y727458D01*
X1267733Y727167D01*
X1267817Y726875D01*
X1268025Y726667D01*
X1268358Y726542D01*
X1268650Y726500D01*
G01X1258517Y718000D02*
Y720500D01*
X1259558D01*
X1259892Y720375D01*
X1260100Y720208D01*
X1260183Y719875D01*
X1260100Y719542D01*
X1259850Y719333D01*
X1259558Y719208D01*
X1258517D01*
G01X1259558D02*
X1260183Y718000D01*
G01X1261533Y718500D02*
X1261783Y718208D01*
X1262117Y718042D01*
X1262492Y718000D01*
X1262825Y718042D01*
X1263158Y718250D01*
X1263367Y718500D01*
X1263408Y718750D01*
X1263325Y719042D01*
X1263033Y719250D01*
X1262742Y719333D01*
X1262367D01*
G01X1262742D02*
X1262992Y719458D01*
X1263200Y719667D01*
X1263283Y719917D01*
X1263200Y720167D01*
X1262992Y720375D01*
X1262617Y720500D01*
X1262242Y720458D01*
X1261867Y720292D01*
G01X1265550Y718000D02*
Y720500D01*
X1265050Y720000D01*
G01Y718000D02*
X1266050D01*
G01X1267942Y718292D02*
X1268233Y718083D01*
X1268567Y718000D01*
X1268900Y718083D01*
X1269192Y718333D01*
X1269400Y718708D01*
X1269483Y719083D01*
Y719542D01*
X1269400Y719917D01*
X1269192Y720250D01*
X1268942Y720417D01*
X1268650Y720500D01*
X1268317Y720417D01*
X1268067Y720250D01*
X1267900Y720000D01*
X1267817Y719667D01*
X1267900Y719375D01*
X1268108Y719083D01*
X1268358Y718917D01*
X1268650Y718875D01*
X1268983Y718958D01*
X1269233Y719167D01*
X1269483Y719542D01*
G01X1258517Y722000D02*
Y724500D01*
X1259558D01*
X1259892Y724375D01*
X1260100Y724208D01*
X1260183Y723875D01*
X1260100Y723542D01*
X1259850Y723333D01*
X1259558Y723208D01*
X1258517D01*
G01X1259558D02*
X1260183Y722000D01*
G01X1261533Y722500D02*
X1261783Y722208D01*
X1262117Y722042D01*
X1262492Y722000D01*
X1262825Y722042D01*
X1263158Y722250D01*
X1263367Y722500D01*
X1263408Y722750D01*
X1263325Y723042D01*
X1263033Y723250D01*
X1262742Y723333D01*
X1262367D01*
G01X1262742D02*
X1262992Y723458D01*
X1263200Y723667D01*
X1263283Y723917D01*
X1263200Y724167D01*
X1262992Y724375D01*
X1262617Y724500D01*
X1262242Y724458D01*
X1261867Y724292D01*
G01X1264633Y722500D02*
X1264883Y722208D01*
X1265217Y722042D01*
X1265592Y722000D01*
X1265925Y722042D01*
X1266258Y722250D01*
X1266467Y722500D01*
X1266508Y722750D01*
X1266425Y723042D01*
X1266133Y723250D01*
X1265842Y723333D01*
X1265467D01*
G01X1265842D02*
X1266092Y723458D01*
X1266300Y723667D01*
X1266383Y723917D01*
X1266300Y724167D01*
X1266092Y724375D01*
X1265717Y724500D01*
X1265342Y724458D01*
X1264967Y724292D01*
G01X1268567Y722000D02*
X1268650Y722542D01*
X1268775Y723000D01*
X1268942Y723417D01*
X1269150Y723875D01*
X1269483Y724500D01*
X1267817D01*
G01X1260300Y748000D02*
Y745500D01*
G01X1259342Y748000D02*
X1261258D01*
G01X1262567Y745500D02*
Y748000D01*
X1263567D01*
X1263900Y747875D01*
X1264150Y747583D01*
X1264233Y747250D01*
X1264150Y746917D01*
X1263942Y746667D01*
X1263567Y746542D01*
X1262567D01*
G01X1266500Y745500D02*
Y748000D01*
X1266000Y747500D01*
G01Y745500D02*
X1267000D01*
G01X1269600D02*
X1269892Y745542D01*
X1270225Y745667D01*
X1270433Y745875D01*
X1270517Y746167D01*
X1270433Y746458D01*
X1270183Y746708D01*
X1269808Y746833D01*
X1269392D01*
X1269142Y746917D01*
X1268933Y747125D01*
X1268850Y747417D01*
X1268975Y747708D01*
X1269267Y747917D01*
X1269600Y748000D01*
X1269933Y747917D01*
X1270225Y747708D01*
X1270350Y747417D01*
X1270267Y747125D01*
X1270058Y746917D01*
X1269808Y746833D01*
X1269392D01*
X1269017Y746708D01*
X1268767Y746458D01*
X1268683Y746167D01*
X1268767Y745875D01*
X1268975Y745667D01*
X1269308Y745542D01*
X1269600Y745500D01*
G01X1272700Y748000D02*
X1272367Y747917D01*
X1272117Y747708D01*
X1271950Y747458D01*
X1271825Y747125D01*
X1271783Y746750D01*
X1271825Y746375D01*
X1271950Y746042D01*
X1272117Y745792D01*
X1272367Y745583D01*
X1272700Y745500D01*
X1273033Y745583D01*
X1273283Y745792D01*
X1273450Y746042D01*
X1273575Y746375D01*
X1273617Y746750D01*
X1273575Y747125D01*
X1273450Y747458D01*
X1273283Y747708D01*
X1273033Y747917D01*
X1272700Y748000D01*
G01X1260300Y752500D02*
Y750000D01*
G01X1259342Y752500D02*
X1261258D01*
G01X1262567Y750000D02*
Y752500D01*
X1263567D01*
X1263900Y752375D01*
X1264150Y752083D01*
X1264233Y751750D01*
X1264150Y751417D01*
X1263942Y751167D01*
X1263567Y751042D01*
X1262567D01*
G01X1266500Y750000D02*
Y752500D01*
X1266000Y752000D01*
G01Y750000D02*
X1267000D01*
G01X1269517D02*
X1269600Y750542D01*
X1269725Y751000D01*
X1269892Y751417D01*
X1270100Y751875D01*
X1270433Y752500D01*
X1268767D01*
G01X1272617Y750000D02*
X1272700Y750542D01*
X1272825Y751000D01*
X1272992Y751417D01*
X1273200Y751875D01*
X1273533Y752500D01*
X1271867D01*
G01X1258017Y761500D02*
Y764000D01*
X1259058D01*
X1259392Y763875D01*
X1259600Y763708D01*
X1259683Y763375D01*
X1259600Y763042D01*
X1259350Y762833D01*
X1259058Y762708D01*
X1258017D01*
G01X1259058D02*
X1259683Y761500D01*
G01X1261867D02*
X1261950Y762042D01*
X1262075Y762500D01*
X1262242Y762917D01*
X1262450Y763375D01*
X1262783Y764000D01*
X1261117D01*
G01X1264342Y761792D02*
X1264633Y761583D01*
X1264967Y761500D01*
X1265300Y761583D01*
X1265592Y761833D01*
X1265800Y762208D01*
X1265883Y762583D01*
Y763042D01*
X1265800Y763417D01*
X1265592Y763750D01*
X1265342Y763917D01*
X1265050Y764000D01*
X1264717Y763917D01*
X1264467Y763750D01*
X1264300Y763500D01*
X1264217Y763167D01*
X1264300Y762875D01*
X1264508Y762583D01*
X1264758Y762417D01*
X1265050Y762375D01*
X1265383Y762458D01*
X1265633Y762667D01*
X1265883Y763042D01*
G01X1267442Y761792D02*
X1267733Y761583D01*
X1268067Y761500D01*
X1268400Y761583D01*
X1268692Y761833D01*
X1268900Y762208D01*
X1268983Y762583D01*
Y763042D01*
X1268900Y763417D01*
X1268692Y763750D01*
X1268442Y763917D01*
X1268150Y764000D01*
X1267817Y763917D01*
X1267567Y763750D01*
X1267400Y763500D01*
X1267317Y763167D01*
X1267400Y762875D01*
X1267608Y762583D01*
X1267858Y762417D01*
X1268150Y762375D01*
X1268483Y762458D01*
X1268733Y762667D01*
X1268983Y763042D01*
G01X1257300Y781000D02*
Y777000D01*
X1264700D01*
G01X1256517Y792000D02*
Y794500D01*
X1257558D01*
X1257892Y794375D01*
X1258100Y794208D01*
X1258183Y793875D01*
X1258100Y793542D01*
X1257850Y793333D01*
X1257558Y793208D01*
X1256517D01*
G01X1257558D02*
X1258183Y792000D01*
G01X1259533Y792375D02*
X1259783Y792167D01*
X1260075Y792042D01*
X1260450Y792000D01*
X1260825Y792083D01*
X1261117Y792250D01*
X1261325Y792542D01*
X1261367Y792875D01*
X1261283Y793208D01*
X1261075Y793417D01*
X1260783Y793583D01*
X1260492Y793625D01*
X1260200Y793583D01*
X1259825Y793417D01*
X1259950Y794500D01*
X1261075D01*
G01X1264050Y792000D02*
Y794500D01*
X1262508Y792708D01*
X1264592D01*
G01X1265858Y793042D02*
X1266150Y793333D01*
X1266400Y793500D01*
X1266733Y793583D01*
X1267025Y793500D01*
X1267233Y793333D01*
X1267400Y793083D01*
X1267442Y792792D01*
X1267400Y792542D01*
X1267233Y792292D01*
X1266983Y792083D01*
X1266692Y792000D01*
X1266358Y792083D01*
X1266067Y792333D01*
X1265900Y792708D01*
X1265858Y793125D01*
X1265942Y793667D01*
X1266067Y793958D01*
X1266275Y794250D01*
X1266567Y794458D01*
X1266858Y794500D01*
X1267150Y794417D01*
X1267358Y794208D01*
G01X1264700Y781000D02*
Y785000D01*
X1257300D01*
G01X1256517Y787500D02*
Y790000D01*
X1257558D01*
X1257892Y789875D01*
X1258100Y789708D01*
X1258183Y789375D01*
X1258100Y789042D01*
X1257850Y788833D01*
X1257558Y788708D01*
X1256517D01*
G01X1257558D02*
X1258183Y787500D01*
G01X1259533Y787875D02*
X1259783Y787667D01*
X1260075Y787542D01*
X1260450Y787500D01*
X1260825Y787583D01*
X1261117Y787750D01*
X1261325Y788042D01*
X1261367Y788375D01*
X1261283Y788708D01*
X1261075Y788917D01*
X1260783Y789083D01*
X1260492Y789125D01*
X1260200Y789083D01*
X1259825Y788917D01*
X1259950Y790000D01*
X1261075D01*
G01X1262758Y788542D02*
X1263050Y788833D01*
X1263300Y789000D01*
X1263633Y789083D01*
X1263925Y789000D01*
X1264133Y788833D01*
X1264300Y788583D01*
X1264342Y788292D01*
X1264300Y788042D01*
X1264133Y787792D01*
X1263883Y787583D01*
X1263592Y787500D01*
X1263258Y787583D01*
X1262967Y787833D01*
X1262800Y788208D01*
X1262758Y788625D01*
X1262842Y789167D01*
X1262967Y789458D01*
X1263175Y789750D01*
X1263467Y789958D01*
X1263758Y790000D01*
X1264050Y789917D01*
X1264258Y789708D01*
G01X1266650Y787500D02*
Y790000D01*
X1266150Y789500D01*
G01Y787500D02*
X1267150D01*
G01X1261017Y828000D02*
Y830500D01*
X1262058D01*
X1262392Y830375D01*
X1262600Y830208D01*
X1262683Y829875D01*
X1262600Y829542D01*
X1262350Y829333D01*
X1262058Y829208D01*
X1261017D01*
G01X1262058D02*
X1262683Y828000D01*
G01X1264033Y828375D02*
X1264283Y828167D01*
X1264575Y828042D01*
X1264950Y828000D01*
X1265325Y828083D01*
X1265617Y828250D01*
X1265825Y828542D01*
X1265867Y828875D01*
X1265783Y829208D01*
X1265575Y829417D01*
X1265283Y829583D01*
X1264992Y829625D01*
X1264700Y829583D01*
X1264325Y829417D01*
X1264450Y830500D01*
X1265575D01*
G01X1267258Y829042D02*
X1267550Y829333D01*
X1267800Y829500D01*
X1268133Y829583D01*
X1268425Y829500D01*
X1268633Y829333D01*
X1268800Y829083D01*
X1268842Y828792D01*
X1268800Y828542D01*
X1268633Y828292D01*
X1268383Y828083D01*
X1268092Y828000D01*
X1267758Y828083D01*
X1267467Y828333D01*
X1267300Y828708D01*
X1267258Y829125D01*
X1267342Y829667D01*
X1267467Y829958D01*
X1267675Y830250D01*
X1267967Y830458D01*
X1268258Y830500D01*
X1268550Y830417D01*
X1268758Y830208D01*
G01X1270233Y828500D02*
X1270483Y828208D01*
X1270817Y828042D01*
X1271192Y828000D01*
X1271525Y828042D01*
X1271858Y828250D01*
X1272067Y828500D01*
X1272108Y828750D01*
X1272025Y829042D01*
X1271733Y829250D01*
X1271442Y829333D01*
X1271067D01*
G01X1271442D02*
X1271692Y829458D01*
X1271900Y829667D01*
X1271983Y829917D01*
X1271900Y830167D01*
X1271692Y830375D01*
X1271317Y830500D01*
X1270942Y830458D01*
X1270567Y830292D01*
G01X1253100Y837600D02*
X1267100D01*
G01X1253100Y850600D02*
Y837600D01*
G01X1267300Y833100D02*
Y837100D01*
X1259900D01*
G01X1258900Y853500D02*
X1258567Y853542D01*
X1258275Y853708D01*
X1258025Y853958D01*
X1257858Y854250D01*
X1257775Y854583D01*
Y854917D01*
X1257858Y855250D01*
X1258025Y855542D01*
X1258275Y855792D01*
X1258567Y855958D01*
X1258900Y856000D01*
X1259233Y855958D01*
X1259525Y855792D01*
X1259775Y855542D01*
X1259942Y855250D01*
X1260025Y854917D01*
Y854583D01*
X1259942Y854250D01*
X1259775Y853958D01*
X1259525Y853708D01*
X1259233Y853542D01*
X1258900Y853500D01*
G01X1259233Y854167D02*
X1259733Y853500D01*
G01X1262000D02*
Y856000D01*
X1261500Y855500D01*
G01Y853500D02*
X1262500D01*
G01X1264308Y854542D02*
X1264600Y854833D01*
X1264850Y855000D01*
X1265183Y855083D01*
X1265475Y855000D01*
X1265683Y854833D01*
X1265850Y854583D01*
X1265892Y854292D01*
X1265850Y854042D01*
X1265683Y853792D01*
X1265433Y853583D01*
X1265142Y853500D01*
X1264808Y853583D01*
X1264517Y853833D01*
X1264350Y854208D01*
X1264308Y854625D01*
X1264392Y855167D01*
X1264517Y855458D01*
X1264725Y855750D01*
X1265017Y855958D01*
X1265308Y856000D01*
X1265600Y855917D01*
X1265808Y855708D01*
G01X1267100Y850600D02*
X1253100D01*
G01X1277927Y-8713D02*
Y-1613D01*
X1266127D01*
Y14987D01*
X1272627D01*
Y23787D01*
X1299027D01*
Y14987D01*
X1305527D01*
Y-1613D01*
X1293727D01*
Y-8713D01*
X1277927D01*
G01X1271017Y47500D02*
Y45000D01*
X1272683D01*
G01X1275783D02*
X1274117D01*
Y47500D01*
X1275783D01*
G01X1275117Y46292D02*
X1274117D01*
G01X1277133Y45000D02*
Y47500D01*
X1277967D01*
X1278300Y47375D01*
X1278550Y47208D01*
X1278758Y46958D01*
X1278925Y46667D01*
X1278967Y46250D01*
X1278925Y45833D01*
X1278758Y45542D01*
X1278550Y45292D01*
X1278300Y45125D01*
X1277967Y45000D01*
X1277133D01*
G01X1280358Y46042D02*
X1280650Y46333D01*
X1280900Y46500D01*
X1281233Y46583D01*
X1281525Y46500D01*
X1281733Y46333D01*
X1281900Y46083D01*
X1281942Y45792D01*
X1281900Y45542D01*
X1281733Y45292D01*
X1281483Y45083D01*
X1281192Y45000D01*
X1280858Y45083D01*
X1280567Y45333D01*
X1280400Y45708D01*
X1280358Y46125D01*
X1280442Y46667D01*
X1280567Y46958D01*
X1280775Y47250D01*
X1281067Y47458D01*
X1281358Y47500D01*
X1281650Y47417D01*
X1281858Y47208D01*
G01X1280500Y125417D02*
X1275500D01*
Y128583D01*
G01X1277917Y127417D02*
Y125417D01*
G01X1280500Y132600D02*
X1275500D01*
X1276500Y131600D01*
G01X1280500D02*
Y133600D01*
G01X1280667Y138200D02*
X1280583Y138033D01*
X1280417D01*
X1280333Y138200D01*
X1280417Y138367D01*
X1280583D01*
X1280667Y138200D01*
G01X1278417D02*
X1278333Y138033D01*
X1278167D01*
X1278083Y138200D01*
X1278167Y138367D01*
X1278333D01*
X1278417Y138200D01*
G01X1280500Y143800D02*
X1275500D01*
X1276500Y142800D01*
G01X1280500D02*
Y144800D01*
G01X1280667Y149400D02*
X1280583Y149233D01*
X1280417D01*
X1280333Y149400D01*
X1280417Y149567D01*
X1280583D01*
X1280667Y149400D01*
G01X1279750Y153167D02*
X1280167Y153667D01*
X1280417Y154250D01*
X1280500Y155000D01*
X1280333Y155750D01*
X1280000Y156333D01*
X1279417Y156750D01*
X1278750Y156833D01*
X1278083Y156667D01*
X1277667Y156250D01*
X1277333Y155667D01*
X1277250Y155083D01*
X1277333Y154500D01*
X1277667Y153750D01*
X1275500Y154000D01*
Y156250D01*
G01X1280500Y158517D02*
X1275500Y160600D01*
X1280500Y162683D01*
G01X1278750Y161933D02*
Y159267D01*
G01X1280667Y164700D02*
X1275500Y167700D01*
G01X1280500Y171800D02*
X1280417Y172383D01*
X1280167Y173050D01*
X1279750Y173467D01*
X1279167Y173633D01*
X1278583Y173467D01*
X1278083Y172967D01*
X1277833Y172217D01*
Y171383D01*
X1277667Y170883D01*
X1277250Y170467D01*
X1276667Y170300D01*
X1276083Y170550D01*
X1275667Y171133D01*
X1275500Y171800D01*
X1275667Y172467D01*
X1276083Y173050D01*
X1276667Y173300D01*
X1277250Y173133D01*
X1277667Y172717D01*
X1277833Y172217D01*
Y171383D01*
X1278083Y170633D01*
X1278583Y170133D01*
X1279167Y169967D01*
X1279750Y170133D01*
X1280167Y170550D01*
X1280417Y171217D01*
X1280500Y171800D01*
G01X1275500Y175317D02*
X1280500Y177400D01*
X1275500Y179483D01*
G01X1266180Y170340D02*
X1268680D01*
G01X1266180Y169382D02*
Y171298D01*
G01X1266388Y174357D02*
X1266263Y174107D01*
X1266180Y173815D01*
Y173482D01*
X1266305Y173107D01*
X1266513Y172815D01*
X1266763Y172607D01*
X1267180Y172440D01*
X1267555Y172398D01*
X1267930Y172482D01*
X1268180Y172607D01*
X1268430Y172857D01*
X1268597Y173148D01*
X1268680Y173440D01*
Y173732D01*
X1268597Y174023D01*
X1268472Y174273D01*
X1268305Y174482D01*
G01X1268680Y176540D02*
X1266180D01*
X1266680Y176040D01*
G01X1268680D02*
Y177040D01*
G01Y180140D02*
X1266180D01*
X1267972Y178598D01*
Y180682D01*
G01X1266180Y183340D02*
X1268680D01*
G01X1266180Y182382D02*
Y184298D01*
G01X1266388Y187357D02*
X1266263Y187107D01*
X1266180Y186815D01*
Y186482D01*
X1266305Y186107D01*
X1266513Y185815D01*
X1266763Y185607D01*
X1267180Y185440D01*
X1267555Y185398D01*
X1267930Y185482D01*
X1268180Y185607D01*
X1268430Y185857D01*
X1268597Y186148D01*
X1268680Y186440D01*
Y186732D01*
X1268597Y187023D01*
X1268472Y187273D01*
X1268305Y187482D01*
G01X1268680Y189540D02*
X1266180D01*
X1266680Y189040D01*
G01X1268680D02*
Y190040D01*
G01X1268180Y191723D02*
X1268472Y191973D01*
X1268638Y192307D01*
X1268680Y192682D01*
X1268638Y193015D01*
X1268430Y193348D01*
X1268180Y193557D01*
X1267930Y193598D01*
X1267638Y193515D01*
X1267430Y193223D01*
X1267347Y192932D01*
Y192557D01*
G01Y192932D02*
X1267222Y193182D01*
X1267013Y193390D01*
X1266763Y193473D01*
X1266513Y193390D01*
X1266305Y193182D01*
X1266180Y192807D01*
X1266222Y192432D01*
X1266388Y192057D01*
G01X1268505Y219500D02*
Y222000D01*
X1269546D01*
X1269880Y221875D01*
X1270088Y221708D01*
X1270171Y221375D01*
X1270088Y221042D01*
X1269838Y220833D01*
X1269546Y220708D01*
X1268505D01*
G01X1269546D02*
X1270171Y219500D01*
G01X1271646Y221583D02*
X1271896Y221833D01*
X1272188Y221958D01*
X1272521Y222000D01*
X1272938Y221917D01*
X1273230Y221708D01*
X1273313Y221458D01*
X1273271Y221208D01*
X1273105Y221000D01*
X1272271Y220583D01*
X1271896Y220292D01*
X1271646Y219875D01*
X1271563Y219500D01*
X1273313D01*
G01X1275538D02*
Y222000D01*
X1275038Y221500D01*
G01Y219500D02*
X1276038D01*
G01X1278638Y222000D02*
X1278305Y221917D01*
X1278055Y221708D01*
X1277888Y221458D01*
X1277763Y221125D01*
X1277721Y220750D01*
X1277763Y220375D01*
X1277888Y220042D01*
X1278055Y219792D01*
X1278305Y219583D01*
X1278638Y219500D01*
X1278971Y219583D01*
X1279221Y219792D01*
X1279388Y220042D01*
X1279513Y220375D01*
X1279555Y220750D01*
X1279513Y221125D01*
X1279388Y221458D01*
X1279221Y221708D01*
X1278971Y221917D01*
X1278638Y222000D01*
G01X1268505Y224000D02*
Y226500D01*
X1269546D01*
X1269880Y226375D01*
X1270088Y226208D01*
X1270171Y225875D01*
X1270088Y225542D01*
X1269838Y225333D01*
X1269546Y225208D01*
X1268505D01*
G01X1269546D02*
X1270171Y224000D01*
G01X1271646Y226083D02*
X1271896Y226333D01*
X1272188Y226458D01*
X1272521Y226500D01*
X1272938Y226417D01*
X1273230Y226208D01*
X1273313Y225958D01*
X1273271Y225708D01*
X1273105Y225500D01*
X1272271Y225083D01*
X1271896Y224792D01*
X1271646Y224375D01*
X1271563Y224000D01*
X1273313D01*
G01X1275538D02*
Y226500D01*
X1275038Y226000D01*
G01Y224000D02*
X1276038D01*
G01X1278638D02*
Y226500D01*
X1278138Y226000D01*
G01Y224000D02*
X1279138D01*
G01X1268505Y228500D02*
Y231000D01*
X1269546D01*
X1269880Y230875D01*
X1270088Y230708D01*
X1270171Y230375D01*
X1270088Y230042D01*
X1269838Y229833D01*
X1269546Y229708D01*
X1268505D01*
G01X1269546D02*
X1270171Y228500D01*
G01X1271646Y230583D02*
X1271896Y230833D01*
X1272188Y230958D01*
X1272521Y231000D01*
X1272938Y230917D01*
X1273230Y230708D01*
X1273313Y230458D01*
X1273271Y230208D01*
X1273105Y230000D01*
X1272271Y229583D01*
X1271896Y229292D01*
X1271646Y228875D01*
X1271563Y228500D01*
X1273313D01*
G01X1275538D02*
Y231000D01*
X1275038Y230500D01*
G01Y228500D02*
X1276038D01*
G01X1277721Y229000D02*
X1277971Y228708D01*
X1278305Y228542D01*
X1278680Y228500D01*
X1279013Y228542D01*
X1279346Y228750D01*
X1279555Y229000D01*
X1279596Y229250D01*
X1279513Y229542D01*
X1279221Y229750D01*
X1278930Y229833D01*
X1278555D01*
G01X1278930D02*
X1279180Y229958D01*
X1279388Y230167D01*
X1279471Y230417D01*
X1279388Y230667D01*
X1279180Y230875D01*
X1278805Y231000D01*
X1278430Y230958D01*
X1278055Y230792D01*
G01X1268505Y233000D02*
Y235500D01*
X1269546D01*
X1269880Y235375D01*
X1270088Y235208D01*
X1270171Y234875D01*
X1270088Y234542D01*
X1269838Y234333D01*
X1269546Y234208D01*
X1268505D01*
G01X1269546D02*
X1270171Y233000D01*
G01X1271646Y235083D02*
X1271896Y235333D01*
X1272188Y235458D01*
X1272521Y235500D01*
X1272938Y235417D01*
X1273230Y235208D01*
X1273313Y234958D01*
X1273271Y234708D01*
X1273105Y234500D01*
X1272271Y234083D01*
X1271896Y233792D01*
X1271646Y233375D01*
X1271563Y233000D01*
X1273313D01*
G01X1275538D02*
Y235500D01*
X1275038Y235000D01*
G01Y233000D02*
X1276038D01*
G01X1279138D02*
Y235500D01*
X1277596Y233708D01*
X1279680D01*
G01X1269694Y241500D02*
Y244000D01*
X1270735D01*
X1271069Y243875D01*
X1271277Y243708D01*
X1271360Y243375D01*
X1271277Y243042D01*
X1271027Y242833D01*
X1270735Y242708D01*
X1269694D01*
G01X1270735D02*
X1271360Y241500D01*
G01X1272835Y243583D02*
X1273085Y243833D01*
X1273377Y243958D01*
X1273710Y244000D01*
X1274127Y243917D01*
X1274419Y243708D01*
X1274502Y243458D01*
X1274460Y243208D01*
X1274294Y243000D01*
X1273460Y242583D01*
X1273085Y242292D01*
X1272835Y241875D01*
X1272752Y241500D01*
X1274502D01*
G01X1275810Y241875D02*
X1276060Y241667D01*
X1276352Y241542D01*
X1276727Y241500D01*
X1277102Y241583D01*
X1277394Y241750D01*
X1277602Y242042D01*
X1277644Y242375D01*
X1277560Y242708D01*
X1277352Y242917D01*
X1277060Y243083D01*
X1276769Y243125D01*
X1276477Y243083D01*
X1276102Y242917D01*
X1276227Y244000D01*
X1277352D01*
G01X1280327Y241500D02*
Y244000D01*
X1278785Y242208D01*
X1280869D01*
G01X1269694Y245500D02*
Y248000D01*
X1270735D01*
X1271069Y247875D01*
X1271277Y247708D01*
X1271360Y247375D01*
X1271277Y247042D01*
X1271027Y246833D01*
X1270735Y246708D01*
X1269694D01*
G01X1270735D02*
X1271360Y245500D01*
G01X1272835Y247583D02*
X1273085Y247833D01*
X1273377Y247958D01*
X1273710Y248000D01*
X1274127Y247917D01*
X1274419Y247708D01*
X1274502Y247458D01*
X1274460Y247208D01*
X1274294Y247000D01*
X1273460Y246583D01*
X1273085Y246292D01*
X1272835Y245875D01*
X1272752Y245500D01*
X1274502D01*
G01X1275810Y245875D02*
X1276060Y245667D01*
X1276352Y245542D01*
X1276727Y245500D01*
X1277102Y245583D01*
X1277394Y245750D01*
X1277602Y246042D01*
X1277644Y246375D01*
X1277560Y246708D01*
X1277352Y246917D01*
X1277060Y247083D01*
X1276769Y247125D01*
X1276477Y247083D01*
X1276102Y246917D01*
X1276227Y248000D01*
X1277352D01*
G01X1278910Y245875D02*
X1279160Y245667D01*
X1279452Y245542D01*
X1279827Y245500D01*
X1280202Y245583D01*
X1280494Y245750D01*
X1280702Y246042D01*
X1280744Y246375D01*
X1280660Y246708D01*
X1280452Y246917D01*
X1280160Y247083D01*
X1279869Y247125D01*
X1279577Y247083D01*
X1279202Y246917D01*
X1279327Y248000D01*
X1280452D01*
G01X1267433Y296500D02*
Y294708D01*
X1267600Y294333D01*
X1267933Y294083D01*
X1268350Y294000D01*
X1268767Y294083D01*
X1269100Y294333D01*
X1269267Y294708D01*
Y296500D01*
G01X1271450Y294000D02*
Y296500D01*
X1270950Y296000D01*
G01Y294000D02*
X1271950D01*
G01X1273842Y294292D02*
X1274133Y294083D01*
X1274467Y294000D01*
X1274800Y294083D01*
X1275092Y294333D01*
X1275300Y294708D01*
X1275383Y295083D01*
Y295542D01*
X1275300Y295917D01*
X1275092Y296250D01*
X1274842Y296417D01*
X1274550Y296500D01*
X1274217Y296417D01*
X1273967Y296250D01*
X1273800Y296000D01*
X1273717Y295667D01*
X1273800Y295375D01*
X1274008Y295083D01*
X1274258Y294917D01*
X1274550Y294875D01*
X1274883Y294958D01*
X1275133Y295167D01*
X1275383Y295542D01*
G01X1276733Y294375D02*
X1276983Y294167D01*
X1277275Y294042D01*
X1277650Y294000D01*
X1278025Y294083D01*
X1278317Y294250D01*
X1278525Y294542D01*
X1278567Y294875D01*
X1278483Y295208D01*
X1278275Y295417D01*
X1277983Y295583D01*
X1277692Y295625D01*
X1277400Y295583D01*
X1277025Y295417D01*
X1277150Y296500D01*
X1278275D01*
G01X1279375Y350516D02*
Y347516D01*
G01X1282017Y341500D02*
Y344000D01*
X1283058D01*
X1283392Y343875D01*
X1283600Y343708D01*
X1283683Y343375D01*
X1283600Y343042D01*
X1283350Y342833D01*
X1283058Y342708D01*
X1282017D01*
G01X1283058D02*
X1283683Y341500D01*
G01X1285158Y342542D02*
X1285450Y342833D01*
X1285700Y343000D01*
X1286033Y343083D01*
X1286325Y343000D01*
X1286533Y342833D01*
X1286700Y342583D01*
X1286742Y342292D01*
X1286700Y342042D01*
X1286533Y341792D01*
X1286283Y341583D01*
X1285992Y341500D01*
X1285658Y341583D01*
X1285367Y341833D01*
X1285200Y342208D01*
X1285158Y342625D01*
X1285242Y343167D01*
X1285367Y343458D01*
X1285575Y343750D01*
X1285867Y343958D01*
X1286158Y344000D01*
X1286450Y343917D01*
X1286658Y343708D01*
G01X1289050Y341500D02*
X1289342Y341542D01*
X1289675Y341667D01*
X1289883Y341875D01*
X1289967Y342167D01*
X1289883Y342458D01*
X1289633Y342708D01*
X1289258Y342833D01*
X1288842D01*
X1288592Y342917D01*
X1288383Y343125D01*
X1288300Y343417D01*
X1288425Y343708D01*
X1288717Y343917D01*
X1289050Y344000D01*
X1289383Y343917D01*
X1289675Y343708D01*
X1289800Y343417D01*
X1289717Y343125D01*
X1289508Y342917D01*
X1289258Y342833D01*
X1288842D01*
X1288467Y342708D01*
X1288217Y342458D01*
X1288133Y342167D01*
X1288217Y341875D01*
X1288425Y341667D01*
X1288758Y341542D01*
X1289050Y341500D01*
G01X1292650D02*
Y344000D01*
X1291108Y342208D01*
X1293192D01*
G01X1282017Y337500D02*
Y340000D01*
X1283058D01*
X1283392Y339875D01*
X1283600Y339708D01*
X1283683Y339375D01*
X1283600Y339042D01*
X1283350Y338833D01*
X1283058Y338708D01*
X1282017D01*
G01X1283058D02*
X1283683Y337500D01*
G01X1286450D02*
Y340000D01*
X1284908Y338208D01*
X1286992D01*
G01X1289050Y337500D02*
X1289342Y337542D01*
X1289675Y337667D01*
X1289883Y337875D01*
X1289967Y338167D01*
X1289883Y338458D01*
X1289633Y338708D01*
X1289258Y338833D01*
X1288842D01*
X1288592Y338917D01*
X1288383Y339125D01*
X1288300Y339417D01*
X1288425Y339708D01*
X1288717Y339917D01*
X1289050Y340000D01*
X1289383Y339917D01*
X1289675Y339708D01*
X1289800Y339417D01*
X1289717Y339125D01*
X1289508Y338917D01*
X1289258Y338833D01*
X1288842D01*
X1288467Y338708D01*
X1288217Y338458D01*
X1288133Y338167D01*
X1288217Y337875D01*
X1288425Y337667D01*
X1288758Y337542D01*
X1289050Y337500D01*
G01X1291358Y338542D02*
X1291650Y338833D01*
X1291900Y339000D01*
X1292233Y339083D01*
X1292525Y339000D01*
X1292733Y338833D01*
X1292900Y338583D01*
X1292942Y338292D01*
X1292900Y338042D01*
X1292733Y337792D01*
X1292483Y337583D01*
X1292192Y337500D01*
X1291858Y337583D01*
X1291567Y337833D01*
X1291400Y338208D01*
X1291358Y338625D01*
X1291442Y339167D01*
X1291567Y339458D01*
X1291775Y339750D01*
X1292067Y339958D01*
X1292358Y340000D01*
X1292650Y339917D01*
X1292858Y339708D01*
G01X1280200Y367000D02*
Y375000D01*
G01X1285700Y367000D02*
X1280200D01*
G01Y384000D02*
X1285700D01*
G01X1280200Y376000D02*
Y384000D01*
G01X1285700Y376000D02*
X1280200D01*
G01Y375000D02*
X1285700D01*
G01X1278268Y430434D02*
X1283268D01*
Y435434D01*
G01X1277342Y431441D02*
Y428441D01*
G01X1267499Y431441D02*
Y429441D01*
G01X1283268Y453134D02*
Y458134D01*
X1278268D01*
G01X1273405Y457127D02*
Y459127D01*
G01X1279000Y475017D02*
X1276500D01*
Y476017D01*
X1276625Y476350D01*
X1276917Y476600D01*
X1277250Y476683D01*
X1277583Y476600D01*
X1277833Y476392D01*
X1277958Y476017D01*
Y475017D01*
G01X1276708Y479867D02*
X1276583Y479617D01*
X1276500Y479325D01*
Y478992D01*
X1276625Y478617D01*
X1276833Y478325D01*
X1277083Y478117D01*
X1277500Y477950D01*
X1277875Y477908D01*
X1278250Y477992D01*
X1278500Y478117D01*
X1278750Y478367D01*
X1278917Y478658D01*
X1279000Y478950D01*
Y479242D01*
X1278917Y479533D01*
X1278792Y479783D01*
X1278625Y479992D01*
G01X1276917Y481258D02*
X1276667Y481508D01*
X1276542Y481800D01*
X1276500Y482133D01*
X1276583Y482550D01*
X1276792Y482842D01*
X1277042Y482925D01*
X1277292Y482883D01*
X1277500Y482717D01*
X1277917Y481883D01*
X1278208Y481508D01*
X1278625Y481258D01*
X1279000Y481175D01*
Y482925D01*
G01X1278500Y484233D02*
X1278792Y484483D01*
X1278958Y484817D01*
X1279000Y485192D01*
X1278958Y485525D01*
X1278750Y485858D01*
X1278500Y486067D01*
X1278250Y486108D01*
X1277958Y486025D01*
X1277750Y485733D01*
X1277667Y485442D01*
Y485067D01*
G01Y485442D02*
X1277542Y485692D01*
X1277333Y485900D01*
X1277083Y485983D01*
X1276833Y485900D01*
X1276625Y485692D01*
X1276500Y485317D01*
X1276542Y484942D01*
X1276708Y484567D01*
G01X1270000Y476017D02*
X1267500D01*
Y477017D01*
X1267625Y477350D01*
X1267917Y477600D01*
X1268250Y477683D01*
X1268583Y477600D01*
X1268833Y477392D01*
X1268958Y477017D01*
Y476017D01*
G01X1267708Y480867D02*
X1267583Y480617D01*
X1267500Y480325D01*
Y479992D01*
X1267625Y479617D01*
X1267833Y479325D01*
X1268083Y479117D01*
X1268500Y478950D01*
X1268875Y478908D01*
X1269250Y478992D01*
X1269500Y479117D01*
X1269750Y479367D01*
X1269917Y479658D01*
X1270000Y479950D01*
Y480242D01*
X1269917Y480533D01*
X1269792Y480783D01*
X1269625Y480992D01*
G01X1267917Y482258D02*
X1267667Y482508D01*
X1267542Y482800D01*
X1267500Y483133D01*
X1267583Y483550D01*
X1267792Y483842D01*
X1268042Y483925D01*
X1268292Y483883D01*
X1268500Y483717D01*
X1268917Y482883D01*
X1269208Y482508D01*
X1269625Y482258D01*
X1270000Y482175D01*
Y483925D01*
G01X1269708Y485442D02*
X1269917Y485733D01*
X1270000Y486067D01*
X1269917Y486400D01*
X1269667Y486692D01*
X1269292Y486900D01*
X1268917Y486983D01*
X1268458D01*
X1268083Y486900D01*
X1267750Y486692D01*
X1267583Y486442D01*
X1267500Y486150D01*
X1267583Y485817D01*
X1267750Y485567D01*
X1268000Y485400D01*
X1268333Y485317D01*
X1268625Y485400D01*
X1268917Y485608D01*
X1269083Y485858D01*
X1269125Y486150D01*
X1269042Y486483D01*
X1268833Y486733D01*
X1268458Y486983D01*
G01X1280075Y547500D02*
X1281825Y550000D01*
G01X1280075D02*
X1281825Y547500D01*
G01X1283258Y549583D02*
X1283508Y549833D01*
X1283800Y549958D01*
X1284133Y550000D01*
X1284550Y549917D01*
X1284842Y549708D01*
X1284925Y549458D01*
X1284883Y549208D01*
X1284717Y549000D01*
X1283883Y548583D01*
X1283508Y548292D01*
X1283258Y547875D01*
X1283175Y547500D01*
X1284925D01*
G01X1275967Y542500D02*
Y545000D01*
X1277008D01*
X1277342Y544875D01*
X1277550Y544708D01*
X1277633Y544375D01*
X1277550Y544042D01*
X1277300Y543833D01*
X1277008Y543708D01*
X1275967D01*
G01X1277008D02*
X1277633Y542500D01*
G01X1278983Y542875D02*
X1279233Y542667D01*
X1279525Y542542D01*
X1279900Y542500D01*
X1280275Y542583D01*
X1280567Y542750D01*
X1280775Y543042D01*
X1280817Y543375D01*
X1280733Y543708D01*
X1280525Y543917D01*
X1280233Y544083D01*
X1279942Y544125D01*
X1279650Y544083D01*
X1279275Y543917D01*
X1279400Y545000D01*
X1280525D01*
G01X1282208Y544583D02*
X1282458Y544833D01*
X1282750Y544958D01*
X1283083Y545000D01*
X1283500Y544917D01*
X1283792Y544708D01*
X1283875Y544458D01*
X1283833Y544208D01*
X1283667Y544000D01*
X1282833Y543583D01*
X1282458Y543292D01*
X1282208Y542875D01*
X1282125Y542500D01*
X1283875D01*
G01X1286100Y545000D02*
X1285767Y544917D01*
X1285517Y544708D01*
X1285350Y544458D01*
X1285225Y544125D01*
X1285183Y543750D01*
X1285225Y543375D01*
X1285350Y543042D01*
X1285517Y542792D01*
X1285767Y542583D01*
X1286100Y542500D01*
X1286433Y542583D01*
X1286683Y542792D01*
X1286850Y543042D01*
X1286975Y543375D01*
X1287017Y543750D01*
X1286975Y544125D01*
X1286850Y544458D01*
X1286683Y544708D01*
X1286433Y544917D01*
X1286100Y545000D01*
G01X1288408Y544583D02*
X1288658Y544833D01*
X1288950Y544958D01*
X1289283Y545000D01*
X1289700Y544917D01*
X1289992Y544708D01*
X1290075Y544458D01*
X1290033Y544208D01*
X1289867Y544000D01*
X1289033Y543583D01*
X1288658Y543292D01*
X1288408Y542875D01*
X1288325Y542500D01*
X1290075D01*
G01X1273500Y550700D02*
X1269500D01*
Y543300D01*
G01X1269650Y552550D02*
Y561450D01*
X1287350D01*
Y552550D01*
X1269650D01*
G01X1281467Y573000D02*
Y575500D01*
X1282508D01*
X1282842Y575375D01*
X1283050Y575208D01*
X1283133Y574875D01*
X1283050Y574542D01*
X1282800Y574333D01*
X1282508Y574208D01*
X1281467D01*
G01X1282508D02*
X1283133Y573000D01*
G01X1285400D02*
Y575500D01*
X1284900Y575000D01*
G01Y573000D02*
X1285900D01*
G01X1288500D02*
X1288792Y573042D01*
X1289125Y573167D01*
X1289333Y573375D01*
X1289417Y573667D01*
X1289333Y573958D01*
X1289083Y574208D01*
X1288708Y574333D01*
X1288292D01*
X1288042Y574417D01*
X1287833Y574625D01*
X1287750Y574917D01*
X1287875Y575208D01*
X1288167Y575417D01*
X1288500Y575500D01*
X1288833Y575417D01*
X1289125Y575208D01*
X1289250Y574917D01*
X1289167Y574625D01*
X1288958Y574417D01*
X1288708Y574333D01*
X1288292D01*
X1287917Y574208D01*
X1287667Y573958D01*
X1287583Y573667D01*
X1287667Y573375D01*
X1287875Y573167D01*
X1288208Y573042D01*
X1288500Y573000D01*
G01X1292100D02*
Y575500D01*
X1290558Y573708D01*
X1292642D01*
G01X1294700Y573000D02*
X1294992Y573042D01*
X1295325Y573167D01*
X1295533Y573375D01*
X1295617Y573667D01*
X1295533Y573958D01*
X1295283Y574208D01*
X1294908Y574333D01*
X1294492D01*
X1294242Y574417D01*
X1294033Y574625D01*
X1293950Y574917D01*
X1294075Y575208D01*
X1294367Y575417D01*
X1294700Y575500D01*
X1295033Y575417D01*
X1295325Y575208D01*
X1295450Y574917D01*
X1295367Y574625D01*
X1295158Y574417D01*
X1294908Y574333D01*
X1294492D01*
X1294117Y574208D01*
X1293867Y573958D01*
X1293783Y573667D01*
X1293867Y573375D01*
X1294075Y573167D01*
X1294408Y573042D01*
X1294700Y573000D01*
G01X1273000Y642017D02*
X1270500D01*
Y643058D01*
X1270625Y643392D01*
X1270792Y643600D01*
X1271125Y643683D01*
X1271458Y643600D01*
X1271667Y643350D01*
X1271792Y643058D01*
Y642017D01*
G01Y643058D02*
X1273000Y643683D01*
G01X1270917Y645158D02*
X1270667Y645408D01*
X1270542Y645700D01*
X1270500Y646033D01*
X1270583Y646450D01*
X1270792Y646742D01*
X1271042Y646825D01*
X1271292Y646783D01*
X1271500Y646617D01*
X1271917Y645783D01*
X1272208Y645408D01*
X1272625Y645158D01*
X1273000Y645075D01*
Y646825D01*
G01Y648967D02*
X1272458Y649050D01*
X1272000Y649175D01*
X1271583Y649342D01*
X1271125Y649550D01*
X1270500Y649883D01*
Y648217D01*
G01X1272625Y651233D02*
X1272833Y651483D01*
X1272958Y651775D01*
X1273000Y652150D01*
X1272917Y652525D01*
X1272750Y652817D01*
X1272458Y653025D01*
X1272125Y653067D01*
X1271792Y652983D01*
X1271583Y652775D01*
X1271417Y652483D01*
X1271375Y652192D01*
X1271417Y651900D01*
X1271583Y651525D01*
X1270500Y651650D01*
Y652775D01*
G01X1277500Y642017D02*
X1275000D01*
Y643058D01*
X1275125Y643392D01*
X1275292Y643600D01*
X1275625Y643683D01*
X1275958Y643600D01*
X1276167Y643350D01*
X1276292Y643058D01*
Y642017D01*
G01Y643058D02*
X1277500Y643683D01*
G01X1275417Y645158D02*
X1275167Y645408D01*
X1275042Y645700D01*
X1275000Y646033D01*
X1275083Y646450D01*
X1275292Y646742D01*
X1275542Y646825D01*
X1275792Y646783D01*
X1276000Y646617D01*
X1276417Y645783D01*
X1276708Y645408D01*
X1277125Y645158D01*
X1277500Y645075D01*
Y646825D01*
G01Y649050D02*
X1277458Y649342D01*
X1277333Y649675D01*
X1277125Y649883D01*
X1276833Y649967D01*
X1276542Y649883D01*
X1276292Y649633D01*
X1276167Y649258D01*
Y648842D01*
X1276083Y648592D01*
X1275875Y648383D01*
X1275583Y648300D01*
X1275292Y648425D01*
X1275083Y648717D01*
X1275000Y649050D01*
X1275083Y649383D01*
X1275292Y649675D01*
X1275583Y649800D01*
X1275875Y649717D01*
X1276083Y649508D01*
X1276167Y649258D01*
Y648842D01*
X1276292Y648467D01*
X1276542Y648217D01*
X1276833Y648133D01*
X1277125Y648217D01*
X1277333Y648425D01*
X1277458Y648758D01*
X1277500Y649050D01*
G01X1277208Y651442D02*
X1277417Y651733D01*
X1277500Y652067D01*
X1277417Y652400D01*
X1277167Y652692D01*
X1276792Y652900D01*
X1276417Y652983D01*
X1275958D01*
X1275583Y652900D01*
X1275250Y652692D01*
X1275083Y652442D01*
X1275000Y652150D01*
X1275083Y651817D01*
X1275250Y651567D01*
X1275500Y651400D01*
X1275833Y651317D01*
X1276125Y651400D01*
X1276417Y651608D01*
X1276583Y651858D01*
X1276625Y652150D01*
X1276542Y652483D01*
X1276333Y652733D01*
X1275958Y652983D01*
G01X1278000Y665700D02*
X1274000D01*
Y658300D01*
G01X1271300Y676500D02*
Y672500D01*
X1278700D01*
G01X1271300Y683000D02*
Y679000D01*
X1278700D01*
G01X1272017Y687500D02*
Y690000D01*
X1273058D01*
X1273392Y689875D01*
X1273600Y689708D01*
X1273683Y689375D01*
X1273600Y689042D01*
X1273350Y688833D01*
X1273058Y688708D01*
X1272017D01*
G01X1273058D02*
X1273683Y687500D01*
G01X1276450D02*
Y690000D01*
X1274908Y688208D01*
X1276992D01*
G01X1279050Y687500D02*
Y690000D01*
X1278550Y689500D01*
G01Y687500D02*
X1279550D01*
G01X1281358Y689583D02*
X1281608Y689833D01*
X1281900Y689958D01*
X1282233Y690000D01*
X1282650Y689917D01*
X1282942Y689708D01*
X1283025Y689458D01*
X1282983Y689208D01*
X1282817Y689000D01*
X1281983Y688583D01*
X1281608Y688292D01*
X1281358Y687875D01*
X1281275Y687500D01*
X1283025D01*
G01X1272017Y691500D02*
Y694000D01*
X1273058D01*
X1273392Y693875D01*
X1273600Y693708D01*
X1273683Y693375D01*
X1273600Y693042D01*
X1273350Y692833D01*
X1273058Y692708D01*
X1272017D01*
G01X1273058D02*
X1273683Y691500D01*
G01X1276450D02*
Y694000D01*
X1274908Y692208D01*
X1276992D01*
G01X1278133Y692000D02*
X1278383Y691708D01*
X1278717Y691542D01*
X1279092Y691500D01*
X1279425Y691542D01*
X1279758Y691750D01*
X1279967Y692000D01*
X1280008Y692250D01*
X1279925Y692542D01*
X1279633Y692750D01*
X1279342Y692833D01*
X1278967D01*
G01X1279342D02*
X1279592Y692958D01*
X1279800Y693167D01*
X1279883Y693417D01*
X1279800Y693667D01*
X1279592Y693875D01*
X1279217Y694000D01*
X1278842Y693958D01*
X1278467Y693792D01*
G01X1281233Y691875D02*
X1281483Y691667D01*
X1281775Y691542D01*
X1282150Y691500D01*
X1282525Y691583D01*
X1282817Y691750D01*
X1283025Y692042D01*
X1283067Y692375D01*
X1282983Y692708D01*
X1282775Y692917D01*
X1282483Y693083D01*
X1282192Y693125D01*
X1281900Y693083D01*
X1281525Y692917D01*
X1281650Y694000D01*
X1282775D01*
G01X1275000Y703800D02*
X1279000D01*
Y711200D01*
G01X1283000D02*
X1279000D01*
Y703800D01*
G01X1279500Y723967D02*
X1277000D01*
Y725008D01*
X1277125Y725342D01*
X1277292Y725550D01*
X1277625Y725633D01*
X1277958Y725550D01*
X1278167Y725300D01*
X1278292Y725008D01*
Y723967D01*
G01Y725008D02*
X1279500Y725633D01*
G01X1279125Y726983D02*
X1279333Y727233D01*
X1279458Y727525D01*
X1279500Y727900D01*
X1279417Y728275D01*
X1279250Y728567D01*
X1278958Y728775D01*
X1278625Y728817D01*
X1278292Y728733D01*
X1278083Y728525D01*
X1277917Y728233D01*
X1277875Y727942D01*
X1277917Y727650D01*
X1278083Y727275D01*
X1277000Y727400D01*
Y728525D01*
G01X1279500Y730917D02*
X1278958Y731000D01*
X1278500Y731125D01*
X1278083Y731292D01*
X1277625Y731500D01*
X1277000Y731833D01*
Y730167D01*
G01X1278458Y733308D02*
X1278167Y733600D01*
X1278000Y733850D01*
X1277917Y734183D01*
X1278000Y734475D01*
X1278167Y734683D01*
X1278417Y734850D01*
X1278708Y734892D01*
X1278958Y734850D01*
X1279208Y734683D01*
X1279417Y734433D01*
X1279500Y734142D01*
X1279417Y733808D01*
X1279167Y733517D01*
X1278792Y733350D01*
X1278375Y733308D01*
X1277833Y733392D01*
X1277542Y733517D01*
X1277250Y733725D01*
X1277042Y734017D01*
X1277000Y734308D01*
X1277083Y734600D01*
X1277292Y734808D01*
G01X1279500Y737117D02*
X1278958Y737200D01*
X1278500Y737325D01*
X1278083Y737492D01*
X1277625Y737700D01*
X1277000Y738033D01*
Y736367D01*
G01X1279000Y721700D02*
X1275000D01*
Y714300D01*
G01X1283500Y723967D02*
X1281000D01*
Y725008D01*
X1281125Y725342D01*
X1281292Y725550D01*
X1281625Y725633D01*
X1281958Y725550D01*
X1282167Y725300D01*
X1282292Y725008D01*
Y723967D01*
G01Y725008D02*
X1283500Y725633D01*
G01X1283125Y726983D02*
X1283333Y727233D01*
X1283458Y727525D01*
X1283500Y727900D01*
X1283417Y728275D01*
X1283250Y728567D01*
X1282958Y728775D01*
X1282625Y728817D01*
X1282292Y728733D01*
X1282083Y728525D01*
X1281917Y728233D01*
X1281875Y727942D01*
X1281917Y727650D01*
X1282083Y727275D01*
X1281000Y727400D01*
Y728525D01*
G01X1283500Y730917D02*
X1282958Y731000D01*
X1282500Y731125D01*
X1282083Y731292D01*
X1281625Y731500D01*
X1281000Y731833D01*
Y730167D01*
G01X1282458Y733308D02*
X1282167Y733600D01*
X1282000Y733850D01*
X1281917Y734183D01*
X1282000Y734475D01*
X1282167Y734683D01*
X1282417Y734850D01*
X1282708Y734892D01*
X1282958Y734850D01*
X1283208Y734683D01*
X1283417Y734433D01*
X1283500Y734142D01*
X1283417Y733808D01*
X1283167Y733517D01*
X1282792Y733350D01*
X1282375Y733308D01*
X1281833Y733392D01*
X1281542Y733517D01*
X1281250Y733725D01*
X1281042Y734017D01*
X1281000Y734308D01*
X1281083Y734600D01*
X1281292Y734808D01*
G01X1283125Y736283D02*
X1283333Y736533D01*
X1283458Y736825D01*
X1283500Y737200D01*
X1283417Y737575D01*
X1283250Y737867D01*
X1282958Y738075D01*
X1282625Y738117D01*
X1282292Y738033D01*
X1282083Y737825D01*
X1281917Y737533D01*
X1281875Y737242D01*
X1281917Y736950D01*
X1282083Y736575D01*
X1281000Y736700D01*
Y737825D01*
G01X1279000Y714300D02*
X1283000D01*
Y721700D01*
G01X1273208Y725717D02*
X1273083Y725467D01*
X1273000Y725175D01*
Y724842D01*
X1273125Y724467D01*
X1273333Y724175D01*
X1273583Y723967D01*
X1274000Y723800D01*
X1274375Y723758D01*
X1274750Y723842D01*
X1275000Y723967D01*
X1275250Y724217D01*
X1275417Y724508D01*
X1275500Y724800D01*
Y725092D01*
X1275417Y725383D01*
X1275292Y725633D01*
X1275125Y725842D01*
G01X1275500Y727900D02*
X1275458Y728192D01*
X1275333Y728525D01*
X1275125Y728733D01*
X1274833Y728817D01*
X1274542Y728733D01*
X1274292Y728483D01*
X1274167Y728108D01*
Y727692D01*
X1274083Y727442D01*
X1273875Y727233D01*
X1273583Y727150D01*
X1273292Y727275D01*
X1273083Y727567D01*
X1273000Y727900D01*
X1273083Y728233D01*
X1273292Y728525D01*
X1273583Y728650D01*
X1273875Y728567D01*
X1274083Y728358D01*
X1274167Y728108D01*
Y727692D01*
X1274292Y727317D01*
X1274542Y727067D01*
X1274833Y726983D01*
X1275125Y727067D01*
X1275333Y727275D01*
X1275458Y727608D01*
X1275500Y727900D01*
G01X1273000Y731000D02*
X1273083Y730667D01*
X1273292Y730417D01*
X1273542Y730250D01*
X1273875Y730125D01*
X1274250Y730083D01*
X1274625Y730125D01*
X1274958Y730250D01*
X1275208Y730417D01*
X1275417Y730667D01*
X1275500Y731000D01*
X1275417Y731333D01*
X1275208Y731583D01*
X1274958Y731750D01*
X1274625Y731875D01*
X1274250Y731917D01*
X1273875Y731875D01*
X1273542Y731750D01*
X1273292Y731583D01*
X1273083Y731333D01*
X1273000Y731000D01*
G01X1275500Y734100D02*
X1275458Y734392D01*
X1275333Y734725D01*
X1275125Y734933D01*
X1274833Y735017D01*
X1274542Y734933D01*
X1274292Y734683D01*
X1274167Y734308D01*
Y733892D01*
X1274083Y733642D01*
X1273875Y733433D01*
X1273583Y733350D01*
X1273292Y733475D01*
X1273083Y733767D01*
X1273000Y734100D01*
X1273083Y734433D01*
X1273292Y734725D01*
X1273583Y734850D01*
X1273875Y734767D01*
X1274083Y734558D01*
X1274167Y734308D01*
Y733892D01*
X1274292Y733517D01*
X1274542Y733267D01*
X1274833Y733183D01*
X1275125Y733267D01*
X1275333Y733475D01*
X1275458Y733808D01*
X1275500Y734100D01*
G01X1275125Y736283D02*
X1275333Y736533D01*
X1275458Y736825D01*
X1275500Y737200D01*
X1275417Y737575D01*
X1275250Y737867D01*
X1274958Y738075D01*
X1274625Y738117D01*
X1274292Y738033D01*
X1274083Y737825D01*
X1273917Y737533D01*
X1273875Y737242D01*
X1273917Y736950D01*
X1274083Y736575D01*
X1273000Y736700D01*
Y737825D01*
G01X1276800Y752500D02*
Y750000D01*
G01X1275842Y752500D02*
X1277758D01*
G01X1279067Y750000D02*
Y752500D01*
X1280067D01*
X1280400Y752375D01*
X1280650Y752083D01*
X1280733Y751750D01*
X1280650Y751417D01*
X1280442Y751167D01*
X1280067Y751042D01*
X1279067D01*
G01X1283000Y750000D02*
Y752500D01*
X1282500Y752000D01*
G01Y750000D02*
X1283500D01*
G01X1286017D02*
X1286100Y750542D01*
X1286225Y751000D01*
X1286392Y751417D01*
X1286600Y751875D01*
X1286933Y752500D01*
X1285267D01*
G01X1289200Y750000D02*
X1289492Y750042D01*
X1289825Y750167D01*
X1290033Y750375D01*
X1290117Y750667D01*
X1290033Y750958D01*
X1289783Y751208D01*
X1289408Y751333D01*
X1288992D01*
X1288742Y751417D01*
X1288533Y751625D01*
X1288450Y751917D01*
X1288575Y752208D01*
X1288867Y752417D01*
X1289200Y752500D01*
X1289533Y752417D01*
X1289825Y752208D01*
X1289950Y751917D01*
X1289867Y751625D01*
X1289658Y751417D01*
X1289408Y751333D01*
X1288992D01*
X1288617Y751208D01*
X1288367Y750958D01*
X1288283Y750667D01*
X1288367Y750375D01*
X1288575Y750167D01*
X1288908Y750042D01*
X1289200Y750000D01*
G01X1267100Y837600D02*
Y850600D01*
G01X1284468Y838301D02*
X1281968D01*
Y839342D01*
X1282093Y839676D01*
X1282260Y839884D01*
X1282593Y839967D01*
X1282926Y839884D01*
X1283135Y839634D01*
X1283260Y839342D01*
Y838301D01*
G01Y839342D02*
X1284468Y839967D01*
G01Y842234D02*
X1281968D01*
X1282468Y841734D01*
G01X1284468D02*
Y842734D01*
G01Y845334D02*
X1284426Y845626D01*
X1284301Y845959D01*
X1284093Y846167D01*
X1283801Y846251D01*
X1283510Y846167D01*
X1283260Y845917D01*
X1283135Y845542D01*
Y845126D01*
X1283051Y844876D01*
X1282843Y844667D01*
X1282551Y844584D01*
X1282260Y844709D01*
X1282051Y845001D01*
X1281968Y845334D01*
X1282051Y845667D01*
X1282260Y845959D01*
X1282551Y846084D01*
X1282843Y846001D01*
X1283051Y845792D01*
X1283135Y845542D01*
Y845126D01*
X1283260Y844751D01*
X1283510Y844501D01*
X1283801Y844417D01*
X1284093Y844501D01*
X1284301Y844709D01*
X1284426Y845042D01*
X1284468Y845334D01*
G01Y848434D02*
X1281968D01*
X1282468Y847934D01*
G01X1284468D02*
Y848934D01*
G01X1282866Y34133D02*
Y43033D01*
G01X1290000Y35517D02*
X1287500D01*
Y36558D01*
X1287625Y36892D01*
X1287792Y37100D01*
X1288125Y37183D01*
X1288458Y37100D01*
X1288667Y36850D01*
X1288792Y36558D01*
Y35517D01*
G01Y36558D02*
X1290000Y37183D01*
G01Y39950D02*
X1287500D01*
X1289292Y38408D01*
Y40492D01*
G01X1289625Y41633D02*
X1289833Y41883D01*
X1289958Y42175D01*
X1290000Y42550D01*
X1289917Y42925D01*
X1289750Y43217D01*
X1289458Y43425D01*
X1289125Y43467D01*
X1288792Y43383D01*
X1288583Y43175D01*
X1288417Y42883D01*
X1288375Y42592D01*
X1288417Y42300D01*
X1288583Y41925D01*
X1287500Y42050D01*
Y43175D01*
G01X1290000Y45650D02*
X1289958Y45942D01*
X1289833Y46275D01*
X1289625Y46483D01*
X1289333Y46567D01*
X1289042Y46483D01*
X1288792Y46233D01*
X1288667Y45858D01*
Y45442D01*
X1288583Y45192D01*
X1288375Y44983D01*
X1288083Y44900D01*
X1287792Y45025D01*
X1287583Y45317D01*
X1287500Y45650D01*
X1287583Y45983D01*
X1287792Y46275D01*
X1288083Y46400D01*
X1288375Y46317D01*
X1288583Y46108D01*
X1288667Y45858D01*
Y45442D01*
X1288792Y45067D01*
X1289042Y44817D01*
X1289333Y44733D01*
X1289625Y44817D01*
X1289833Y45025D01*
X1289958Y45358D01*
X1290000Y45650D01*
G01X1297500Y36200D02*
X1293500D01*
Y28800D01*
G01X1291722Y290600D02*
Y311000D01*
G01X1310522Y290600D02*
X1291722D01*
G01X1301122Y308100D02*
X1297522Y311700D01*
G01X1310522D02*
X1283122D01*
G01X1290200Y335500D02*
X1301700D01*
Y313500D01*
X1290200D01*
Y335500D01*
G01X1286500Y320200D02*
X1282500D01*
Y312800D01*
G01Y321300D02*
X1286500D01*
Y328700D01*
G01X1283517Y351500D02*
Y354000D01*
X1284517D01*
X1284850Y353875D01*
X1285100Y353583D01*
X1285183Y353250D01*
X1285100Y352917D01*
X1284892Y352667D01*
X1284517Y352542D01*
X1283517D01*
G01X1288367Y353792D02*
X1288117Y353917D01*
X1287825Y354000D01*
X1287492D01*
X1287117Y353875D01*
X1286825Y353667D01*
X1286617Y353417D01*
X1286450Y353000D01*
X1286408Y352625D01*
X1286492Y352250D01*
X1286617Y352000D01*
X1286867Y351750D01*
X1287158Y351583D01*
X1287450Y351500D01*
X1287742D01*
X1288033Y351583D01*
X1288283Y351708D01*
X1288492Y351875D01*
G01X1291050Y351500D02*
Y354000D01*
X1289508Y352208D01*
X1291592D01*
G01X1293650Y354000D02*
X1293317Y353917D01*
X1293067Y353708D01*
X1292900Y353458D01*
X1292775Y353125D01*
X1292733Y352750D01*
X1292775Y352375D01*
X1292900Y352042D01*
X1293067Y351792D01*
X1293317Y351583D01*
X1293650Y351500D01*
X1293983Y351583D01*
X1294233Y351792D01*
X1294400Y352042D01*
X1294525Y352375D01*
X1294567Y352750D01*
X1294525Y353125D01*
X1294400Y353458D01*
X1294233Y353708D01*
X1293983Y353917D01*
X1293650Y354000D01*
G01X1283517Y347000D02*
Y349500D01*
X1284517D01*
X1284850Y349375D01*
X1285100Y349083D01*
X1285183Y348750D01*
X1285100Y348417D01*
X1284892Y348167D01*
X1284517Y348042D01*
X1283517D01*
G01X1288367Y349292D02*
X1288117Y349417D01*
X1287825Y349500D01*
X1287492D01*
X1287117Y349375D01*
X1286825Y349167D01*
X1286617Y348917D01*
X1286450Y348500D01*
X1286408Y348125D01*
X1286492Y347750D01*
X1286617Y347500D01*
X1286867Y347250D01*
X1287158Y347083D01*
X1287450Y347000D01*
X1287742D01*
X1288033Y347083D01*
X1288283Y347208D01*
X1288492Y347375D01*
G01X1289633Y347500D02*
X1289883Y347208D01*
X1290217Y347042D01*
X1290592Y347000D01*
X1290925Y347042D01*
X1291258Y347250D01*
X1291467Y347500D01*
X1291508Y347750D01*
X1291425Y348042D01*
X1291133Y348250D01*
X1290842Y348333D01*
X1290467D01*
G01X1290842D02*
X1291092Y348458D01*
X1291300Y348667D01*
X1291383Y348917D01*
X1291300Y349167D01*
X1291092Y349375D01*
X1290717Y349500D01*
X1290342Y349458D01*
X1289967Y349292D01*
G01X1292733Y347375D02*
X1292983Y347167D01*
X1293275Y347042D01*
X1293650Y347000D01*
X1294025Y347083D01*
X1294317Y347250D01*
X1294525Y347542D01*
X1294567Y347875D01*
X1294483Y348208D01*
X1294275Y348417D01*
X1293983Y348583D01*
X1293692Y348625D01*
X1293400Y348583D01*
X1293025Y348417D01*
X1293150Y349500D01*
X1294275D01*
G01X1283517Y356000D02*
Y358500D01*
X1284517D01*
X1284850Y358375D01*
X1285100Y358083D01*
X1285183Y357750D01*
X1285100Y357417D01*
X1284892Y357167D01*
X1284517Y357042D01*
X1283517D01*
G01X1288367Y358292D02*
X1288117Y358417D01*
X1287825Y358500D01*
X1287492D01*
X1287117Y358375D01*
X1286825Y358167D01*
X1286617Y357917D01*
X1286450Y357500D01*
X1286408Y357125D01*
X1286492Y356750D01*
X1286617Y356500D01*
X1286867Y356250D01*
X1287158Y356083D01*
X1287450Y356000D01*
X1287742D01*
X1288033Y356083D01*
X1288283Y356208D01*
X1288492Y356375D01*
G01X1289633Y356500D02*
X1289883Y356208D01*
X1290217Y356042D01*
X1290592Y356000D01*
X1290925Y356042D01*
X1291258Y356250D01*
X1291467Y356500D01*
X1291508Y356750D01*
X1291425Y357042D01*
X1291133Y357250D01*
X1290842Y357333D01*
X1290467D01*
G01X1290842D02*
X1291092Y357458D01*
X1291300Y357667D01*
X1291383Y357917D01*
X1291300Y358167D01*
X1291092Y358375D01*
X1290717Y358500D01*
X1290342Y358458D01*
X1289967Y358292D01*
G01X1292942Y356292D02*
X1293233Y356083D01*
X1293567Y356000D01*
X1293900Y356083D01*
X1294192Y356333D01*
X1294400Y356708D01*
X1294483Y357083D01*
Y357542D01*
X1294400Y357917D01*
X1294192Y358250D01*
X1293942Y358417D01*
X1293650Y358500D01*
X1293317Y358417D01*
X1293067Y358250D01*
X1292900Y358000D01*
X1292817Y357667D01*
X1292900Y357375D01*
X1293108Y357083D01*
X1293358Y356917D01*
X1293650Y356875D01*
X1293983Y356958D01*
X1294233Y357167D01*
X1294483Y357542D01*
G01X1297800Y367000D02*
X1292300D01*
G01X1297800Y375000D02*
Y367000D01*
G01Y376000D02*
X1292300D01*
G01X1297800Y384000D02*
Y376000D01*
G01X1292300Y384000D02*
X1297800D01*
G01X1292300Y375000D02*
X1297800D01*
G01X1287500Y421900D02*
X1315500D01*
Y386100D01*
X1287500D01*
Y421900D01*
G01X1295268Y431284D02*
X1303068D01*
G01X1295268Y438284D02*
Y431284D01*
G01X1286017Y439500D02*
Y442000D01*
X1287017D01*
X1287350Y441875D01*
X1287600Y441583D01*
X1287683Y441250D01*
X1287600Y440917D01*
X1287392Y440667D01*
X1287017Y440542D01*
X1286017D01*
G01X1290867Y441792D02*
X1290617Y441917D01*
X1290325Y442000D01*
X1289992D01*
X1289617Y441875D01*
X1289325Y441667D01*
X1289117Y441417D01*
X1288950Y441000D01*
X1288908Y440625D01*
X1288992Y440250D01*
X1289117Y440000D01*
X1289367Y439750D01*
X1289658Y439583D01*
X1289950Y439500D01*
X1290242D01*
X1290533Y439583D01*
X1290783Y439708D01*
X1290992Y439875D01*
G01X1292258Y441583D02*
X1292508Y441833D01*
X1292800Y441958D01*
X1293133Y442000D01*
X1293550Y441917D01*
X1293842Y441708D01*
X1293925Y441458D01*
X1293883Y441208D01*
X1293717Y441000D01*
X1292883Y440583D01*
X1292508Y440292D01*
X1292258Y439875D01*
X1292175Y439500D01*
X1293925D01*
G01X1296150D02*
X1296442Y439542D01*
X1296775Y439667D01*
X1296983Y439875D01*
X1297067Y440167D01*
X1296983Y440458D01*
X1296733Y440708D01*
X1296358Y440833D01*
X1295942D01*
X1295692Y440917D01*
X1295483Y441125D01*
X1295400Y441417D01*
X1295525Y441708D01*
X1295817Y441917D01*
X1296150Y442000D01*
X1296483Y441917D01*
X1296775Y441708D01*
X1296900Y441417D01*
X1296817Y441125D01*
X1296608Y440917D01*
X1296358Y440833D01*
X1295942D01*
X1295567Y440708D01*
X1295317Y440458D01*
X1295233Y440167D01*
X1295317Y439875D01*
X1295525Y439667D01*
X1295858Y439542D01*
X1296150Y439500D01*
G01X1295268Y438284D02*
X1300468D01*
G01X1298400Y459800D02*
X1305600D01*
G01X1298400Y473200D02*
Y459800D01*
G01X1305600Y473200D02*
X1298400D01*
G01X1295000Y475017D02*
X1292500D01*
Y476017D01*
X1292625Y476350D01*
X1292917Y476600D01*
X1293250Y476683D01*
X1293583Y476600D01*
X1293833Y476392D01*
X1293958Y476017D01*
Y475017D01*
G01X1292708Y479867D02*
X1292583Y479617D01*
X1292500Y479325D01*
Y478992D01*
X1292625Y478617D01*
X1292833Y478325D01*
X1293083Y478117D01*
X1293500Y477950D01*
X1293875Y477908D01*
X1294250Y477992D01*
X1294500Y478117D01*
X1294750Y478367D01*
X1294917Y478658D01*
X1295000Y478950D01*
Y479242D01*
X1294917Y479533D01*
X1294792Y479783D01*
X1294625Y479992D01*
G01X1292917Y481258D02*
X1292667Y481508D01*
X1292542Y481800D01*
X1292500Y482133D01*
X1292583Y482550D01*
X1292792Y482842D01*
X1293042Y482925D01*
X1293292Y482883D01*
X1293500Y482717D01*
X1293917Y481883D01*
X1294208Y481508D01*
X1294625Y481258D01*
X1295000Y481175D01*
Y482925D01*
G01X1292917Y484358D02*
X1292667Y484608D01*
X1292542Y484900D01*
X1292500Y485233D01*
X1292583Y485650D01*
X1292792Y485942D01*
X1293042Y486025D01*
X1293292Y485983D01*
X1293500Y485817D01*
X1293917Y484983D01*
X1294208Y484608D01*
X1294625Y484358D01*
X1295000Y484275D01*
Y486025D01*
G01X1287000Y475017D02*
X1284500D01*
Y476017D01*
X1284625Y476350D01*
X1284917Y476600D01*
X1285250Y476683D01*
X1285583Y476600D01*
X1285833Y476392D01*
X1285958Y476017D01*
Y475017D01*
G01X1284708Y479867D02*
X1284583Y479617D01*
X1284500Y479325D01*
Y478992D01*
X1284625Y478617D01*
X1284833Y478325D01*
X1285083Y478117D01*
X1285500Y477950D01*
X1285875Y477908D01*
X1286250Y477992D01*
X1286500Y478117D01*
X1286750Y478367D01*
X1286917Y478658D01*
X1287000Y478950D01*
Y479242D01*
X1286917Y479533D01*
X1286792Y479783D01*
X1286625Y479992D01*
G01X1284917Y481258D02*
X1284667Y481508D01*
X1284542Y481800D01*
X1284500Y482133D01*
X1284583Y482550D01*
X1284792Y482842D01*
X1285042Y482925D01*
X1285292Y482883D01*
X1285500Y482717D01*
X1285917Y481883D01*
X1286208Y481508D01*
X1286625Y481258D01*
X1287000Y481175D01*
Y482925D01*
G01Y485650D02*
X1284500D01*
X1286292Y484108D01*
Y486192D01*
G01X1289708Y557767D02*
X1289583Y557517D01*
X1289500Y557225D01*
Y556892D01*
X1289625Y556517D01*
X1289833Y556225D01*
X1290083Y556017D01*
X1290500Y555850D01*
X1290875Y555808D01*
X1291250Y555892D01*
X1291500Y556017D01*
X1291750Y556267D01*
X1291917Y556558D01*
X1292000Y556850D01*
Y557142D01*
X1291917Y557433D01*
X1291792Y557683D01*
X1291625Y557892D01*
G01X1291500Y559033D02*
X1291792Y559283D01*
X1291958Y559617D01*
X1292000Y559992D01*
X1291958Y560325D01*
X1291750Y560658D01*
X1291500Y560867D01*
X1291250Y560908D01*
X1290958Y560825D01*
X1290750Y560533D01*
X1290667Y560242D01*
Y559867D01*
G01Y560242D02*
X1290542Y560492D01*
X1290333Y560700D01*
X1290083Y560783D01*
X1289833Y560700D01*
X1289625Y560492D01*
X1289500Y560117D01*
X1289542Y559742D01*
X1289708Y559367D01*
G01X1289500Y563050D02*
X1289583Y562717D01*
X1289792Y562467D01*
X1290042Y562300D01*
X1290375Y562175D01*
X1290750Y562133D01*
X1291125Y562175D01*
X1291458Y562300D01*
X1291708Y562467D01*
X1291917Y562717D01*
X1292000Y563050D01*
X1291917Y563383D01*
X1291708Y563633D01*
X1291458Y563800D01*
X1291125Y563925D01*
X1290750Y563967D01*
X1290375Y563925D01*
X1290042Y563800D01*
X1289792Y563633D01*
X1289583Y563383D01*
X1289500Y563050D01*
G01X1290958Y565358D02*
X1290667Y565650D01*
X1290500Y565900D01*
X1290417Y566233D01*
X1290500Y566525D01*
X1290667Y566733D01*
X1290917Y566900D01*
X1291208Y566942D01*
X1291458Y566900D01*
X1291708Y566733D01*
X1291917Y566483D01*
X1292000Y566192D01*
X1291917Y565858D01*
X1291667Y565567D01*
X1291292Y565400D01*
X1290875Y565358D01*
X1290333Y565442D01*
X1290042Y565567D01*
X1289750Y565775D01*
X1289542Y566067D01*
X1289500Y566358D01*
X1289583Y566650D01*
X1289792Y566858D01*
G01X1294708Y557767D02*
X1294583Y557517D01*
X1294500Y557225D01*
Y556892D01*
X1294625Y556517D01*
X1294833Y556225D01*
X1295083Y556017D01*
X1295500Y555850D01*
X1295875Y555808D01*
X1296250Y555892D01*
X1296500Y556017D01*
X1296750Y556267D01*
X1296917Y556558D01*
X1297000Y556850D01*
Y557142D01*
X1296917Y557433D01*
X1296792Y557683D01*
X1296625Y557892D01*
G01X1296500Y559033D02*
X1296792Y559283D01*
X1296958Y559617D01*
X1297000Y559992D01*
X1296958Y560325D01*
X1296750Y560658D01*
X1296500Y560867D01*
X1296250Y560908D01*
X1295958Y560825D01*
X1295750Y560533D01*
X1295667Y560242D01*
Y559867D01*
G01Y560242D02*
X1295542Y560492D01*
X1295333Y560700D01*
X1295083Y560783D01*
X1294833Y560700D01*
X1294625Y560492D01*
X1294500Y560117D01*
X1294542Y559742D01*
X1294708Y559367D01*
G01X1294500Y563050D02*
X1294583Y562717D01*
X1294792Y562467D01*
X1295042Y562300D01*
X1295375Y562175D01*
X1295750Y562133D01*
X1296125Y562175D01*
X1296458Y562300D01*
X1296708Y562467D01*
X1296917Y562717D01*
X1297000Y563050D01*
X1296917Y563383D01*
X1296708Y563633D01*
X1296458Y563800D01*
X1296125Y563925D01*
X1295750Y563967D01*
X1295375Y563925D01*
X1295042Y563800D01*
X1294792Y563633D01*
X1294583Y563383D01*
X1294500Y563050D01*
G01X1297000Y566067D02*
X1296458Y566150D01*
X1296000Y566275D01*
X1295583Y566442D01*
X1295125Y566650D01*
X1294500Y566983D01*
Y565317D01*
G01X1297517Y582000D02*
Y584500D01*
X1298558D01*
X1298892Y584375D01*
X1299100Y584208D01*
X1299183Y583875D01*
X1299100Y583542D01*
X1298850Y583333D01*
X1298558Y583208D01*
X1297517D01*
G01X1298558D02*
X1299183Y582000D01*
G01X1300533Y582375D02*
X1300783Y582167D01*
X1301075Y582042D01*
X1301450Y582000D01*
X1301825Y582083D01*
X1302117Y582250D01*
X1302325Y582542D01*
X1302367Y582875D01*
X1302283Y583208D01*
X1302075Y583417D01*
X1301783Y583583D01*
X1301492Y583625D01*
X1301200Y583583D01*
X1300825Y583417D01*
X1300950Y584500D01*
X1302075D01*
G01X1303633Y582375D02*
X1303883Y582167D01*
X1304175Y582042D01*
X1304550Y582000D01*
X1304925Y582083D01*
X1305217Y582250D01*
X1305425Y582542D01*
X1305467Y582875D01*
X1305383Y583208D01*
X1305175Y583417D01*
X1304883Y583583D01*
X1304592Y583625D01*
X1304300Y583583D01*
X1303925Y583417D01*
X1304050Y584500D01*
X1305175D01*
G01X1306858Y584083D02*
X1307108Y584333D01*
X1307400Y584458D01*
X1307733Y584500D01*
X1308150Y584417D01*
X1308442Y584208D01*
X1308525Y583958D01*
X1308483Y583708D01*
X1308317Y583500D01*
X1307483Y583083D01*
X1307108Y582792D01*
X1306858Y582375D01*
X1306775Y582000D01*
X1308525D01*
G01X1299267Y579292D02*
X1299017Y579417D01*
X1298725Y579500D01*
X1298392D01*
X1298017Y579375D01*
X1297725Y579167D01*
X1297517Y578917D01*
X1297350Y578500D01*
X1297308Y578125D01*
X1297392Y577750D01*
X1297517Y577500D01*
X1297767Y577250D01*
X1298058Y577083D01*
X1298350Y577000D01*
X1298642D01*
X1298933Y577083D01*
X1299183Y577208D01*
X1299392Y577375D01*
G01X1300533Y577500D02*
X1300783Y577208D01*
X1301117Y577042D01*
X1301492Y577000D01*
X1301825Y577042D01*
X1302158Y577250D01*
X1302367Y577500D01*
X1302408Y577750D01*
X1302325Y578042D01*
X1302033Y578250D01*
X1301742Y578333D01*
X1301367D01*
G01X1301742D02*
X1301992Y578458D01*
X1302200Y578667D01*
X1302283Y578917D01*
X1302200Y579167D01*
X1301992Y579375D01*
X1301617Y579500D01*
X1301242Y579458D01*
X1300867Y579292D01*
G01X1304550Y577000D02*
Y579500D01*
X1304050Y579000D01*
G01Y577000D02*
X1305050D01*
G01X1307650D02*
X1307942Y577042D01*
X1308275Y577167D01*
X1308483Y577375D01*
X1308567Y577667D01*
X1308483Y577958D01*
X1308233Y578208D01*
X1307858Y578333D01*
X1307442D01*
X1307192Y578417D01*
X1306983Y578625D01*
X1306900Y578917D01*
X1307025Y579208D01*
X1307317Y579417D01*
X1307650Y579500D01*
X1307983Y579417D01*
X1308275Y579208D01*
X1308400Y578917D01*
X1308317Y578625D01*
X1308108Y578417D01*
X1307858Y578333D01*
X1307442D01*
X1307067Y578208D01*
X1306817Y577958D01*
X1306733Y577667D01*
X1306817Y577375D01*
X1307025Y577167D01*
X1307358Y577042D01*
X1307650Y577000D01*
G01X1298017Y591000D02*
Y593500D01*
X1299058D01*
X1299392Y593375D01*
X1299600Y593208D01*
X1299683Y592875D01*
X1299600Y592542D01*
X1299350Y592333D01*
X1299058Y592208D01*
X1298017D01*
G01X1299058D02*
X1299683Y591000D01*
G01X1301033Y591375D02*
X1301283Y591167D01*
X1301575Y591042D01*
X1301950Y591000D01*
X1302325Y591083D01*
X1302617Y591250D01*
X1302825Y591542D01*
X1302867Y591875D01*
X1302783Y592208D01*
X1302575Y592417D01*
X1302283Y592583D01*
X1301992Y592625D01*
X1301700Y592583D01*
X1301325Y592417D01*
X1301450Y593500D01*
X1302575D01*
G01X1305550Y591000D02*
Y593500D01*
X1304008Y591708D01*
X1306092D01*
G01X1308150Y591000D02*
X1308442Y591042D01*
X1308775Y591167D01*
X1308983Y591375D01*
X1309067Y591667D01*
X1308983Y591958D01*
X1308733Y592208D01*
X1308358Y592333D01*
X1307942D01*
X1307692Y592417D01*
X1307483Y592625D01*
X1307400Y592917D01*
X1307525Y593208D01*
X1307817Y593417D01*
X1308150Y593500D01*
X1308483Y593417D01*
X1308775Y593208D01*
X1308900Y592917D01*
X1308817Y592625D01*
X1308608Y592417D01*
X1308358Y592333D01*
X1307942D01*
X1307567Y592208D01*
X1307317Y591958D01*
X1307233Y591667D01*
X1307317Y591375D01*
X1307525Y591167D01*
X1307858Y591042D01*
X1308150Y591000D01*
G01X1297517Y586500D02*
Y589000D01*
X1298558D01*
X1298892Y588875D01*
X1299100Y588708D01*
X1299183Y588375D01*
X1299100Y588042D01*
X1298850Y587833D01*
X1298558Y587708D01*
X1297517D01*
G01X1298558D02*
X1299183Y586500D01*
G01X1300533Y586875D02*
X1300783Y586667D01*
X1301075Y586542D01*
X1301450Y586500D01*
X1301825Y586583D01*
X1302117Y586750D01*
X1302325Y587042D01*
X1302367Y587375D01*
X1302283Y587708D01*
X1302075Y587917D01*
X1301783Y588083D01*
X1301492Y588125D01*
X1301200Y588083D01*
X1300825Y587917D01*
X1300950Y589000D01*
X1302075D01*
G01X1303633Y586875D02*
X1303883Y586667D01*
X1304175Y586542D01*
X1304550Y586500D01*
X1304925Y586583D01*
X1305217Y586750D01*
X1305425Y587042D01*
X1305467Y587375D01*
X1305383Y587708D01*
X1305175Y587917D01*
X1304883Y588083D01*
X1304592Y588125D01*
X1304300Y588083D01*
X1303925Y587917D01*
X1304050Y589000D01*
X1305175D01*
G01X1307650D02*
X1307317Y588917D01*
X1307067Y588708D01*
X1306900Y588458D01*
X1306775Y588125D01*
X1306733Y587750D01*
X1306775Y587375D01*
X1306900Y587042D01*
X1307067Y586792D01*
X1307317Y586583D01*
X1307650Y586500D01*
X1307983Y586583D01*
X1308233Y586792D01*
X1308400Y587042D01*
X1308525Y587375D01*
X1308567Y587750D01*
X1308525Y588125D01*
X1308400Y588458D01*
X1308233Y588708D01*
X1307983Y588917D01*
X1307650Y589000D01*
G01X1294967Y595000D02*
Y597500D01*
X1296008D01*
X1296342Y597375D01*
X1296550Y597208D01*
X1296633Y596875D01*
X1296550Y596542D01*
X1296300Y596333D01*
X1296008Y596208D01*
X1294967D01*
G01X1296008D02*
X1296633Y595000D01*
G01X1298817D02*
X1298900Y595542D01*
X1299025Y596000D01*
X1299192Y596417D01*
X1299400Y596875D01*
X1299733Y597500D01*
X1298067D01*
G01X1302000Y595000D02*
X1302292Y595042D01*
X1302625Y595167D01*
X1302833Y595375D01*
X1302917Y595667D01*
X1302833Y595958D01*
X1302583Y596208D01*
X1302208Y596333D01*
X1301792D01*
X1301542Y596417D01*
X1301333Y596625D01*
X1301250Y596917D01*
X1301375Y597208D01*
X1301667Y597417D01*
X1302000Y597500D01*
X1302333Y597417D01*
X1302625Y597208D01*
X1302750Y596917D01*
X1302667Y596625D01*
X1302458Y596417D01*
X1302208Y596333D01*
X1301792D01*
X1301417Y596208D01*
X1301167Y595958D01*
X1301083Y595667D01*
X1301167Y595375D01*
X1301375Y595167D01*
X1301708Y595042D01*
X1302000Y595000D01*
G01X1304392Y595292D02*
X1304683Y595083D01*
X1305017Y595000D01*
X1305350Y595083D01*
X1305642Y595333D01*
X1305850Y595708D01*
X1305933Y596083D01*
Y596542D01*
X1305850Y596917D01*
X1305642Y597250D01*
X1305392Y597417D01*
X1305100Y597500D01*
X1304767Y597417D01*
X1304517Y597250D01*
X1304350Y597000D01*
X1304267Y596667D01*
X1304350Y596375D01*
X1304558Y596083D01*
X1304808Y595917D01*
X1305100Y595875D01*
X1305433Y595958D01*
X1305683Y596167D01*
X1305933Y596542D01*
G01X1308200Y595000D02*
X1308492Y595042D01*
X1308825Y595167D01*
X1309033Y595375D01*
X1309117Y595667D01*
X1309033Y595958D01*
X1308783Y596208D01*
X1308408Y596333D01*
X1307992D01*
X1307742Y596417D01*
X1307533Y596625D01*
X1307450Y596917D01*
X1307575Y597208D01*
X1307867Y597417D01*
X1308200Y597500D01*
X1308533Y597417D01*
X1308825Y597208D01*
X1308950Y596917D01*
X1308867Y596625D01*
X1308658Y596417D01*
X1308408Y596333D01*
X1307992D01*
X1307617Y596208D01*
X1307367Y595958D01*
X1307283Y595667D01*
X1307367Y595375D01*
X1307575Y595167D01*
X1307908Y595042D01*
X1308200Y595000D01*
G01X1297634Y612412D02*
Y614912D01*
X1298675D01*
X1299009Y614787D01*
X1299217Y614620D01*
X1299300Y614287D01*
X1299217Y613954D01*
X1298967Y613745D01*
X1298675Y613620D01*
X1297634D01*
G01X1298675D02*
X1299300Y612412D01*
G01X1300650Y612787D02*
X1300900Y612579D01*
X1301192Y612454D01*
X1301567Y612412D01*
X1301942Y612495D01*
X1302234Y612662D01*
X1302442Y612954D01*
X1302484Y613287D01*
X1302400Y613620D01*
X1302192Y613829D01*
X1301900Y613995D01*
X1301609Y614037D01*
X1301317Y613995D01*
X1300942Y613829D01*
X1301067Y614912D01*
X1302192D01*
G01X1305167Y612412D02*
Y614912D01*
X1303625Y613120D01*
X1305709D01*
G01X1307059Y612704D02*
X1307350Y612495D01*
X1307684Y612412D01*
X1308017Y612495D01*
X1308309Y612745D01*
X1308517Y613120D01*
X1308600Y613495D01*
Y613954D01*
X1308517Y614329D01*
X1308309Y614662D01*
X1308059Y614829D01*
X1307767Y614912D01*
X1307434Y614829D01*
X1307184Y614662D01*
X1307017Y614412D01*
X1306934Y614079D01*
X1307017Y613787D01*
X1307225Y613495D01*
X1307475Y613329D01*
X1307767Y613287D01*
X1308100Y613370D01*
X1308350Y613579D01*
X1308600Y613954D01*
G01X1298017Y599500D02*
Y602000D01*
X1299058D01*
X1299392Y601875D01*
X1299600Y601708D01*
X1299683Y601375D01*
X1299600Y601042D01*
X1299350Y600833D01*
X1299058Y600708D01*
X1298017D01*
G01X1299058D02*
X1299683Y599500D01*
G01X1301033Y599875D02*
X1301283Y599667D01*
X1301575Y599542D01*
X1301950Y599500D01*
X1302325Y599583D01*
X1302617Y599750D01*
X1302825Y600042D01*
X1302867Y600375D01*
X1302783Y600708D01*
X1302575Y600917D01*
X1302283Y601083D01*
X1301992Y601125D01*
X1301700Y601083D01*
X1301325Y600917D01*
X1301450Y602000D01*
X1302575D01*
G01X1304133Y600000D02*
X1304383Y599708D01*
X1304717Y599542D01*
X1305092Y599500D01*
X1305425Y599542D01*
X1305758Y599750D01*
X1305967Y600000D01*
X1306008Y600250D01*
X1305925Y600542D01*
X1305633Y600750D01*
X1305342Y600833D01*
X1304967D01*
G01X1305342D02*
X1305592Y600958D01*
X1305800Y601167D01*
X1305883Y601417D01*
X1305800Y601667D01*
X1305592Y601875D01*
X1305217Y602000D01*
X1304842Y601958D01*
X1304467Y601792D01*
G01X1307358Y600542D02*
X1307650Y600833D01*
X1307900Y601000D01*
X1308233Y601083D01*
X1308525Y601000D01*
X1308733Y600833D01*
X1308900Y600583D01*
X1308942Y600292D01*
X1308900Y600042D01*
X1308733Y599792D01*
X1308483Y599583D01*
X1308192Y599500D01*
X1307858Y599583D01*
X1307567Y599833D01*
X1307400Y600208D01*
X1307358Y600625D01*
X1307442Y601167D01*
X1307567Y601458D01*
X1307775Y601750D01*
X1308067Y601958D01*
X1308358Y602000D01*
X1308650Y601917D01*
X1308858Y601708D01*
G01X1297634Y607912D02*
Y610412D01*
X1298675D01*
X1299009Y610287D01*
X1299217Y610120D01*
X1299300Y609787D01*
X1299217Y609454D01*
X1298967Y609245D01*
X1298675Y609120D01*
X1297634D01*
G01X1298675D02*
X1299300Y607912D01*
G01X1300775Y609995D02*
X1301025Y610245D01*
X1301317Y610370D01*
X1301650Y610412D01*
X1302067Y610329D01*
X1302359Y610120D01*
X1302442Y609870D01*
X1302400Y609620D01*
X1302234Y609412D01*
X1301400Y608995D01*
X1301025Y608704D01*
X1300775Y608287D01*
X1300692Y607912D01*
X1302442D01*
G01X1304667D02*
Y610412D01*
X1304167Y609912D01*
G01Y607912D02*
X1305167D01*
G01X1307684D02*
X1307767Y608454D01*
X1307892Y608912D01*
X1308059Y609329D01*
X1308267Y609787D01*
X1308600Y610412D01*
X1306934D01*
G01X1299384Y606204D02*
X1299134Y606329D01*
X1298842Y606412D01*
X1298509D01*
X1298134Y606287D01*
X1297842Y606079D01*
X1297634Y605829D01*
X1297467Y605412D01*
X1297425Y605037D01*
X1297509Y604662D01*
X1297634Y604412D01*
X1297884Y604162D01*
X1298175Y603995D01*
X1298467Y603912D01*
X1298759D01*
X1299050Y603995D01*
X1299300Y604120D01*
X1299509Y604287D01*
G01X1301567Y603912D02*
Y606412D01*
X1301067Y605912D01*
G01Y603912D02*
X1302067D01*
G01X1303750Y604287D02*
X1304000Y604079D01*
X1304292Y603954D01*
X1304667Y603912D01*
X1305042Y603995D01*
X1305334Y604162D01*
X1305542Y604454D01*
X1305584Y604787D01*
X1305500Y605120D01*
X1305292Y605329D01*
X1305000Y605495D01*
X1304709Y605537D01*
X1304417Y605495D01*
X1304042Y605329D01*
X1304167Y606412D01*
X1305292D01*
G01X1306850Y604287D02*
X1307100Y604079D01*
X1307392Y603954D01*
X1307767Y603912D01*
X1308142Y603995D01*
X1308434Y604162D01*
X1308642Y604454D01*
X1308684Y604787D01*
X1308600Y605120D01*
X1308392Y605329D01*
X1308100Y605495D01*
X1307809Y605537D01*
X1307517Y605495D01*
X1307142Y605329D01*
X1307267Y606412D01*
X1308392D01*
G01X1297634Y621412D02*
Y623912D01*
X1298675D01*
X1299009Y623787D01*
X1299217Y623620D01*
X1299300Y623287D01*
X1299217Y622954D01*
X1298967Y622745D01*
X1298675Y622620D01*
X1297634D01*
G01X1298675D02*
X1299300Y621412D01*
G01X1300775Y623495D02*
X1301025Y623745D01*
X1301317Y623870D01*
X1301650Y623912D01*
X1302067Y623829D01*
X1302359Y623620D01*
X1302442Y623370D01*
X1302400Y623120D01*
X1302234Y622912D01*
X1301400Y622495D01*
X1301025Y622204D01*
X1300775Y621787D01*
X1300692Y621412D01*
X1302442D01*
G01X1304667D02*
Y623912D01*
X1304167Y623412D01*
G01Y621412D02*
X1305167D01*
G01X1306975Y622454D02*
X1307267Y622745D01*
X1307517Y622912D01*
X1307850Y622995D01*
X1308142Y622912D01*
X1308350Y622745D01*
X1308517Y622495D01*
X1308559Y622204D01*
X1308517Y621954D01*
X1308350Y621704D01*
X1308100Y621495D01*
X1307809Y621412D01*
X1307475Y621495D01*
X1307184Y621745D01*
X1307017Y622120D01*
X1306975Y622537D01*
X1307059Y623079D01*
X1307184Y623370D01*
X1307392Y623662D01*
X1307684Y623870D01*
X1307975Y623912D01*
X1308267Y623829D01*
X1308475Y623620D01*
G01X1297634Y616912D02*
Y619412D01*
X1298675D01*
X1299009Y619287D01*
X1299217Y619120D01*
X1299300Y618787D01*
X1299217Y618454D01*
X1298967Y618245D01*
X1298675Y618120D01*
X1297634D01*
G01X1298675D02*
X1299300Y616912D01*
G01X1300775Y618995D02*
X1301025Y619245D01*
X1301317Y619370D01*
X1301650Y619412D01*
X1302067Y619329D01*
X1302359Y619120D01*
X1302442Y618870D01*
X1302400Y618620D01*
X1302234Y618412D01*
X1301400Y617995D01*
X1301025Y617704D01*
X1300775Y617287D01*
X1300692Y616912D01*
X1302442D01*
G01X1305167D02*
Y619412D01*
X1303625Y617620D01*
X1305709D01*
G01X1307767Y616912D02*
X1308059Y616954D01*
X1308392Y617079D01*
X1308600Y617287D01*
X1308684Y617579D01*
X1308600Y617870D01*
X1308350Y618120D01*
X1307975Y618245D01*
X1307559D01*
X1307309Y618329D01*
X1307100Y618537D01*
X1307017Y618829D01*
X1307142Y619120D01*
X1307434Y619329D01*
X1307767Y619412D01*
X1308100Y619329D01*
X1308392Y619120D01*
X1308517Y618829D01*
X1308434Y618537D01*
X1308225Y618329D01*
X1307975Y618245D01*
X1307559D01*
X1307184Y618120D01*
X1306934Y617870D01*
X1306850Y617579D01*
X1306934Y617287D01*
X1307142Y617079D01*
X1307475Y616954D01*
X1307767Y616912D01*
G01X1297983Y635000D02*
Y633208D01*
X1298150Y632833D01*
X1298483Y632583D01*
X1298900Y632500D01*
X1299317Y632583D01*
X1299650Y632833D01*
X1299817Y633208D01*
Y635000D01*
G01X1301208Y634583D02*
X1301458Y634833D01*
X1301750Y634958D01*
X1302083Y635000D01*
X1302500Y634917D01*
X1302792Y634708D01*
X1302875Y634458D01*
X1302833Y634208D01*
X1302667Y634000D01*
X1301833Y633583D01*
X1301458Y633292D01*
X1301208Y632875D01*
X1301125Y632500D01*
X1302875D01*
G01X1304308Y633542D02*
X1304600Y633833D01*
X1304850Y634000D01*
X1305183Y634083D01*
X1305475Y634000D01*
X1305683Y633833D01*
X1305850Y633583D01*
X1305892Y633292D01*
X1305850Y633042D01*
X1305683Y632792D01*
X1305433Y632583D01*
X1305142Y632500D01*
X1304808Y632583D01*
X1304517Y632833D01*
X1304350Y633208D01*
X1304308Y633625D01*
X1304392Y634167D01*
X1304517Y634458D01*
X1304725Y634750D01*
X1305017Y634958D01*
X1305308Y635000D01*
X1305600Y634917D01*
X1305808Y634708D01*
G01X1292968Y653684D02*
X1300968D01*
Y641284D01*
X1292968D01*
Y653684D01*
G01X1296968Y651984D02*
X1298468Y653484D01*
G01X1296968Y651984D02*
X1295468Y653484D01*
G01X1287468Y657584D02*
X1291468D01*
Y664984D01*
G01X1301968Y663484D02*
X1297968D01*
Y656084D01*
G01X1295968Y664984D02*
X1291968D01*
Y657584D01*
G01X1287000Y665200D02*
X1283000D01*
Y657800D01*
G01X1292468Y685184D02*
X1300468D01*
Y672784D01*
X1292468D01*
Y685184D01*
G01X1295983Y691000D02*
Y689208D01*
X1296150Y688833D01*
X1296483Y688583D01*
X1296900Y688500D01*
X1297317Y688583D01*
X1297650Y688833D01*
X1297817Y689208D01*
Y691000D01*
G01X1299208Y690583D02*
X1299458Y690833D01*
X1299750Y690958D01*
X1300083Y691000D01*
X1300500Y690917D01*
X1300792Y690708D01*
X1300875Y690458D01*
X1300833Y690208D01*
X1300667Y690000D01*
X1299833Y689583D01*
X1299458Y689292D01*
X1299208Y688875D01*
X1299125Y688500D01*
X1300875D01*
G01X1303017D02*
X1303100Y689042D01*
X1303225Y689500D01*
X1303392Y689917D01*
X1303600Y690375D01*
X1303933Y691000D01*
X1302267D01*
G01X1296468Y683484D02*
X1297968Y684984D01*
G01X1296468Y683484D02*
X1294968Y684984D01*
G01X1291000Y698967D02*
X1288500D01*
Y700008D01*
X1288625Y700342D01*
X1288792Y700550D01*
X1289125Y700633D01*
X1289458Y700550D01*
X1289667Y700300D01*
X1289792Y700008D01*
Y698967D01*
G01Y700008D02*
X1291000Y700633D01*
G01X1290500Y701983D02*
X1290792Y702233D01*
X1290958Y702567D01*
X1291000Y702942D01*
X1290958Y703275D01*
X1290750Y703608D01*
X1290500Y703817D01*
X1290250Y703858D01*
X1289958Y703775D01*
X1289750Y703483D01*
X1289667Y703192D01*
Y702817D01*
G01Y703192D02*
X1289542Y703442D01*
X1289333Y703650D01*
X1289083Y703733D01*
X1288833Y703650D01*
X1288625Y703442D01*
X1288500Y703067D01*
X1288542Y702692D01*
X1288708Y702317D01*
G01X1288500Y706000D02*
X1288583Y705667D01*
X1288792Y705417D01*
X1289042Y705250D01*
X1289375Y705125D01*
X1289750Y705083D01*
X1290125Y705125D01*
X1290458Y705250D01*
X1290708Y705417D01*
X1290917Y705667D01*
X1291000Y706000D01*
X1290917Y706333D01*
X1290708Y706583D01*
X1290458Y706750D01*
X1290125Y706875D01*
X1289750Y706917D01*
X1289375Y706875D01*
X1289042Y706750D01*
X1288792Y706583D01*
X1288583Y706333D01*
X1288500Y706000D01*
G01X1290708Y708392D02*
X1290917Y708683D01*
X1291000Y709017D01*
X1290917Y709350D01*
X1290667Y709642D01*
X1290292Y709850D01*
X1289917Y709933D01*
X1289458D01*
X1289083Y709850D01*
X1288750Y709642D01*
X1288583Y709392D01*
X1288500Y709100D01*
X1288583Y708767D01*
X1288750Y708517D01*
X1289000Y708350D01*
X1289333Y708267D01*
X1289625Y708350D01*
X1289917Y708558D01*
X1290083Y708808D01*
X1290125Y709100D01*
X1290042Y709433D01*
X1289833Y709683D01*
X1289458Y709933D01*
G01X1291000Y712200D02*
X1290958Y712492D01*
X1290833Y712825D01*
X1290625Y713033D01*
X1290333Y713117D01*
X1290042Y713033D01*
X1289792Y712783D01*
X1289667Y712408D01*
Y711992D01*
X1289583Y711742D01*
X1289375Y711533D01*
X1289083Y711450D01*
X1288792Y711575D01*
X1288583Y711867D01*
X1288500Y712200D01*
X1288583Y712533D01*
X1288792Y712825D01*
X1289083Y712950D01*
X1289375Y712867D01*
X1289583Y712658D01*
X1289667Y712408D01*
Y711992D01*
X1289792Y711617D01*
X1290042Y711367D01*
X1290333Y711283D01*
X1290625Y711367D01*
X1290833Y711575D01*
X1290958Y711908D01*
X1291000Y712200D01*
G01X1295000Y698967D02*
X1292500D01*
Y700008D01*
X1292625Y700342D01*
X1292792Y700550D01*
X1293125Y700633D01*
X1293458Y700550D01*
X1293667Y700300D01*
X1293792Y700008D01*
Y698967D01*
G01Y700008D02*
X1295000Y700633D01*
G01X1294625Y701983D02*
X1294833Y702233D01*
X1294958Y702525D01*
X1295000Y702900D01*
X1294917Y703275D01*
X1294750Y703567D01*
X1294458Y703775D01*
X1294125Y703817D01*
X1293792Y703733D01*
X1293583Y703525D01*
X1293417Y703233D01*
X1293375Y702942D01*
X1293417Y702650D01*
X1293583Y702275D01*
X1292500Y702400D01*
Y703525D01*
G01X1295000Y705917D02*
X1294458Y706000D01*
X1294000Y706125D01*
X1293583Y706292D01*
X1293125Y706500D01*
X1292500Y706833D01*
Y705167D01*
G01X1293958Y708308D02*
X1293667Y708600D01*
X1293500Y708850D01*
X1293417Y709183D01*
X1293500Y709475D01*
X1293667Y709683D01*
X1293917Y709850D01*
X1294208Y709892D01*
X1294458Y709850D01*
X1294708Y709683D01*
X1294917Y709433D01*
X1295000Y709142D01*
X1294917Y708808D01*
X1294667Y708517D01*
X1294292Y708350D01*
X1293875Y708308D01*
X1293333Y708392D01*
X1293042Y708517D01*
X1292750Y708725D01*
X1292542Y709017D01*
X1292500Y709308D01*
X1292583Y709600D01*
X1292792Y709808D01*
G01X1294708Y711492D02*
X1294917Y711783D01*
X1295000Y712117D01*
X1294917Y712450D01*
X1294667Y712742D01*
X1294292Y712950D01*
X1293917Y713033D01*
X1293458D01*
X1293083Y712950D01*
X1292750Y712742D01*
X1292583Y712492D01*
X1292500Y712200D01*
X1292583Y711867D01*
X1292750Y711617D01*
X1293000Y711450D01*
X1293333Y711367D01*
X1293625Y711450D01*
X1293917Y711658D01*
X1294083Y711908D01*
X1294125Y712200D01*
X1294042Y712533D01*
X1293833Y712783D01*
X1293458Y713033D01*
G01X1284708Y700717D02*
X1284583Y700467D01*
X1284500Y700175D01*
Y699842D01*
X1284625Y699467D01*
X1284833Y699175D01*
X1285083Y698967D01*
X1285500Y698800D01*
X1285875Y698758D01*
X1286250Y698842D01*
X1286500Y698967D01*
X1286750Y699217D01*
X1286917Y699508D01*
X1287000Y699800D01*
Y700092D01*
X1286917Y700383D01*
X1286792Y700633D01*
X1286625Y700842D01*
G01X1287000Y702900D02*
X1286958Y703192D01*
X1286833Y703525D01*
X1286625Y703733D01*
X1286333Y703817D01*
X1286042Y703733D01*
X1285792Y703483D01*
X1285667Y703108D01*
Y702692D01*
X1285583Y702442D01*
X1285375Y702233D01*
X1285083Y702150D01*
X1284792Y702275D01*
X1284583Y702567D01*
X1284500Y702900D01*
X1284583Y703233D01*
X1284792Y703525D01*
X1285083Y703650D01*
X1285375Y703567D01*
X1285583Y703358D01*
X1285667Y703108D01*
Y702692D01*
X1285792Y702317D01*
X1286042Y702067D01*
X1286333Y701983D01*
X1286625Y702067D01*
X1286833Y702275D01*
X1286958Y702608D01*
X1287000Y702900D01*
G01X1284500Y706000D02*
X1284583Y705667D01*
X1284792Y705417D01*
X1285042Y705250D01*
X1285375Y705125D01*
X1285750Y705083D01*
X1286125Y705125D01*
X1286458Y705250D01*
X1286708Y705417D01*
X1286917Y705667D01*
X1287000Y706000D01*
X1286917Y706333D01*
X1286708Y706583D01*
X1286458Y706750D01*
X1286125Y706875D01*
X1285750Y706917D01*
X1285375Y706875D01*
X1285042Y706750D01*
X1284792Y706583D01*
X1284583Y706333D01*
X1284500Y706000D01*
G01X1287000Y709100D02*
X1286958Y709392D01*
X1286833Y709725D01*
X1286625Y709933D01*
X1286333Y710017D01*
X1286042Y709933D01*
X1285792Y709683D01*
X1285667Y709308D01*
Y708892D01*
X1285583Y708642D01*
X1285375Y708433D01*
X1285083Y708350D01*
X1284792Y708475D01*
X1284583Y708767D01*
X1284500Y709100D01*
X1284583Y709433D01*
X1284792Y709725D01*
X1285083Y709850D01*
X1285375Y709767D01*
X1285583Y709558D01*
X1285667Y709308D01*
Y708892D01*
X1285792Y708517D01*
X1286042Y708267D01*
X1286333Y708183D01*
X1286625Y708267D01*
X1286833Y708475D01*
X1286958Y708808D01*
X1287000Y709100D01*
G01X1285958Y711408D02*
X1285667Y711700D01*
X1285500Y711950D01*
X1285417Y712283D01*
X1285500Y712575D01*
X1285667Y712783D01*
X1285917Y712950D01*
X1286208Y712992D01*
X1286458Y712950D01*
X1286708Y712783D01*
X1286917Y712533D01*
X1287000Y712242D01*
X1286917Y711908D01*
X1286667Y711617D01*
X1286292Y711450D01*
X1285875Y711408D01*
X1285333Y711492D01*
X1285042Y711617D01*
X1284750Y711825D01*
X1284542Y712117D01*
X1284500Y712408D01*
X1284583Y712700D01*
X1284792Y712908D01*
G01X1287784Y768549D02*
X1285284D01*
Y769590D01*
X1285409Y769924D01*
X1285576Y770132D01*
X1285909Y770215D01*
X1286242Y770132D01*
X1286451Y769882D01*
X1286576Y769590D01*
Y768549D01*
G01Y769590D02*
X1287784Y770215D01*
G01Y772482D02*
X1285284D01*
X1285784Y771982D01*
G01X1287784D02*
Y772982D01*
G01X1287492Y774874D02*
X1287701Y775165D01*
X1287784Y775499D01*
X1287701Y775832D01*
X1287451Y776124D01*
X1287076Y776332D01*
X1286701Y776415D01*
X1286242D01*
X1285867Y776332D01*
X1285534Y776124D01*
X1285367Y775874D01*
X1285284Y775582D01*
X1285367Y775249D01*
X1285534Y774999D01*
X1285784Y774832D01*
X1286117Y774749D01*
X1286409Y774832D01*
X1286701Y775040D01*
X1286867Y775290D01*
X1286909Y775582D01*
X1286826Y775915D01*
X1286617Y776165D01*
X1286242Y776415D01*
G01X1285701Y777890D02*
X1285451Y778140D01*
X1285326Y778432D01*
X1285284Y778765D01*
X1285367Y779182D01*
X1285576Y779474D01*
X1285826Y779557D01*
X1286076Y779515D01*
X1286284Y779349D01*
X1286701Y778515D01*
X1286992Y778140D01*
X1287409Y777890D01*
X1287784Y777807D01*
Y779557D01*
G01X1292784Y768549D02*
X1290284D01*
Y769590D01*
X1290409Y769924D01*
X1290576Y770132D01*
X1290909Y770215D01*
X1291242Y770132D01*
X1291451Y769882D01*
X1291576Y769590D01*
Y768549D01*
G01Y769590D02*
X1292784Y770215D01*
G01Y772482D02*
X1290284D01*
X1290784Y771982D01*
G01X1292784D02*
Y772982D01*
G01X1292492Y774874D02*
X1292701Y775165D01*
X1292784Y775499D01*
X1292701Y775832D01*
X1292451Y776124D01*
X1292076Y776332D01*
X1291701Y776415D01*
X1291242D01*
X1290867Y776332D01*
X1290534Y776124D01*
X1290367Y775874D01*
X1290284Y775582D01*
X1290367Y775249D01*
X1290534Y774999D01*
X1290784Y774832D01*
X1291117Y774749D01*
X1291409Y774832D01*
X1291701Y775040D01*
X1291867Y775290D01*
X1291909Y775582D01*
X1291826Y775915D01*
X1291617Y776165D01*
X1291242Y776415D01*
G01X1292284Y777765D02*
X1292576Y778015D01*
X1292742Y778349D01*
X1292784Y778724D01*
X1292742Y779057D01*
X1292534Y779390D01*
X1292284Y779599D01*
X1292034Y779640D01*
X1291742Y779557D01*
X1291534Y779265D01*
X1291451Y778974D01*
Y778599D01*
G01Y778974D02*
X1291326Y779224D01*
X1291117Y779432D01*
X1290867Y779515D01*
X1290617Y779432D01*
X1290409Y779224D01*
X1290284Y778849D01*
X1290326Y778474D01*
X1290492Y778099D01*
G01X1297784Y768549D02*
X1295284D01*
Y769590D01*
X1295409Y769924D01*
X1295576Y770132D01*
X1295909Y770215D01*
X1296242Y770132D01*
X1296451Y769882D01*
X1296576Y769590D01*
Y768549D01*
G01Y769590D02*
X1297784Y770215D01*
G01Y772482D02*
X1295284D01*
X1295784Y771982D01*
G01X1297784D02*
Y772982D01*
G01X1297492Y774874D02*
X1297701Y775165D01*
X1297784Y775499D01*
X1297701Y775832D01*
X1297451Y776124D01*
X1297076Y776332D01*
X1296701Y776415D01*
X1296242D01*
X1295867Y776332D01*
X1295534Y776124D01*
X1295367Y775874D01*
X1295284Y775582D01*
X1295367Y775249D01*
X1295534Y774999D01*
X1295784Y774832D01*
X1296117Y774749D01*
X1296409Y774832D01*
X1296701Y775040D01*
X1296867Y775290D01*
X1296909Y775582D01*
X1296826Y775915D01*
X1296617Y776165D01*
X1296242Y776415D01*
G01X1297784Y779182D02*
X1295284D01*
X1297076Y777640D01*
Y779724D01*
G01X1287284Y783549D02*
X1284784D01*
Y784590D01*
X1284909Y784924D01*
X1285076Y785132D01*
X1285409Y785215D01*
X1285742Y785132D01*
X1285951Y784882D01*
X1286076Y784590D01*
Y783549D01*
G01Y784590D02*
X1287284Y785215D01*
G01Y787482D02*
X1284784D01*
X1285284Y786982D01*
G01X1287284D02*
Y787982D01*
G01X1286992Y789874D02*
X1287201Y790165D01*
X1287284Y790499D01*
X1287201Y790832D01*
X1286951Y791124D01*
X1286576Y791332D01*
X1286201Y791415D01*
X1285742D01*
X1285367Y791332D01*
X1285034Y791124D01*
X1284867Y790874D01*
X1284784Y790582D01*
X1284867Y790249D01*
X1285034Y789999D01*
X1285284Y789832D01*
X1285617Y789749D01*
X1285909Y789832D01*
X1286201Y790040D01*
X1286367Y790290D01*
X1286409Y790582D01*
X1286326Y790915D01*
X1286117Y791165D01*
X1285742Y791415D01*
G01X1287284Y793599D02*
X1286742Y793682D01*
X1286284Y793807D01*
X1285867Y793974D01*
X1285409Y794182D01*
X1284784Y794515D01*
Y792849D01*
G01X1292284Y783549D02*
X1289784D01*
Y784590D01*
X1289909Y784924D01*
X1290076Y785132D01*
X1290409Y785215D01*
X1290742Y785132D01*
X1290951Y784882D01*
X1291076Y784590D01*
Y783549D01*
G01Y784590D02*
X1292284Y785215D01*
G01Y787482D02*
X1289784D01*
X1290284Y786982D01*
G01X1292284D02*
Y787982D01*
G01X1291992Y789874D02*
X1292201Y790165D01*
X1292284Y790499D01*
X1292201Y790832D01*
X1291951Y791124D01*
X1291576Y791332D01*
X1291201Y791415D01*
X1290742D01*
X1290367Y791332D01*
X1290034Y791124D01*
X1289867Y790874D01*
X1289784Y790582D01*
X1289867Y790249D01*
X1290034Y789999D01*
X1290284Y789832D01*
X1290617Y789749D01*
X1290909Y789832D01*
X1291201Y790040D01*
X1291367Y790290D01*
X1291409Y790582D01*
X1291326Y790915D01*
X1291117Y791165D01*
X1290742Y791415D01*
G01X1292284Y793682D02*
X1292242Y793974D01*
X1292117Y794307D01*
X1291909Y794515D01*
X1291617Y794599D01*
X1291326Y794515D01*
X1291076Y794265D01*
X1290951Y793890D01*
Y793474D01*
X1290867Y793224D01*
X1290659Y793015D01*
X1290367Y792932D01*
X1290076Y793057D01*
X1289867Y793349D01*
X1289784Y793682D01*
X1289867Y794015D01*
X1290076Y794307D01*
X1290367Y794432D01*
X1290659Y794349D01*
X1290867Y794140D01*
X1290951Y793890D01*
Y793474D01*
X1291076Y793099D01*
X1291326Y792849D01*
X1291617Y792765D01*
X1291909Y792849D01*
X1292117Y793057D01*
X1292242Y793390D01*
X1292284Y793682D01*
G01X1297784Y783549D02*
X1295284D01*
Y784590D01*
X1295409Y784924D01*
X1295576Y785132D01*
X1295909Y785215D01*
X1296242Y785132D01*
X1296451Y784882D01*
X1296576Y784590D01*
Y783549D01*
G01Y784590D02*
X1297784Y785215D01*
G01Y787482D02*
X1295284D01*
X1295784Y786982D01*
G01X1297784D02*
Y787982D01*
G01X1297492Y789874D02*
X1297701Y790165D01*
X1297784Y790499D01*
X1297701Y790832D01*
X1297451Y791124D01*
X1297076Y791332D01*
X1296701Y791415D01*
X1296242D01*
X1295867Y791332D01*
X1295534Y791124D01*
X1295367Y790874D01*
X1295284Y790582D01*
X1295367Y790249D01*
X1295534Y789999D01*
X1295784Y789832D01*
X1296117Y789749D01*
X1296409Y789832D01*
X1296701Y790040D01*
X1296867Y790290D01*
X1296909Y790582D01*
X1296826Y790915D01*
X1296617Y791165D01*
X1296242Y791415D01*
G01X1297492Y792974D02*
X1297701Y793265D01*
X1297784Y793599D01*
X1297701Y793932D01*
X1297451Y794224D01*
X1297076Y794432D01*
X1296701Y794515D01*
X1296242D01*
X1295867Y794432D01*
X1295534Y794224D01*
X1295367Y793974D01*
X1295284Y793682D01*
X1295367Y793349D01*
X1295534Y793099D01*
X1295784Y792932D01*
X1296117Y792849D01*
X1296409Y792932D01*
X1296701Y793140D01*
X1296867Y793390D01*
X1296909Y793682D01*
X1296826Y794015D01*
X1296617Y794265D01*
X1296242Y794515D01*
G01X1295500Y806483D02*
X1297292D01*
X1297667Y806650D01*
X1297917Y806983D01*
X1298000Y807400D01*
X1297917Y807817D01*
X1297667Y808150D01*
X1297292Y808317D01*
X1295500D01*
G01X1298000Y810500D02*
X1295500D01*
X1296000Y810000D01*
G01X1298000D02*
Y811000D01*
G01X1296958Y812808D02*
X1296667Y813100D01*
X1296500Y813350D01*
X1296417Y813683D01*
X1296500Y813975D01*
X1296667Y814183D01*
X1296917Y814350D01*
X1297208Y814392D01*
X1297458Y814350D01*
X1297708Y814183D01*
X1297917Y813933D01*
X1298000Y813642D01*
X1297917Y813308D01*
X1297667Y813017D01*
X1297292Y812850D01*
X1296875Y812808D01*
X1296333Y812892D01*
X1296042Y813017D01*
X1295750Y813225D01*
X1295542Y813517D01*
X1295500Y813808D01*
X1295583Y814100D01*
X1295792Y814308D01*
G01X1290968Y841584D02*
X1294968D01*
Y848984D01*
G01X1288968Y838301D02*
X1286468D01*
Y839342D01*
X1286593Y839676D01*
X1286760Y839884D01*
X1287093Y839967D01*
X1287426Y839884D01*
X1287635Y839634D01*
X1287760Y839342D01*
Y838301D01*
G01Y839342D02*
X1288968Y839967D01*
G01Y842234D02*
X1286468D01*
X1286968Y841734D01*
G01X1288968D02*
Y842734D01*
G01Y845334D02*
X1288926Y845626D01*
X1288801Y845959D01*
X1288593Y846167D01*
X1288301Y846251D01*
X1288010Y846167D01*
X1287760Y845917D01*
X1287635Y845542D01*
Y845126D01*
X1287551Y844876D01*
X1287343Y844667D01*
X1287051Y844584D01*
X1286760Y844709D01*
X1286551Y845001D01*
X1286468Y845334D01*
X1286551Y845667D01*
X1286760Y845959D01*
X1287051Y846084D01*
X1287343Y846001D01*
X1287551Y845792D01*
X1287635Y845542D01*
Y845126D01*
X1287760Y844751D01*
X1288010Y844501D01*
X1288301Y844417D01*
X1288593Y844501D01*
X1288801Y844709D01*
X1288926Y845042D01*
X1288968Y845334D01*
G01X1286885Y847642D02*
X1286635Y847892D01*
X1286510Y848184D01*
X1286468Y848517D01*
X1286551Y848934D01*
X1286760Y849226D01*
X1287010Y849309D01*
X1287260Y849267D01*
X1287468Y849101D01*
X1287885Y848267D01*
X1288176Y847892D01*
X1288593Y847642D01*
X1288968Y847559D01*
Y849309D01*
G01X1295468Y841584D02*
X1299468D01*
Y848984D01*
G01X1291767Y854292D02*
X1291517Y854417D01*
X1291225Y854500D01*
X1290892D01*
X1290517Y854375D01*
X1290225Y854167D01*
X1290017Y853917D01*
X1289850Y853500D01*
X1289808Y853125D01*
X1289892Y852750D01*
X1290017Y852500D01*
X1290267Y852250D01*
X1290558Y852083D01*
X1290850Y852000D01*
X1291142D01*
X1291433Y852083D01*
X1291683Y852208D01*
X1291892Y852375D01*
G01X1293950Y852000D02*
Y854500D01*
X1293450Y854000D01*
G01Y852000D02*
X1294450D01*
G01X1297550D02*
Y854500D01*
X1296008Y852708D01*
X1298092D01*
G01X1299358Y853042D02*
X1299650Y853333D01*
X1299900Y853500D01*
X1300233Y853583D01*
X1300525Y853500D01*
X1300733Y853333D01*
X1300900Y853083D01*
X1300942Y852792D01*
X1300900Y852542D01*
X1300733Y852292D01*
X1300483Y852083D01*
X1300192Y852000D01*
X1299858Y852083D01*
X1299567Y852333D01*
X1299400Y852708D01*
X1299358Y853125D01*
X1299442Y853667D01*
X1299567Y853958D01*
X1299775Y854250D01*
X1300067Y854458D01*
X1300358Y854500D01*
X1300650Y854417D01*
X1300858Y854208D01*
G01X1291767Y858792D02*
X1291517Y858917D01*
X1291225Y859000D01*
X1290892D01*
X1290517Y858875D01*
X1290225Y858667D01*
X1290017Y858417D01*
X1289850Y858000D01*
X1289808Y857625D01*
X1289892Y857250D01*
X1290017Y857000D01*
X1290267Y856750D01*
X1290558Y856583D01*
X1290850Y856500D01*
X1291142D01*
X1291433Y856583D01*
X1291683Y856708D01*
X1291892Y856875D01*
G01X1293950Y856500D02*
Y859000D01*
X1293450Y858500D01*
G01Y856500D02*
X1294450D01*
G01X1297550D02*
Y859000D01*
X1296008Y857208D01*
X1298092D01*
G01X1299233Y856875D02*
X1299483Y856667D01*
X1299775Y856542D01*
X1300150Y856500D01*
X1300525Y856583D01*
X1300817Y856750D01*
X1301025Y857042D01*
X1301067Y857375D01*
X1300983Y857708D01*
X1300775Y857917D01*
X1300483Y858083D01*
X1300192Y858125D01*
X1299900Y858083D01*
X1299525Y857917D01*
X1299650Y859000D01*
X1300775D01*
G01X1293000Y877483D02*
X1294792D01*
X1295167Y877650D01*
X1295417Y877983D01*
X1295500Y878400D01*
X1295417Y878817D01*
X1295167Y879150D01*
X1294792Y879317D01*
X1293000D01*
G01X1295500Y881500D02*
X1293000D01*
X1293500Y881000D01*
G01X1295500D02*
Y882000D01*
G01Y885100D02*
X1293000D01*
X1294792Y883558D01*
Y885642D01*
G01X1305000Y17467D02*
X1307500D01*
Y19133D01*
G01Y22233D02*
Y20567D01*
X1305000D01*
Y22233D01*
G01X1306208Y21567D02*
Y20567D01*
G01X1307500Y23583D02*
X1305000D01*
Y24417D01*
X1305125Y24750D01*
X1305292Y25000D01*
X1305542Y25208D01*
X1305833Y25375D01*
X1306250Y25417D01*
X1306667Y25375D01*
X1306958Y25208D01*
X1307208Y25000D01*
X1307375Y24750D01*
X1307500Y24417D01*
Y23583D01*
G01Y27600D02*
X1305000D01*
X1305500Y27100D01*
G01X1307500D02*
Y28100D01*
G01X1307125Y29783D02*
X1307333Y30033D01*
X1307458Y30325D01*
X1307500Y30700D01*
X1307417Y31075D01*
X1307250Y31367D01*
X1306958Y31575D01*
X1306625Y31617D01*
X1306292Y31533D01*
X1306083Y31325D01*
X1305917Y31033D01*
X1305875Y30742D01*
X1305917Y30450D01*
X1306083Y30075D01*
X1305000Y30200D01*
Y31325D01*
G01X1301000Y17467D02*
X1303500D01*
Y19133D01*
G01Y22233D02*
Y20567D01*
X1301000D01*
Y22233D01*
G01X1302208Y21567D02*
Y20567D01*
G01X1303500Y23583D02*
X1301000D01*
Y24417D01*
X1301125Y24750D01*
X1301292Y25000D01*
X1301542Y25208D01*
X1301833Y25375D01*
X1302250Y25417D01*
X1302667Y25375D01*
X1302958Y25208D01*
X1303208Y25000D01*
X1303375Y24750D01*
X1303500Y24417D01*
Y23583D01*
G01Y27600D02*
X1301000D01*
X1301500Y27100D01*
G01X1303500D02*
Y28100D01*
G01Y31200D02*
X1301000D01*
X1302792Y29658D01*
Y31742D01*
G01X1309450Y22650D02*
X1315550D01*
G01X1309450Y11350D02*
Y22650D01*
G01X1315550Y11350D02*
X1309450D01*
G01X1312500Y45200D02*
X1308500D01*
Y37800D01*
G01X1316500Y45200D02*
X1312500D01*
Y37800D01*
G01X1301510Y48237D02*
X1315510D01*
G01X1301510Y61237D02*
Y48237D01*
G01X1312875Y63833D02*
X1313208Y63625D01*
X1313583Y63500D01*
X1313917D01*
X1314250Y63625D01*
X1314500Y63833D01*
X1314625Y64125D01*
X1314542Y64417D01*
X1314333Y64667D01*
X1313958Y64833D01*
X1313458Y64917D01*
X1313167Y65083D01*
X1313042Y65375D01*
X1313125Y65667D01*
X1313333Y65875D01*
X1313625Y66000D01*
X1313917D01*
X1314208Y65917D01*
X1314458Y65708D01*
G01X1316017Y66000D02*
Y63500D01*
X1317683D01*
G01X1320783D02*
X1319117D01*
Y66000D01*
X1320783D01*
G01X1320117Y64792D02*
X1319117D01*
G01X1322133Y63500D02*
Y66000D01*
X1322967D01*
X1323300Y65875D01*
X1323550Y65708D01*
X1323758Y65458D01*
X1323925Y65167D01*
X1323967Y64750D01*
X1323925Y64333D01*
X1323758Y64042D01*
X1323550Y63792D01*
X1323300Y63625D01*
X1322967Y63500D01*
X1322133D01*
G01X1325358Y65583D02*
X1325608Y65833D01*
X1325900Y65958D01*
X1326233Y66000D01*
X1326650Y65917D01*
X1326942Y65708D01*
X1327025Y65458D01*
X1326983Y65208D01*
X1326817Y65000D01*
X1325983Y64583D01*
X1325608Y64292D01*
X1325358Y63875D01*
X1325275Y63500D01*
X1327025D01*
G01X1329250D02*
X1329542Y63542D01*
X1329875Y63667D01*
X1330083Y63875D01*
X1330167Y64167D01*
X1330083Y64458D01*
X1329833Y64708D01*
X1329458Y64833D01*
X1329042D01*
X1328792Y64917D01*
X1328583Y65125D01*
X1328500Y65417D01*
X1328625Y65708D01*
X1328917Y65917D01*
X1329250Y66000D01*
X1329583Y65917D01*
X1329875Y65708D01*
X1330000Y65417D01*
X1329917Y65125D01*
X1329708Y64917D01*
X1329458Y64833D01*
X1329042D01*
X1328667Y64708D01*
X1328417Y64458D01*
X1328333Y64167D01*
X1328417Y63875D01*
X1328625Y63667D01*
X1328958Y63542D01*
X1329250Y63500D01*
G01X1303400Y63000D02*
X1303067Y63042D01*
X1302775Y63208D01*
X1302525Y63458D01*
X1302358Y63750D01*
X1302275Y64083D01*
Y64417D01*
X1302358Y64750D01*
X1302525Y65042D01*
X1302775Y65292D01*
X1303067Y65458D01*
X1303400Y65500D01*
X1303733Y65458D01*
X1304025Y65292D01*
X1304275Y65042D01*
X1304442Y64750D01*
X1304525Y64417D01*
Y64083D01*
X1304442Y63750D01*
X1304275Y63458D01*
X1304025Y63208D01*
X1303733Y63042D01*
X1303400Y63000D01*
G01X1303733Y63667D02*
X1304233Y63000D01*
G01X1305708Y65083D02*
X1305958Y65333D01*
X1306250Y65458D01*
X1306583Y65500D01*
X1307000Y65417D01*
X1307292Y65208D01*
X1307375Y64958D01*
X1307333Y64708D01*
X1307167Y64500D01*
X1306333Y64083D01*
X1305958Y63792D01*
X1305708Y63375D01*
X1305625Y63000D01*
X1307375D01*
G01X1309600D02*
Y65500D01*
X1309100Y65000D01*
G01Y63000D02*
X1310100D01*
G01X1315510Y61237D02*
X1301510D01*
G01X1310522Y290600D02*
Y311700D01*
G01X1301122Y308100D02*
X1304722Y311700D01*
G01X1310800Y320000D02*
Y316000D01*
X1318200D01*
G01X1303300Y318500D02*
Y314500D01*
X1310700D01*
G01X1312500Y322517D02*
X1310000D01*
Y323558D01*
X1310125Y323892D01*
X1310292Y324100D01*
X1310625Y324183D01*
X1310958Y324100D01*
X1311167Y323850D01*
X1311292Y323558D01*
Y322517D01*
G01Y323558D02*
X1312500Y324183D01*
G01X1311458Y325658D02*
X1311167Y325950D01*
X1311000Y326200D01*
X1310917Y326533D01*
X1311000Y326825D01*
X1311167Y327033D01*
X1311417Y327200D01*
X1311708Y327242D01*
X1311958Y327200D01*
X1312208Y327033D01*
X1312417Y326783D01*
X1312500Y326492D01*
X1312417Y326158D01*
X1312167Y325867D01*
X1311792Y325700D01*
X1311375Y325658D01*
X1310833Y325742D01*
X1310542Y325867D01*
X1310250Y326075D01*
X1310042Y326367D01*
X1310000Y326658D01*
X1310083Y326950D01*
X1310292Y327158D01*
G01X1312500Y329550D02*
X1312458Y329842D01*
X1312333Y330175D01*
X1312125Y330383D01*
X1311833Y330467D01*
X1311542Y330383D01*
X1311292Y330133D01*
X1311167Y329758D01*
Y329342D01*
X1311083Y329092D01*
X1310875Y328883D01*
X1310583Y328800D01*
X1310292Y328925D01*
X1310083Y329217D01*
X1310000Y329550D01*
X1310083Y329883D01*
X1310292Y330175D01*
X1310583Y330300D01*
X1310875Y330217D01*
X1311083Y330008D01*
X1311167Y329758D01*
Y329342D01*
X1311292Y328967D01*
X1311542Y328717D01*
X1311833Y328633D01*
X1312125Y328717D01*
X1312333Y328925D01*
X1312458Y329258D01*
X1312500Y329550D01*
G01X1310417Y331858D02*
X1310167Y332108D01*
X1310042Y332400D01*
X1310000Y332733D01*
X1310083Y333150D01*
X1310292Y333442D01*
X1310542Y333525D01*
X1310792Y333483D01*
X1311000Y333317D01*
X1311417Y332483D01*
X1311708Y332108D01*
X1312125Y331858D01*
X1312500Y331775D01*
Y333525D01*
G01X1308000Y322517D02*
X1305500D01*
Y323558D01*
X1305625Y323892D01*
X1305792Y324100D01*
X1306125Y324183D01*
X1306458Y324100D01*
X1306667Y323850D01*
X1306792Y323558D01*
Y322517D01*
G01Y323558D02*
X1308000Y324183D01*
G01X1307500Y325533D02*
X1307792Y325783D01*
X1307958Y326117D01*
X1308000Y326492D01*
X1307958Y326825D01*
X1307750Y327158D01*
X1307500Y327367D01*
X1307250Y327408D01*
X1306958Y327325D01*
X1306750Y327033D01*
X1306667Y326742D01*
Y326367D01*
G01Y326742D02*
X1306542Y326992D01*
X1306333Y327200D01*
X1306083Y327283D01*
X1305833Y327200D01*
X1305625Y326992D01*
X1305500Y326617D01*
X1305542Y326242D01*
X1305708Y325867D01*
G01X1307500Y328633D02*
X1307792Y328883D01*
X1307958Y329217D01*
X1308000Y329592D01*
X1307958Y329925D01*
X1307750Y330258D01*
X1307500Y330467D01*
X1307250Y330508D01*
X1306958Y330425D01*
X1306750Y330133D01*
X1306667Y329842D01*
Y329467D01*
G01Y329842D02*
X1306542Y330092D01*
X1306333Y330300D01*
X1306083Y330383D01*
X1305833Y330300D01*
X1305625Y330092D01*
X1305500Y329717D01*
X1305542Y329342D01*
X1305708Y328967D01*
G01X1307708Y331942D02*
X1307917Y332233D01*
X1308000Y332567D01*
X1307917Y332900D01*
X1307667Y333192D01*
X1307292Y333400D01*
X1306917Y333483D01*
X1306458D01*
X1306083Y333400D01*
X1305750Y333192D01*
X1305583Y332942D01*
X1305500Y332650D01*
X1305583Y332317D01*
X1305750Y332067D01*
X1306000Y331900D01*
X1306333Y331817D01*
X1306625Y331900D01*
X1306917Y332108D01*
X1307083Y332358D01*
X1307125Y332650D01*
X1307042Y332983D01*
X1306833Y333233D01*
X1306458Y333483D01*
G01X1302567Y340000D02*
X1302775Y339750D01*
X1303025Y339583D01*
X1303317Y339500D01*
X1303650Y339583D01*
X1303900Y339750D01*
X1304150Y340000D01*
X1304233Y340333D01*
Y342000D01*
G01X1305667Y339500D02*
Y342000D01*
X1306667D01*
X1307000Y341875D01*
X1307250Y341583D01*
X1307333Y341250D01*
X1307250Y340917D01*
X1307042Y340667D01*
X1306667Y340542D01*
X1305667D01*
G01X1309600Y339500D02*
Y342000D01*
X1309100Y341500D01*
G01Y339500D02*
X1310100D01*
G01X1298700Y367000D02*
Y375000D01*
G01X1304200Y367000D02*
X1298700D01*
G01X1316300D02*
X1310800D01*
G01X1315017Y361000D02*
Y363500D01*
X1316017D01*
X1316350Y363375D01*
X1316600Y363083D01*
X1316683Y362750D01*
X1316600Y362417D01*
X1316392Y362167D01*
X1316017Y362042D01*
X1315017D01*
G01X1319867Y363292D02*
X1319617Y363417D01*
X1319325Y363500D01*
X1318992D01*
X1318617Y363375D01*
X1318325Y363167D01*
X1318117Y362917D01*
X1317950Y362500D01*
X1317908Y362125D01*
X1317992Y361750D01*
X1318117Y361500D01*
X1318367Y361250D01*
X1318658Y361083D01*
X1318950Y361000D01*
X1319242D01*
X1319533Y361083D01*
X1319783Y361208D01*
X1319992Y361375D01*
G01X1321133Y361500D02*
X1321383Y361208D01*
X1321717Y361042D01*
X1322092Y361000D01*
X1322425Y361042D01*
X1322758Y361250D01*
X1322967Y361500D01*
X1323008Y361750D01*
X1322925Y362042D01*
X1322633Y362250D01*
X1322342Y362333D01*
X1321967D01*
G01X1322342D02*
X1322592Y362458D01*
X1322800Y362667D01*
X1322883Y362917D01*
X1322800Y363167D01*
X1322592Y363375D01*
X1322217Y363500D01*
X1321842Y363458D01*
X1321467Y363292D01*
G01X1324358Y362042D02*
X1324650Y362333D01*
X1324900Y362500D01*
X1325233Y362583D01*
X1325525Y362500D01*
X1325733Y362333D01*
X1325900Y362083D01*
X1325942Y361792D01*
X1325900Y361542D01*
X1325733Y361292D01*
X1325483Y361083D01*
X1325192Y361000D01*
X1324858Y361083D01*
X1324567Y361333D01*
X1324400Y361708D01*
X1324358Y362125D01*
X1324442Y362667D01*
X1324567Y362958D01*
X1324775Y363250D01*
X1325067Y363458D01*
X1325358Y363500D01*
X1325650Y363417D01*
X1325858Y363208D01*
G01X1298700Y375000D02*
X1304200D01*
G01X1310800D02*
X1316300D01*
G01X1298700Y384000D02*
X1304200D01*
G01X1298700Y376000D02*
Y384000D01*
G01X1304200Y376000D02*
X1298700D01*
G01X1316300D02*
X1310800D01*
G01Y384000D02*
X1316300D01*
G01X1302567Y424500D02*
Y427000D01*
X1303567D01*
X1303900Y426875D01*
X1304150Y426583D01*
X1304233Y426250D01*
X1304150Y425917D01*
X1303942Y425667D01*
X1303567Y425542D01*
X1302567D01*
G01X1305667Y427000D02*
Y424500D01*
X1307333D01*
G01X1308683Y425000D02*
X1308933Y424708D01*
X1309267Y424542D01*
X1309642Y424500D01*
X1309975Y424542D01*
X1310308Y424750D01*
X1310517Y425000D01*
X1310558Y425250D01*
X1310475Y425542D01*
X1310183Y425750D01*
X1309892Y425833D01*
X1309517D01*
G01X1309892D02*
X1310142Y425958D01*
X1310350Y426167D01*
X1310433Y426417D01*
X1310350Y426667D01*
X1310142Y426875D01*
X1309767Y427000D01*
X1309392Y426958D01*
X1309017Y426792D01*
G01X1314800Y430500D02*
X1320000D01*
G01X1314800Y423500D02*
X1322600D01*
G01X1314800Y430500D02*
Y423500D01*
G01X1313500Y431517D02*
X1311000D01*
Y432517D01*
X1311125Y432850D01*
X1311417Y433100D01*
X1311750Y433183D01*
X1312083Y433100D01*
X1312333Y432892D01*
X1312458Y432517D01*
Y431517D01*
G01X1313500Y434617D02*
X1311000D01*
Y435658D01*
X1311125Y435992D01*
X1311292Y436200D01*
X1311625Y436283D01*
X1311958Y436200D01*
X1312167Y435950D01*
X1312292Y435658D01*
Y434617D01*
G01Y435658D02*
X1313500Y436283D01*
G01X1311417Y437758D02*
X1311167Y438008D01*
X1311042Y438300D01*
X1311000Y438633D01*
X1311083Y439050D01*
X1311292Y439342D01*
X1311542Y439425D01*
X1311792Y439383D01*
X1312000Y439217D01*
X1312417Y438383D01*
X1312708Y438008D01*
X1313125Y437758D01*
X1313500Y437675D01*
Y439425D01*
G01Y441650D02*
X1313458Y441942D01*
X1313333Y442275D01*
X1313125Y442483D01*
X1312833Y442567D01*
X1312542Y442483D01*
X1312292Y442233D01*
X1312167Y441858D01*
Y441442D01*
X1312083Y441192D01*
X1311875Y440983D01*
X1311583Y440900D01*
X1311292Y441025D01*
X1311083Y441317D01*
X1311000Y441650D01*
X1311083Y441983D01*
X1311292Y442275D01*
X1311583Y442400D01*
X1311875Y442317D01*
X1312083Y442108D01*
X1312167Y441858D01*
Y441442D01*
X1312292Y441067D01*
X1312542Y440817D01*
X1312833Y440733D01*
X1313125Y440817D01*
X1313333Y441025D01*
X1313458Y441358D01*
X1313500Y441650D01*
G01X1308668Y431284D02*
Y438284D01*
G01X1302268Y431284D02*
X1308668D01*
G01Y438284D02*
X1299968D01*
G01X1308500Y446517D02*
X1306000D01*
Y447517D01*
X1306125Y447850D01*
X1306417Y448100D01*
X1306750Y448183D01*
X1307083Y448100D01*
X1307333Y447892D01*
X1307458Y447517D01*
Y446517D01*
G01X1306208Y451367D02*
X1306083Y451117D01*
X1306000Y450825D01*
Y450492D01*
X1306125Y450117D01*
X1306333Y449825D01*
X1306583Y449617D01*
X1307000Y449450D01*
X1307375Y449408D01*
X1307750Y449492D01*
X1308000Y449617D01*
X1308250Y449867D01*
X1308417Y450158D01*
X1308500Y450450D01*
Y450742D01*
X1308417Y451033D01*
X1308292Y451283D01*
X1308125Y451492D01*
G01X1306417Y452758D02*
X1306167Y453008D01*
X1306042Y453300D01*
X1306000Y453633D01*
X1306083Y454050D01*
X1306292Y454342D01*
X1306542Y454425D01*
X1306792Y454383D01*
X1307000Y454217D01*
X1307417Y453383D01*
X1307708Y453008D01*
X1308125Y452758D01*
X1308500Y452675D01*
Y454425D01*
G01Y456650D02*
X1306000D01*
X1306500Y456150D01*
G01X1308500D02*
Y457150D01*
G01X1302500Y441017D02*
X1300000D01*
Y442017D01*
X1300125Y442350D01*
X1300417Y442600D01*
X1300750Y442683D01*
X1301083Y442600D01*
X1301333Y442392D01*
X1301458Y442017D01*
Y441017D01*
G01X1300208Y445867D02*
X1300083Y445617D01*
X1300000Y445325D01*
Y444992D01*
X1300125Y444617D01*
X1300333Y444325D01*
X1300583Y444117D01*
X1301000Y443950D01*
X1301375Y443908D01*
X1301750Y443992D01*
X1302000Y444117D01*
X1302250Y444367D01*
X1302417Y444658D01*
X1302500Y444950D01*
Y445242D01*
X1302417Y445533D01*
X1302292Y445783D01*
X1302125Y445992D01*
G01X1300417Y447258D02*
X1300167Y447508D01*
X1300042Y447800D01*
X1300000Y448133D01*
X1300083Y448550D01*
X1300292Y448842D01*
X1300542Y448925D01*
X1300792Y448883D01*
X1301000Y448717D01*
X1301417Y447883D01*
X1301708Y447508D01*
X1302125Y447258D01*
X1302500Y447175D01*
Y448925D01*
G01X1302125Y450233D02*
X1302333Y450483D01*
X1302458Y450775D01*
X1302500Y451150D01*
X1302417Y451525D01*
X1302250Y451817D01*
X1301958Y452025D01*
X1301625Y452067D01*
X1301292Y451983D01*
X1301083Y451775D01*
X1300917Y451483D01*
X1300875Y451192D01*
X1300917Y450900D01*
X1301083Y450525D01*
X1300000Y450650D01*
Y451775D01*
G01X1305600Y459800D02*
Y473200D01*
G01X1303500Y476567D02*
X1301000D01*
Y477567D01*
X1301125Y477900D01*
X1301417Y478150D01*
X1301750Y478233D01*
X1302083Y478150D01*
X1302333Y477942D01*
X1302458Y477567D01*
Y476567D01*
G01X1301000Y479667D02*
X1303500D01*
Y481333D01*
G01X1301417Y482808D02*
X1301167Y483058D01*
X1301042Y483350D01*
X1301000Y483683D01*
X1301083Y484100D01*
X1301292Y484392D01*
X1301542Y484475D01*
X1301792Y484433D01*
X1302000Y484267D01*
X1302417Y483433D01*
X1302708Y483058D01*
X1303125Y482808D01*
X1303500Y482725D01*
Y484475D01*
G01X1312134Y549912D02*
Y552412D01*
X1313175D01*
X1313509Y552287D01*
X1313717Y552120D01*
X1313800Y551787D01*
X1313717Y551454D01*
X1313467Y551245D01*
X1313175Y551120D01*
X1312134D01*
G01X1313175D02*
X1313800Y549912D01*
G01X1315150Y550287D02*
X1315400Y550079D01*
X1315692Y549954D01*
X1316067Y549912D01*
X1316442Y549995D01*
X1316734Y550162D01*
X1316942Y550454D01*
X1316984Y550787D01*
X1316900Y551120D01*
X1316692Y551329D01*
X1316400Y551495D01*
X1316109Y551537D01*
X1315817Y551495D01*
X1315442Y551329D01*
X1315567Y552412D01*
X1316692D01*
G01X1318250Y550287D02*
X1318500Y550079D01*
X1318792Y549954D01*
X1319167Y549912D01*
X1319542Y549995D01*
X1319834Y550162D01*
X1320042Y550454D01*
X1320084Y550787D01*
X1320000Y551120D01*
X1319792Y551329D01*
X1319500Y551495D01*
X1319209Y551537D01*
X1318917Y551495D01*
X1318542Y551329D01*
X1318667Y552412D01*
X1319792D01*
G01X1322267Y549912D02*
X1322559Y549954D01*
X1322892Y550079D01*
X1323100Y550287D01*
X1323184Y550579D01*
X1323100Y550870D01*
X1322850Y551120D01*
X1322475Y551245D01*
X1322059D01*
X1321809Y551329D01*
X1321600Y551537D01*
X1321517Y551829D01*
X1321642Y552120D01*
X1321934Y552329D01*
X1322267Y552412D01*
X1322600Y552329D01*
X1322892Y552120D01*
X1323017Y551829D01*
X1322934Y551537D01*
X1322725Y551329D01*
X1322475Y551245D01*
X1322059D01*
X1321684Y551120D01*
X1321434Y550870D01*
X1321350Y550579D01*
X1321434Y550287D01*
X1321642Y550079D01*
X1321975Y549954D01*
X1322267Y549912D01*
G01X1312134Y540912D02*
Y543412D01*
X1313175D01*
X1313509Y543287D01*
X1313717Y543120D01*
X1313800Y542787D01*
X1313717Y542454D01*
X1313467Y542245D01*
X1313175Y542120D01*
X1312134D01*
G01X1313175D02*
X1313800Y540912D01*
G01X1315275Y542995D02*
X1315525Y543245D01*
X1315817Y543370D01*
X1316150Y543412D01*
X1316567Y543329D01*
X1316859Y543120D01*
X1316942Y542870D01*
X1316900Y542620D01*
X1316734Y542412D01*
X1315900Y541995D01*
X1315525Y541704D01*
X1315275Y541287D01*
X1315192Y540912D01*
X1316942D01*
G01X1318375Y542995D02*
X1318625Y543245D01*
X1318917Y543370D01*
X1319250Y543412D01*
X1319667Y543329D01*
X1319959Y543120D01*
X1320042Y542870D01*
X1320000Y542620D01*
X1319834Y542412D01*
X1319000Y541995D01*
X1318625Y541704D01*
X1318375Y541287D01*
X1318292Y540912D01*
X1320042D01*
G01X1321350Y541412D02*
X1321600Y541120D01*
X1321934Y540954D01*
X1322309Y540912D01*
X1322642Y540954D01*
X1322975Y541162D01*
X1323184Y541412D01*
X1323225Y541662D01*
X1323142Y541954D01*
X1322850Y542162D01*
X1322559Y542245D01*
X1322184D01*
G01X1322559D02*
X1322809Y542370D01*
X1323017Y542579D01*
X1323100Y542829D01*
X1323017Y543079D01*
X1322809Y543287D01*
X1322434Y543412D01*
X1322059Y543370D01*
X1321684Y543204D01*
G01X1310584Y545412D02*
Y547912D01*
X1311625D01*
X1311959Y547787D01*
X1312167Y547620D01*
X1312250Y547287D01*
X1312167Y546954D01*
X1311917Y546745D01*
X1311625Y546620D01*
X1310584D01*
G01X1311625D02*
X1312250Y545412D01*
G01X1314434D02*
X1314517Y545954D01*
X1314642Y546412D01*
X1314809Y546829D01*
X1315017Y547287D01*
X1315350Y547912D01*
X1313684D01*
G01X1317617Y545412D02*
X1317909Y545454D01*
X1318242Y545579D01*
X1318450Y545787D01*
X1318534Y546079D01*
X1318450Y546370D01*
X1318200Y546620D01*
X1317825Y546745D01*
X1317409D01*
X1317159Y546829D01*
X1316950Y547037D01*
X1316867Y547329D01*
X1316992Y547620D01*
X1317284Y547829D01*
X1317617Y547912D01*
X1317950Y547829D01*
X1318242Y547620D01*
X1318367Y547329D01*
X1318284Y547037D01*
X1318075Y546829D01*
X1317825Y546745D01*
X1317409D01*
X1317034Y546620D01*
X1316784Y546370D01*
X1316700Y546079D01*
X1316784Y545787D01*
X1316992Y545579D01*
X1317325Y545454D01*
X1317617Y545412D01*
G01X1320009Y545704D02*
X1320300Y545495D01*
X1320634Y545412D01*
X1320967Y545495D01*
X1321259Y545745D01*
X1321467Y546120D01*
X1321550Y546495D01*
Y546954D01*
X1321467Y547329D01*
X1321259Y547662D01*
X1321009Y547829D01*
X1320717Y547912D01*
X1320384Y547829D01*
X1320134Y547662D01*
X1319967Y547412D01*
X1319884Y547079D01*
X1319967Y546787D01*
X1320175Y546495D01*
X1320425Y546329D01*
X1320717Y546287D01*
X1321050Y546370D01*
X1321300Y546579D01*
X1321550Y546954D01*
G01X1323025Y546454D02*
X1323317Y546745D01*
X1323567Y546912D01*
X1323900Y546995D01*
X1324192Y546912D01*
X1324400Y546745D01*
X1324567Y546495D01*
X1324609Y546204D01*
X1324567Y545954D01*
X1324400Y545704D01*
X1324150Y545495D01*
X1323859Y545412D01*
X1323525Y545495D01*
X1323234Y545745D01*
X1323067Y546120D01*
X1323025Y546537D01*
X1323109Y547079D01*
X1323234Y547370D01*
X1323442Y547662D01*
X1323734Y547870D01*
X1324025Y547912D01*
X1324317Y547829D01*
X1324525Y547620D01*
G01X1304708Y550767D02*
X1304583Y550517D01*
X1304500Y550225D01*
Y549892D01*
X1304625Y549517D01*
X1304833Y549225D01*
X1305083Y549017D01*
X1305500Y548850D01*
X1305875Y548808D01*
X1306250Y548892D01*
X1306500Y549017D01*
X1306750Y549267D01*
X1306917Y549558D01*
X1307000Y549850D01*
Y550142D01*
X1306917Y550433D01*
X1306792Y550683D01*
X1306625Y550892D01*
G01X1306500Y552033D02*
X1306792Y552283D01*
X1306958Y552617D01*
X1307000Y552992D01*
X1306958Y553325D01*
X1306750Y553658D01*
X1306500Y553867D01*
X1306250Y553908D01*
X1305958Y553825D01*
X1305750Y553533D01*
X1305667Y553242D01*
Y552867D01*
G01Y553242D02*
X1305542Y553492D01*
X1305333Y553700D01*
X1305083Y553783D01*
X1304833Y553700D01*
X1304625Y553492D01*
X1304500Y553117D01*
X1304542Y552742D01*
X1304708Y552367D01*
G01X1307000Y556050D02*
X1304500D01*
X1305000Y555550D01*
G01X1307000D02*
Y556550D01*
G01Y559067D02*
X1306458Y559150D01*
X1306000Y559275D01*
X1305583Y559442D01*
X1305125Y559650D01*
X1304500Y559983D01*
Y558317D01*
G01X1310917Y561912D02*
Y557912D01*
X1318317D01*
G01X1310917Y566412D02*
Y562412D01*
X1318317D01*
G01X1310667Y554000D02*
Y556500D01*
X1311708D01*
X1312042Y556375D01*
X1312250Y556208D01*
X1312333Y555875D01*
X1312250Y555542D01*
X1312000Y555333D01*
X1311708Y555208D01*
X1310667D01*
G01X1311708D02*
X1312333Y554000D01*
G01X1314517D02*
X1314600Y554542D01*
X1314725Y555000D01*
X1314892Y555417D01*
X1315100Y555875D01*
X1315433Y556500D01*
X1313767D01*
G01X1317700Y554000D02*
X1317992Y554042D01*
X1318325Y554167D01*
X1318533Y554375D01*
X1318617Y554667D01*
X1318533Y554958D01*
X1318283Y555208D01*
X1317908Y555333D01*
X1317492D01*
X1317242Y555417D01*
X1317033Y555625D01*
X1316950Y555917D01*
X1317075Y556208D01*
X1317367Y556417D01*
X1317700Y556500D01*
X1318033Y556417D01*
X1318325Y556208D01*
X1318450Y555917D01*
X1318367Y555625D01*
X1318158Y555417D01*
X1317908Y555333D01*
X1317492D01*
X1317117Y555208D01*
X1316867Y554958D01*
X1316783Y554667D01*
X1316867Y554375D01*
X1317075Y554167D01*
X1317408Y554042D01*
X1317700Y554000D01*
G01X1320092Y554292D02*
X1320383Y554083D01*
X1320717Y554000D01*
X1321050Y554083D01*
X1321342Y554333D01*
X1321550Y554708D01*
X1321633Y555083D01*
Y555542D01*
X1321550Y555917D01*
X1321342Y556250D01*
X1321092Y556417D01*
X1320800Y556500D01*
X1320467Y556417D01*
X1320217Y556250D01*
X1320050Y556000D01*
X1319967Y555667D01*
X1320050Y555375D01*
X1320258Y555083D01*
X1320508Y554917D01*
X1320800Y554875D01*
X1321133Y554958D01*
X1321383Y555167D01*
X1321633Y555542D01*
G01X1323817Y554000D02*
X1323900Y554542D01*
X1324025Y555000D01*
X1324192Y555417D01*
X1324400Y555875D01*
X1324733Y556500D01*
X1323067D01*
G01X1310917Y570912D02*
Y566912D01*
X1318317D01*
G01X1310917Y583912D02*
Y579912D01*
X1318317D01*
G01X1311000Y575000D02*
Y571000D01*
X1318400D01*
G01X1310917Y592912D02*
Y588912D01*
X1318317D01*
G01Y584412D02*
Y588412D01*
X1310917D01*
G01X1318317Y593412D02*
Y597412D01*
X1310917D01*
G01X1318317Y610412D02*
Y614412D01*
X1310917D01*
G01X1318317Y597912D02*
Y601912D01*
X1310917D01*
G01Y609912D02*
Y605912D01*
X1318317D01*
G01X1310917Y623412D02*
Y619412D01*
X1318317D01*
G01X1310917Y618912D02*
Y614912D01*
X1318317D01*
G01X1308000Y657017D02*
X1305500D01*
Y658058D01*
X1305625Y658392D01*
X1305792Y658600D01*
X1306125Y658683D01*
X1306458Y658600D01*
X1306667Y658350D01*
X1306792Y658058D01*
Y657017D01*
G01Y658058D02*
X1308000Y658683D01*
G01X1305917Y660158D02*
X1305667Y660408D01*
X1305542Y660700D01*
X1305500Y661033D01*
X1305583Y661450D01*
X1305792Y661742D01*
X1306042Y661825D01*
X1306292Y661783D01*
X1306500Y661617D01*
X1306917Y660783D01*
X1307208Y660408D01*
X1307625Y660158D01*
X1308000Y660075D01*
Y661825D01*
G01Y663967D02*
X1307458Y664050D01*
X1307000Y664175D01*
X1306583Y664342D01*
X1306125Y664550D01*
X1305500Y664883D01*
Y663217D01*
G01X1308000Y667650D02*
X1305500D01*
X1307292Y666108D01*
Y668192D01*
G01X1316000Y657017D02*
X1313500D01*
Y658058D01*
X1313625Y658392D01*
X1313792Y658600D01*
X1314125Y658683D01*
X1314458Y658600D01*
X1314667Y658350D01*
X1314792Y658058D01*
Y657017D01*
G01Y658058D02*
X1316000Y658683D01*
G01X1315500Y660033D02*
X1315792Y660283D01*
X1315958Y660617D01*
X1316000Y660992D01*
X1315958Y661325D01*
X1315750Y661658D01*
X1315500Y661867D01*
X1315250Y661908D01*
X1314958Y661825D01*
X1314750Y661533D01*
X1314667Y661242D01*
Y660867D01*
G01Y661242D02*
X1314542Y661492D01*
X1314333Y661700D01*
X1314083Y661783D01*
X1313833Y661700D01*
X1313625Y661492D01*
X1313500Y661117D01*
X1313542Y660742D01*
X1313708Y660367D01*
G01X1316000Y664050D02*
X1313500D01*
X1314000Y663550D01*
G01X1316000D02*
Y664550D01*
G01X1313917Y666358D02*
X1313667Y666608D01*
X1313542Y666900D01*
X1313500Y667233D01*
X1313583Y667650D01*
X1313792Y667942D01*
X1314042Y668025D01*
X1314292Y667983D01*
X1314500Y667817D01*
X1314917Y666983D01*
X1315208Y666608D01*
X1315625Y666358D01*
X1316000Y666275D01*
Y668025D01*
G01X1312000Y657017D02*
X1309500D01*
Y658058D01*
X1309625Y658392D01*
X1309792Y658600D01*
X1310125Y658683D01*
X1310458Y658600D01*
X1310667Y658350D01*
X1310792Y658058D01*
Y657017D01*
G01Y658058D02*
X1312000Y658683D01*
G01X1311500Y660033D02*
X1311792Y660283D01*
X1311958Y660617D01*
X1312000Y660992D01*
X1311958Y661325D01*
X1311750Y661658D01*
X1311500Y661867D01*
X1311250Y661908D01*
X1310958Y661825D01*
X1310750Y661533D01*
X1310667Y661242D01*
Y660867D01*
G01Y661242D02*
X1310542Y661492D01*
X1310333Y661700D01*
X1310083Y661783D01*
X1309833Y661700D01*
X1309625Y661492D01*
X1309500Y661117D01*
X1309542Y660742D01*
X1309708Y660367D01*
G01X1309917Y663258D02*
X1309667Y663508D01*
X1309542Y663800D01*
X1309500Y664133D01*
X1309583Y664550D01*
X1309792Y664842D01*
X1310042Y664925D01*
X1310292Y664883D01*
X1310500Y664717D01*
X1310917Y663883D01*
X1311208Y663508D01*
X1311625Y663258D01*
X1312000Y663175D01*
Y664925D01*
G01X1311500Y666233D02*
X1311792Y666483D01*
X1311958Y666817D01*
X1312000Y667192D01*
X1311958Y667525D01*
X1311750Y667858D01*
X1311500Y668067D01*
X1311250Y668108D01*
X1310958Y668025D01*
X1310750Y667733D01*
X1310667Y667442D01*
Y667067D01*
G01Y667442D02*
X1310542Y667692D01*
X1310333Y667900D01*
X1310083Y667983D01*
X1309833Y667900D01*
X1309625Y667692D01*
X1309500Y667317D01*
X1309542Y666942D01*
X1309708Y666567D01*
G01X1301784Y773332D02*
X1305784D01*
Y780732D01*
G01X1306784Y773332D02*
X1310784D01*
Y780732D01*
G01X1311784Y773332D02*
X1315784D01*
Y780732D01*
G01X1305784Y791232D02*
X1301784D01*
Y783832D01*
G01X1310784Y791232D02*
X1306784D01*
Y783832D01*
G01X1316284Y791232D02*
X1312284D01*
Y783832D01*
G01X1300584Y813032D02*
X1302684Y811232D01*
X1300584Y809032D01*
G01X1300484Y805432D02*
X1319684D01*
Y816632D01*
X1300484D01*
Y805432D01*
X1300884D01*
G01X1310500Y828800D02*
X1314500D01*
Y836200D01*
G01Y828800D02*
X1318500D01*
Y836200D01*
G01X1306500Y828800D02*
X1310500D01*
Y836200D01*
G01X1302500Y828800D02*
X1306500D01*
Y836200D01*
G01X1314500Y859450D02*
X1310500D01*
Y852050D01*
G01X1315368Y886784D02*
Y878784D01*
X1302968D01*
Y886784D01*
X1315368D01*
G01X1313668Y882784D02*
X1315168Y881284D01*
G01X1313668Y882784D02*
X1315168Y884284D01*
G01X1308468Y921801D02*
X1305968D01*
Y922842D01*
X1306093Y923176D01*
X1306260Y923384D01*
X1306593Y923467D01*
X1306926Y923384D01*
X1307135Y923134D01*
X1307260Y922842D01*
Y921801D01*
G01Y922842D02*
X1308468Y923467D01*
G01Y925734D02*
X1305968D01*
X1306468Y925234D01*
G01X1308468D02*
Y926234D01*
G01Y928751D02*
X1307926Y928834D01*
X1307468Y928959D01*
X1307051Y929126D01*
X1306593Y929334D01*
X1305968Y929667D01*
Y928001D01*
G01X1308176Y931226D02*
X1308385Y931517D01*
X1308468Y931851D01*
X1308385Y932184D01*
X1308135Y932476D01*
X1307760Y932684D01*
X1307385Y932767D01*
X1306926D01*
X1306551Y932684D01*
X1306218Y932476D01*
X1306051Y932226D01*
X1305968Y931934D01*
X1306051Y931601D01*
X1306218Y931351D01*
X1306468Y931184D01*
X1306801Y931101D01*
X1307093Y931184D01*
X1307385Y931392D01*
X1307551Y931642D01*
X1307593Y931934D01*
X1307510Y932267D01*
X1307301Y932517D01*
X1306926Y932767D01*
G01X1309468Y918984D02*
X1305468D01*
Y911584D01*
G01X1303000Y922017D02*
X1300500D01*
Y923058D01*
X1300625Y923392D01*
X1300792Y923600D01*
X1301125Y923683D01*
X1301458Y923600D01*
X1301667Y923350D01*
X1301792Y923058D01*
Y922017D01*
G01Y923058D02*
X1303000Y923683D01*
G01Y925950D02*
X1300500D01*
X1301000Y925450D01*
G01X1303000D02*
Y926450D01*
G01Y929050D02*
X1302958Y929342D01*
X1302833Y929675D01*
X1302625Y929883D01*
X1302333Y929967D01*
X1302042Y929883D01*
X1301792Y929633D01*
X1301667Y929258D01*
Y928842D01*
X1301583Y928592D01*
X1301375Y928383D01*
X1301083Y928300D01*
X1300792Y928425D01*
X1300583Y928717D01*
X1300500Y929050D01*
X1300583Y929383D01*
X1300792Y929675D01*
X1301083Y929800D01*
X1301375Y929717D01*
X1301583Y929508D01*
X1301667Y929258D01*
Y928842D01*
X1301792Y928467D01*
X1302042Y928217D01*
X1302333Y928133D01*
X1302625Y928217D01*
X1302833Y928425D01*
X1302958Y928758D01*
X1303000Y929050D01*
G01X1300500Y932150D02*
X1300583Y931817D01*
X1300792Y931567D01*
X1301042Y931400D01*
X1301375Y931275D01*
X1301750Y931233D01*
X1302125Y931275D01*
X1302458Y931400D01*
X1302708Y931567D01*
X1302917Y931817D01*
X1303000Y932150D01*
X1302917Y932483D01*
X1302708Y932733D01*
X1302458Y932900D01*
X1302125Y933025D01*
X1301750Y933067D01*
X1301375Y933025D01*
X1301042Y932900D01*
X1300792Y932733D01*
X1300583Y932483D01*
X1300500Y932150D01*
G01X1303968Y918984D02*
X1299968D01*
Y911584D01*
G01X1313468Y921801D02*
X1310968D01*
Y922842D01*
X1311093Y923176D01*
X1311260Y923384D01*
X1311593Y923467D01*
X1311926Y923384D01*
X1312135Y923134D01*
X1312260Y922842D01*
Y921801D01*
G01Y922842D02*
X1313468Y923467D01*
G01Y925734D02*
X1310968D01*
X1311468Y925234D01*
G01X1313468D02*
Y926234D01*
G01Y928834D02*
X1313426Y929126D01*
X1313301Y929459D01*
X1313093Y929667D01*
X1312801Y929751D01*
X1312510Y929667D01*
X1312260Y929417D01*
X1312135Y929042D01*
Y928626D01*
X1312051Y928376D01*
X1311843Y928167D01*
X1311551Y928084D01*
X1311260Y928209D01*
X1311051Y928501D01*
X1310968Y928834D01*
X1311051Y929167D01*
X1311260Y929459D01*
X1311551Y929584D01*
X1311843Y929501D01*
X1312051Y929292D01*
X1312135Y929042D01*
Y928626D01*
X1312260Y928251D01*
X1312510Y928001D01*
X1312801Y927917D01*
X1313093Y928001D01*
X1313301Y928209D01*
X1313426Y928542D01*
X1313468Y928834D01*
G01X1313093Y931017D02*
X1313301Y931267D01*
X1313426Y931559D01*
X1313468Y931934D01*
X1313385Y932309D01*
X1313218Y932601D01*
X1312926Y932809D01*
X1312593Y932851D01*
X1312260Y932767D01*
X1312051Y932559D01*
X1311885Y932267D01*
X1311843Y931976D01*
X1311885Y931684D01*
X1312051Y931309D01*
X1310968Y931434D01*
Y932559D01*
G01X1314468Y918984D02*
X1310468D01*
Y911584D01*
G01X1389246Y32991D02*
Y22691D01*
X1395946D01*
Y-4509D01*
X1328346D01*
Y22691D01*
X1335046D01*
Y32991D01*
X1389246D01*
G01X1317950Y22650D02*
X1324050D01*
G01X1317950Y11350D02*
Y22650D01*
G01X1324050Y11350D02*
X1317950D01*
G01X1324050Y22650D02*
Y11350D01*
G01X1315550Y22650D02*
Y11350D01*
G01X1329708Y27317D02*
X1329583Y27067D01*
X1329500Y26775D01*
Y26442D01*
X1329625Y26067D01*
X1329833Y25775D01*
X1330083Y25567D01*
X1330500Y25400D01*
X1330875Y25358D01*
X1331250Y25442D01*
X1331500Y25567D01*
X1331750Y25817D01*
X1331917Y26108D01*
X1332000Y26400D01*
Y26692D01*
X1331917Y26983D01*
X1331792Y27233D01*
X1331625Y27442D01*
G01X1332000Y28542D02*
X1329500D01*
X1332000Y30458D01*
X1329500D01*
G01X1331500Y31683D02*
X1331792Y31933D01*
X1331958Y32267D01*
X1332000Y32642D01*
X1331958Y32975D01*
X1331750Y33308D01*
X1331500Y33517D01*
X1331250Y33558D01*
X1330958Y33475D01*
X1330750Y33183D01*
X1330667Y32892D01*
Y32517D01*
G01Y32892D02*
X1330542Y33142D01*
X1330333Y33350D01*
X1330083Y33433D01*
X1329833Y33350D01*
X1329625Y33142D01*
X1329500Y32767D01*
X1329542Y32392D01*
X1329708Y32017D01*
G01X1324500Y37067D02*
X1322000D01*
Y38108D01*
X1322125Y38442D01*
X1322292Y38650D01*
X1322625Y38733D01*
X1322958Y38650D01*
X1323167Y38400D01*
X1323292Y38108D01*
Y37067D01*
G01Y38108D02*
X1324500Y38733D01*
G01Y41000D02*
X1324458Y41292D01*
X1324333Y41625D01*
X1324125Y41833D01*
X1323833Y41917D01*
X1323542Y41833D01*
X1323292Y41583D01*
X1323167Y41208D01*
Y40792D01*
X1323083Y40542D01*
X1322875Y40333D01*
X1322583Y40250D01*
X1322292Y40375D01*
X1322083Y40667D01*
X1322000Y41000D01*
X1322083Y41333D01*
X1322292Y41625D01*
X1322583Y41750D01*
X1322875Y41667D01*
X1323083Y41458D01*
X1323167Y41208D01*
Y40792D01*
X1323292Y40417D01*
X1323542Y40167D01*
X1323833Y40083D01*
X1324125Y40167D01*
X1324333Y40375D01*
X1324458Y40708D01*
X1324500Y41000D01*
G01X1324125Y43183D02*
X1324333Y43433D01*
X1324458Y43725D01*
X1324500Y44100D01*
X1324417Y44475D01*
X1324250Y44767D01*
X1323958Y44975D01*
X1323625Y45017D01*
X1323292Y44933D01*
X1323083Y44725D01*
X1322917Y44433D01*
X1322875Y44142D01*
X1322917Y43850D01*
X1323083Y43475D01*
X1322000Y43600D01*
Y44725D01*
G01X1329000Y37067D02*
X1326500D01*
Y38108D01*
X1326625Y38442D01*
X1326792Y38650D01*
X1327125Y38733D01*
X1327458Y38650D01*
X1327667Y38400D01*
X1327792Y38108D01*
Y37067D01*
G01Y38108D02*
X1329000Y38733D01*
G01Y41000D02*
X1328958Y41292D01*
X1328833Y41625D01*
X1328625Y41833D01*
X1328333Y41917D01*
X1328042Y41833D01*
X1327792Y41583D01*
X1327667Y41208D01*
Y40792D01*
X1327583Y40542D01*
X1327375Y40333D01*
X1327083Y40250D01*
X1326792Y40375D01*
X1326583Y40667D01*
X1326500Y41000D01*
X1326583Y41333D01*
X1326792Y41625D01*
X1327083Y41750D01*
X1327375Y41667D01*
X1327583Y41458D01*
X1327667Y41208D01*
Y40792D01*
X1327792Y40417D01*
X1328042Y40167D01*
X1328333Y40083D01*
X1328625Y40167D01*
X1328833Y40375D01*
X1328958Y40708D01*
X1329000Y41000D01*
G01X1327958Y43308D02*
X1327667Y43600D01*
X1327500Y43850D01*
X1327417Y44183D01*
X1327500Y44475D01*
X1327667Y44683D01*
X1327917Y44850D01*
X1328208Y44892D01*
X1328458Y44850D01*
X1328708Y44683D01*
X1328917Y44433D01*
X1329000Y44142D01*
X1328917Y43808D01*
X1328667Y43517D01*
X1328292Y43350D01*
X1327875Y43308D01*
X1327333Y43392D01*
X1327042Y43517D01*
X1326750Y43725D01*
X1326542Y44017D01*
X1326500Y44308D01*
X1326583Y44600D01*
X1326792Y44808D01*
G01X1326600Y58400D02*
Y47600D01*
X1321400D01*
Y58400D01*
X1326600D01*
G01X1315510Y48237D02*
Y61237D01*
G01X1334500Y56200D02*
X1330500D01*
Y48800D01*
G01X1325000Y74967D02*
X1322500D01*
Y76008D01*
X1322625Y76342D01*
X1322792Y76550D01*
X1323125Y76633D01*
X1323458Y76550D01*
X1323667Y76300D01*
X1323792Y76008D01*
Y74967D01*
G01Y76008D02*
X1325000Y76633D01*
G01Y78900D02*
X1322500D01*
X1323000Y78400D01*
G01X1325000D02*
Y79400D01*
G01X1324625Y81083D02*
X1324833Y81333D01*
X1324958Y81625D01*
X1325000Y82000D01*
X1324917Y82375D01*
X1324750Y82667D01*
X1324458Y82875D01*
X1324125Y82917D01*
X1323792Y82833D01*
X1323583Y82625D01*
X1323417Y82333D01*
X1323375Y82042D01*
X1323417Y81750D01*
X1323583Y81375D01*
X1322500Y81500D01*
Y82625D01*
G01X1325000Y85100D02*
X1324958Y85392D01*
X1324833Y85725D01*
X1324625Y85933D01*
X1324333Y86017D01*
X1324042Y85933D01*
X1323792Y85683D01*
X1323667Y85308D01*
Y84892D01*
X1323583Y84642D01*
X1323375Y84433D01*
X1323083Y84350D01*
X1322792Y84475D01*
X1322583Y84767D01*
X1322500Y85100D01*
X1322583Y85433D01*
X1322792Y85725D01*
X1323083Y85850D01*
X1323375Y85767D01*
X1323583Y85558D01*
X1323667Y85308D01*
Y84892D01*
X1323792Y84517D01*
X1324042Y84267D01*
X1324333Y84183D01*
X1324625Y84267D01*
X1324833Y84475D01*
X1324958Y84808D01*
X1325000Y85100D01*
G01X1322917Y87408D02*
X1322667Y87658D01*
X1322542Y87950D01*
X1322500Y88283D01*
X1322583Y88700D01*
X1322792Y88992D01*
X1323042Y89075D01*
X1323292Y89033D01*
X1323500Y88867D01*
X1323917Y88033D01*
X1324208Y87658D01*
X1324625Y87408D01*
X1325000Y87325D01*
Y89075D01*
G01X1327208Y76767D02*
X1327083Y76517D01*
X1327000Y76225D01*
Y75892D01*
X1327125Y75517D01*
X1327333Y75225D01*
X1327583Y75017D01*
X1328000Y74850D01*
X1328375Y74808D01*
X1328750Y74892D01*
X1329000Y75017D01*
X1329250Y75267D01*
X1329417Y75558D01*
X1329500Y75850D01*
Y76142D01*
X1329417Y76433D01*
X1329292Y76683D01*
X1329125Y76892D01*
G01X1327417Y78158D02*
X1327167Y78408D01*
X1327042Y78700D01*
X1327000Y79033D01*
X1327083Y79450D01*
X1327292Y79742D01*
X1327542Y79825D01*
X1327792Y79783D01*
X1328000Y79617D01*
X1328417Y78783D01*
X1328708Y78408D01*
X1329125Y78158D01*
X1329500Y78075D01*
Y79825D01*
G01X1329125Y81133D02*
X1329333Y81383D01*
X1329458Y81675D01*
X1329500Y82050D01*
X1329417Y82425D01*
X1329250Y82717D01*
X1328958Y82925D01*
X1328625Y82967D01*
X1328292Y82883D01*
X1328083Y82675D01*
X1327917Y82383D01*
X1327875Y82092D01*
X1327917Y81800D01*
X1328083Y81425D01*
X1327000Y81550D01*
Y82675D01*
G01X1329125Y84233D02*
X1329333Y84483D01*
X1329458Y84775D01*
X1329500Y85150D01*
X1329417Y85525D01*
X1329250Y85817D01*
X1328958Y86025D01*
X1328625Y86067D01*
X1328292Y85983D01*
X1328083Y85775D01*
X1327917Y85483D01*
X1327875Y85192D01*
X1327917Y84900D01*
X1328083Y84525D01*
X1327000Y84650D01*
Y85775D01*
G01X1319975Y264333D02*
X1320308Y264125D01*
X1320683Y264000D01*
X1321017D01*
X1321350Y264125D01*
X1321600Y264333D01*
X1321725Y264625D01*
X1321642Y264917D01*
X1321433Y265167D01*
X1321058Y265333D01*
X1320558Y265417D01*
X1320267Y265583D01*
X1320142Y265875D01*
X1320225Y266167D01*
X1320433Y266375D01*
X1320725Y266500D01*
X1321017D01*
X1321308Y266417D01*
X1321558Y266208D01*
G01X1323033Y264000D02*
Y266500D01*
G01X1324617D02*
X1323033Y264958D01*
G01X1324867Y264000D02*
X1323742Y265667D01*
G01X1327050Y266500D02*
Y264000D01*
G01X1326092Y266500D02*
X1328008D01*
G01X1329233Y264500D02*
X1329483Y264208D01*
X1329817Y264042D01*
X1330192Y264000D01*
X1330525Y264042D01*
X1330858Y264250D01*
X1331067Y264500D01*
X1331108Y264750D01*
X1331025Y265042D01*
X1330733Y265250D01*
X1330442Y265333D01*
X1330067D01*
G01X1330442D02*
X1330692Y265458D01*
X1330900Y265667D01*
X1330983Y265917D01*
X1330900Y266167D01*
X1330692Y266375D01*
X1330317Y266500D01*
X1329942Y266458D01*
X1329567Y266292D01*
G01X1320983Y272000D02*
Y270208D01*
X1321150Y269833D01*
X1321483Y269583D01*
X1321900Y269500D01*
X1322317Y269583D01*
X1322650Y269833D01*
X1322817Y270208D01*
Y272000D01*
G01X1325000Y269500D02*
Y272000D01*
X1324500Y271500D01*
G01Y269500D02*
X1325500D01*
G01X1327392Y269792D02*
X1327683Y269583D01*
X1328017Y269500D01*
X1328350Y269583D01*
X1328642Y269833D01*
X1328850Y270208D01*
X1328933Y270583D01*
Y271042D01*
X1328850Y271417D01*
X1328642Y271750D01*
X1328392Y271917D01*
X1328100Y272000D01*
X1327767Y271917D01*
X1327517Y271750D01*
X1327350Y271500D01*
X1327267Y271167D01*
X1327350Y270875D01*
X1327558Y270583D01*
X1327808Y270417D01*
X1328100Y270375D01*
X1328433Y270458D01*
X1328683Y270667D01*
X1328933Y271042D01*
G01X1321017Y285000D02*
Y287500D01*
X1322058D01*
X1322392Y287375D01*
X1322600Y287208D01*
X1322683Y286875D01*
X1322600Y286542D01*
X1322350Y286333D01*
X1322058Y286208D01*
X1321017D01*
G01X1322058D02*
X1322683Y285000D01*
G01X1324158Y286042D02*
X1324450Y286333D01*
X1324700Y286500D01*
X1325033Y286583D01*
X1325325Y286500D01*
X1325533Y286333D01*
X1325700Y286083D01*
X1325742Y285792D01*
X1325700Y285542D01*
X1325533Y285292D01*
X1325283Y285083D01*
X1324992Y285000D01*
X1324658Y285083D01*
X1324367Y285333D01*
X1324200Y285708D01*
X1324158Y286125D01*
X1324242Y286667D01*
X1324367Y286958D01*
X1324575Y287250D01*
X1324867Y287458D01*
X1325158Y287500D01*
X1325450Y287417D01*
X1325658Y287208D01*
G01X1328050Y285000D02*
X1328342Y285042D01*
X1328675Y285167D01*
X1328883Y285375D01*
X1328967Y285667D01*
X1328883Y285958D01*
X1328633Y286208D01*
X1328258Y286333D01*
X1327842D01*
X1327592Y286417D01*
X1327383Y286625D01*
X1327300Y286917D01*
X1327425Y287208D01*
X1327717Y287417D01*
X1328050Y287500D01*
X1328383Y287417D01*
X1328675Y287208D01*
X1328800Y286917D01*
X1328717Y286625D01*
X1328508Y286417D01*
X1328258Y286333D01*
X1327842D01*
X1327467Y286208D01*
X1327217Y285958D01*
X1327133Y285667D01*
X1327217Y285375D01*
X1327425Y285167D01*
X1327758Y285042D01*
X1328050Y285000D01*
G01X1331150Y287500D02*
X1330817Y287417D01*
X1330567Y287208D01*
X1330400Y286958D01*
X1330275Y286625D01*
X1330233Y286250D01*
X1330275Y285875D01*
X1330400Y285542D01*
X1330567Y285292D01*
X1330817Y285083D01*
X1331150Y285000D01*
X1331483Y285083D01*
X1331733Y285292D01*
X1331900Y285542D01*
X1332025Y285875D01*
X1332067Y286250D01*
X1332025Y286625D01*
X1331900Y286958D01*
X1331733Y287208D01*
X1331483Y287417D01*
X1331150Y287500D01*
G01X1321017Y280000D02*
Y282500D01*
X1322058D01*
X1322392Y282375D01*
X1322600Y282208D01*
X1322683Y281875D01*
X1322600Y281542D01*
X1322350Y281333D01*
X1322058Y281208D01*
X1321017D01*
G01X1322058D02*
X1322683Y280000D01*
G01X1324158Y281042D02*
X1324450Y281333D01*
X1324700Y281500D01*
X1325033Y281583D01*
X1325325Y281500D01*
X1325533Y281333D01*
X1325700Y281083D01*
X1325742Y280792D01*
X1325700Y280542D01*
X1325533Y280292D01*
X1325283Y280083D01*
X1324992Y280000D01*
X1324658Y280083D01*
X1324367Y280333D01*
X1324200Y280708D01*
X1324158Y281125D01*
X1324242Y281667D01*
X1324367Y281958D01*
X1324575Y282250D01*
X1324867Y282458D01*
X1325158Y282500D01*
X1325450Y282417D01*
X1325658Y282208D01*
G01X1328050Y280000D02*
X1328342Y280042D01*
X1328675Y280167D01*
X1328883Y280375D01*
X1328967Y280667D01*
X1328883Y280958D01*
X1328633Y281208D01*
X1328258Y281333D01*
X1327842D01*
X1327592Y281417D01*
X1327383Y281625D01*
X1327300Y281917D01*
X1327425Y282208D01*
X1327717Y282417D01*
X1328050Y282500D01*
X1328383Y282417D01*
X1328675Y282208D01*
X1328800Y281917D01*
X1328717Y281625D01*
X1328508Y281417D01*
X1328258Y281333D01*
X1327842D01*
X1327467Y281208D01*
X1327217Y280958D01*
X1327133Y280667D01*
X1327217Y280375D01*
X1327425Y280167D01*
X1327758Y280042D01*
X1328050Y280000D01*
G01X1331150D02*
Y282500D01*
X1330650Y282000D01*
G01Y280000D02*
X1331650D01*
G01X1332700Y296000D02*
Y300000D01*
X1325300D01*
G01X1332700Y291000D02*
Y295000D01*
X1325300D01*
G01X1328708Y306767D02*
X1328583Y306517D01*
X1328500Y306225D01*
Y305892D01*
X1328625Y305517D01*
X1328833Y305225D01*
X1329083Y305017D01*
X1329500Y304850D01*
X1329875Y304808D01*
X1330250Y304892D01*
X1330500Y305017D01*
X1330750Y305267D01*
X1330917Y305558D01*
X1331000Y305850D01*
Y306142D01*
X1330917Y306433D01*
X1330792Y306683D01*
X1330625Y306892D01*
G01X1330500Y308033D02*
X1330792Y308283D01*
X1330958Y308617D01*
X1331000Y308992D01*
X1330958Y309325D01*
X1330750Y309658D01*
X1330500Y309867D01*
X1330250Y309908D01*
X1329958Y309825D01*
X1329750Y309533D01*
X1329667Y309242D01*
Y308867D01*
G01Y309242D02*
X1329542Y309492D01*
X1329333Y309700D01*
X1329083Y309783D01*
X1328833Y309700D01*
X1328625Y309492D01*
X1328500Y309117D01*
X1328542Y308742D01*
X1328708Y308367D01*
G01X1330500Y311133D02*
X1330792Y311383D01*
X1330958Y311717D01*
X1331000Y312092D01*
X1330958Y312425D01*
X1330750Y312758D01*
X1330500Y312967D01*
X1330250Y313008D01*
X1329958Y312925D01*
X1329750Y312633D01*
X1329667Y312342D01*
Y311967D01*
G01Y312342D02*
X1329542Y312592D01*
X1329333Y312800D01*
X1329083Y312883D01*
X1328833Y312800D01*
X1328625Y312592D01*
X1328500Y312217D01*
X1328542Y311842D01*
X1328708Y311467D01*
G01X1330500Y314233D02*
X1330792Y314483D01*
X1330958Y314817D01*
X1331000Y315192D01*
X1330958Y315525D01*
X1330750Y315858D01*
X1330500Y316067D01*
X1330250Y316108D01*
X1329958Y316025D01*
X1329750Y315733D01*
X1329667Y315442D01*
Y315067D01*
G01Y315442D02*
X1329542Y315692D01*
X1329333Y315900D01*
X1329083Y315983D01*
X1328833Y315900D01*
X1328625Y315692D01*
X1328500Y315317D01*
X1328542Y314942D01*
X1328708Y314567D01*
G01X1315000Y326800D02*
X1319000D01*
Y334200D01*
G01X1320500Y326800D02*
X1324500D01*
Y334200D01*
G01X1329000D02*
X1325000D01*
Y326800D01*
G01X1319500Y336517D02*
X1317000D01*
Y337558D01*
X1317125Y337892D01*
X1317292Y338100D01*
X1317625Y338183D01*
X1317958Y338100D01*
X1318167Y337850D01*
X1318292Y337558D01*
Y336517D01*
G01Y337558D02*
X1319500Y338183D01*
G01X1317417Y339658D02*
X1317167Y339908D01*
X1317042Y340200D01*
X1317000Y340533D01*
X1317083Y340950D01*
X1317292Y341242D01*
X1317542Y341325D01*
X1317792Y341283D01*
X1318000Y341117D01*
X1318417Y340283D01*
X1318708Y339908D01*
X1319125Y339658D01*
X1319500Y339575D01*
Y341325D01*
G01X1319208Y342842D02*
X1319417Y343133D01*
X1319500Y343467D01*
X1319417Y343800D01*
X1319167Y344092D01*
X1318792Y344300D01*
X1318417Y344383D01*
X1317958D01*
X1317583Y344300D01*
X1317250Y344092D01*
X1317083Y343842D01*
X1317000Y343550D01*
X1317083Y343217D01*
X1317250Y342967D01*
X1317500Y342800D01*
X1317833Y342717D01*
X1318125Y342800D01*
X1318417Y343008D01*
X1318583Y343258D01*
X1318625Y343550D01*
X1318542Y343883D01*
X1318333Y344133D01*
X1317958Y344383D01*
G01X1319500Y347150D02*
X1317000D01*
X1318792Y345608D01*
Y347692D01*
G01X1323500Y336517D02*
X1321000D01*
Y337558D01*
X1321125Y337892D01*
X1321292Y338100D01*
X1321625Y338183D01*
X1321958Y338100D01*
X1322167Y337850D01*
X1322292Y337558D01*
Y336517D01*
G01Y337558D02*
X1323500Y338183D01*
G01X1321417Y339658D02*
X1321167Y339908D01*
X1321042Y340200D01*
X1321000Y340533D01*
X1321083Y340950D01*
X1321292Y341242D01*
X1321542Y341325D01*
X1321792Y341283D01*
X1322000Y341117D01*
X1322417Y340283D01*
X1322708Y339908D01*
X1323125Y339658D01*
X1323500Y339575D01*
Y341325D01*
G01X1323208Y342842D02*
X1323417Y343133D01*
X1323500Y343467D01*
X1323417Y343800D01*
X1323167Y344092D01*
X1322792Y344300D01*
X1322417Y344383D01*
X1321958D01*
X1321583Y344300D01*
X1321250Y344092D01*
X1321083Y343842D01*
X1321000Y343550D01*
X1321083Y343217D01*
X1321250Y342967D01*
X1321500Y342800D01*
X1321833Y342717D01*
X1322125Y342800D01*
X1322417Y343008D01*
X1322583Y343258D01*
X1322625Y343550D01*
X1322542Y343883D01*
X1322333Y344133D01*
X1321958Y344383D01*
G01X1322458Y345858D02*
X1322167Y346150D01*
X1322000Y346400D01*
X1321917Y346733D01*
X1322000Y347025D01*
X1322167Y347233D01*
X1322417Y347400D01*
X1322708Y347442D01*
X1322958Y347400D01*
X1323208Y347233D01*
X1323417Y346983D01*
X1323500Y346692D01*
X1323417Y346358D01*
X1323167Y346067D01*
X1322792Y345900D01*
X1322375Y345858D01*
X1321833Y345942D01*
X1321542Y346067D01*
X1321250Y346275D01*
X1321042Y346567D01*
X1321000Y346858D01*
X1321083Y347150D01*
X1321292Y347358D01*
G01X1328000Y336517D02*
X1325500D01*
Y337558D01*
X1325625Y337892D01*
X1325792Y338100D01*
X1326125Y338183D01*
X1326458Y338100D01*
X1326667Y337850D01*
X1326792Y337558D01*
Y336517D01*
G01Y337558D02*
X1328000Y338183D01*
G01X1325917Y339658D02*
X1325667Y339908D01*
X1325542Y340200D01*
X1325500Y340533D01*
X1325583Y340950D01*
X1325792Y341242D01*
X1326042Y341325D01*
X1326292Y341283D01*
X1326500Y341117D01*
X1326917Y340283D01*
X1327208Y339908D01*
X1327625Y339658D01*
X1328000Y339575D01*
Y341325D01*
G01X1326958Y342758D02*
X1326667Y343050D01*
X1326500Y343300D01*
X1326417Y343633D01*
X1326500Y343925D01*
X1326667Y344133D01*
X1326917Y344300D01*
X1327208Y344342D01*
X1327458Y344300D01*
X1327708Y344133D01*
X1327917Y343883D01*
X1328000Y343592D01*
X1327917Y343258D01*
X1327667Y342967D01*
X1327292Y342800D01*
X1326875Y342758D01*
X1326333Y342842D01*
X1326042Y342967D01*
X1325750Y343175D01*
X1325542Y343467D01*
X1325500Y343758D01*
X1325583Y344050D01*
X1325792Y344258D01*
G01X1328000Y347150D02*
X1325500D01*
X1327292Y345608D01*
Y347692D01*
G01X1318517Y367000D02*
Y369500D01*
X1319517D01*
X1319850Y369375D01*
X1320100Y369083D01*
X1320183Y368750D01*
X1320100Y368417D01*
X1319892Y368167D01*
X1319517Y368042D01*
X1318517D01*
G01X1323367Y369292D02*
X1323117Y369417D01*
X1322825Y369500D01*
X1322492D01*
X1322117Y369375D01*
X1321825Y369167D01*
X1321617Y368917D01*
X1321450Y368500D01*
X1321408Y368125D01*
X1321492Y367750D01*
X1321617Y367500D01*
X1321867Y367250D01*
X1322158Y367083D01*
X1322450Y367000D01*
X1322742D01*
X1323033Y367083D01*
X1323283Y367208D01*
X1323492Y367375D01*
G01X1324633Y367500D02*
X1324883Y367208D01*
X1325217Y367042D01*
X1325592Y367000D01*
X1325925Y367042D01*
X1326258Y367250D01*
X1326467Y367500D01*
X1326508Y367750D01*
X1326425Y368042D01*
X1326133Y368250D01*
X1325842Y368333D01*
X1325467D01*
G01X1325842D02*
X1326092Y368458D01*
X1326300Y368667D01*
X1326383Y368917D01*
X1326300Y369167D01*
X1326092Y369375D01*
X1325717Y369500D01*
X1325342Y369458D01*
X1324967Y369292D01*
G01X1328567Y367000D02*
X1328650Y367542D01*
X1328775Y368000D01*
X1328942Y368417D01*
X1329150Y368875D01*
X1329483Y369500D01*
X1327817D01*
G01X1316300Y375000D02*
Y367000D01*
G01X1318517Y371500D02*
Y374000D01*
X1319517D01*
X1319850Y373875D01*
X1320100Y373583D01*
X1320183Y373250D01*
X1320100Y372917D01*
X1319892Y372667D01*
X1319517Y372542D01*
X1318517D01*
G01X1323367Y373792D02*
X1323117Y373917D01*
X1322825Y374000D01*
X1322492D01*
X1322117Y373875D01*
X1321825Y373667D01*
X1321617Y373417D01*
X1321450Y373000D01*
X1321408Y372625D01*
X1321492Y372250D01*
X1321617Y372000D01*
X1321867Y371750D01*
X1322158Y371583D01*
X1322450Y371500D01*
X1322742D01*
X1323033Y371583D01*
X1323283Y371708D01*
X1323492Y371875D01*
G01X1324633Y372000D02*
X1324883Y371708D01*
X1325217Y371542D01*
X1325592Y371500D01*
X1325925Y371542D01*
X1326258Y371750D01*
X1326467Y372000D01*
X1326508Y372250D01*
X1326425Y372542D01*
X1326133Y372750D01*
X1325842Y372833D01*
X1325467D01*
G01X1325842D02*
X1326092Y372958D01*
X1326300Y373167D01*
X1326383Y373417D01*
X1326300Y373667D01*
X1326092Y373875D01*
X1325717Y374000D01*
X1325342Y373958D01*
X1324967Y373792D01*
G01X1328650Y371500D02*
X1328942Y371542D01*
X1329275Y371667D01*
X1329483Y371875D01*
X1329567Y372167D01*
X1329483Y372458D01*
X1329233Y372708D01*
X1328858Y372833D01*
X1328442D01*
X1328192Y372917D01*
X1327983Y373125D01*
X1327900Y373417D01*
X1328025Y373708D01*
X1328317Y373917D01*
X1328650Y374000D01*
X1328983Y373917D01*
X1329275Y373708D01*
X1329400Y373417D01*
X1329317Y373125D01*
X1329108Y372917D01*
X1328858Y372833D01*
X1328442D01*
X1328067Y372708D01*
X1327817Y372458D01*
X1327733Y372167D01*
X1327817Y371875D01*
X1328025Y371667D01*
X1328358Y371542D01*
X1328650Y371500D01*
G01X1316300Y384000D02*
Y376000D01*
G01X1329500Y376800D02*
Y412200D01*
X1357500D01*
Y376800D01*
X1329500D01*
G01X1326032Y389283D02*
X1323532D01*
Y390283D01*
X1323657Y390616D01*
X1323949Y390866D01*
X1324282Y390949D01*
X1324615Y390866D01*
X1324865Y390658D01*
X1324990Y390283D01*
Y389283D01*
G01X1323532Y392383D02*
X1326032D01*
Y394049D01*
G01Y396316D02*
X1323532D01*
X1324032Y395816D01*
G01X1326032D02*
Y396816D01*
G01X1325000Y404517D02*
X1322500D01*
Y405517D01*
X1322625Y405850D01*
X1322917Y406100D01*
X1323250Y406183D01*
X1323583Y406100D01*
X1323833Y405892D01*
X1323958Y405517D01*
Y404517D01*
G01X1322708Y409367D02*
X1322583Y409117D01*
X1322500Y408825D01*
Y408492D01*
X1322625Y408117D01*
X1322833Y407825D01*
X1323083Y407617D01*
X1323500Y407450D01*
X1323875Y407408D01*
X1324250Y407492D01*
X1324500Y407617D01*
X1324750Y407867D01*
X1324917Y408158D01*
X1325000Y408450D01*
Y408742D01*
X1324917Y409033D01*
X1324792Y409283D01*
X1324625Y409492D01*
G01X1325000Y411550D02*
X1322500D01*
X1323000Y411050D01*
G01X1325000D02*
Y412050D01*
G01X1322917Y413858D02*
X1322667Y414108D01*
X1322542Y414400D01*
X1322500Y414733D01*
X1322583Y415150D01*
X1322792Y415442D01*
X1323042Y415525D01*
X1323292Y415483D01*
X1323500Y415317D01*
X1323917Y414483D01*
X1324208Y414108D01*
X1324625Y413858D01*
X1325000Y413775D01*
Y415525D01*
G01X1320500Y406517D02*
X1318000D01*
Y407517D01*
X1318125Y407850D01*
X1318417Y408100D01*
X1318750Y408183D01*
X1319083Y408100D01*
X1319333Y407892D01*
X1319458Y407517D01*
Y406517D01*
G01X1320500Y409617D02*
X1318000D01*
Y410658D01*
X1318125Y410992D01*
X1318292Y411200D01*
X1318625Y411283D01*
X1318958Y411200D01*
X1319167Y410950D01*
X1319292Y410658D01*
Y409617D01*
G01Y410658D02*
X1320500Y411283D01*
G01Y413550D02*
X1318000D01*
X1318500Y413050D01*
G01X1320500D02*
Y414050D01*
G01X1320125Y415733D02*
X1320333Y415983D01*
X1320458Y416275D01*
X1320500Y416650D01*
X1320417Y417025D01*
X1320250Y417317D01*
X1319958Y417525D01*
X1319625Y417567D01*
X1319292Y417483D01*
X1319083Y417275D01*
X1318917Y416983D01*
X1318875Y416692D01*
X1318917Y416400D01*
X1319083Y416025D01*
X1318000Y416150D01*
Y417275D01*
G01X1328200Y430500D02*
X1319500D01*
G01X1328200Y423500D02*
Y430500D01*
G01X1321800Y423500D02*
X1328200D01*
G01X1325500Y438700D02*
X1321500D01*
Y431300D01*
G01X1333094Y439453D02*
X1331094D01*
G01X1325500Y450700D02*
X1321500D01*
Y443300D01*
G01X1316500D02*
X1320500D01*
Y450700D01*
G01X1327500Y465517D02*
X1325000D01*
Y466517D01*
X1325125Y466850D01*
X1325417Y467100D01*
X1325750Y467183D01*
X1326083Y467100D01*
X1326333Y466892D01*
X1326458Y466517D01*
Y465517D01*
G01X1327500Y468617D02*
X1325000D01*
Y469658D01*
X1325125Y469992D01*
X1325292Y470200D01*
X1325625Y470283D01*
X1325958Y470200D01*
X1326167Y469950D01*
X1326292Y469658D01*
Y468617D01*
G01Y469658D02*
X1327500Y470283D01*
G01Y472550D02*
X1325000D01*
X1325500Y472050D01*
G01X1327500D02*
Y473050D01*
G01X1326458Y474858D02*
X1326167Y475150D01*
X1326000Y475400D01*
X1325917Y475733D01*
X1326000Y476025D01*
X1326167Y476233D01*
X1326417Y476400D01*
X1326708Y476442D01*
X1326958Y476400D01*
X1327208Y476233D01*
X1327417Y475983D01*
X1327500Y475692D01*
X1327417Y475358D01*
X1327167Y475067D01*
X1326792Y474900D01*
X1326375Y474858D01*
X1325833Y474942D01*
X1325542Y475067D01*
X1325250Y475275D01*
X1325042Y475567D01*
X1325000Y475858D01*
X1325083Y476150D01*
X1325292Y476358D01*
G01X1323000Y452517D02*
X1320500D01*
Y453517D01*
X1320625Y453850D01*
X1320917Y454100D01*
X1321250Y454183D01*
X1321583Y454100D01*
X1321833Y453892D01*
X1321958Y453517D01*
Y452517D01*
G01X1323000Y455617D02*
X1320500D01*
Y456658D01*
X1320625Y456992D01*
X1320792Y457200D01*
X1321125Y457283D01*
X1321458Y457200D01*
X1321667Y456950D01*
X1321792Y456658D01*
Y455617D01*
G01Y456658D02*
X1323000Y457283D01*
G01Y459550D02*
X1320500D01*
X1321000Y459050D01*
G01X1323000D02*
Y460050D01*
G01Y462567D02*
X1322458Y462650D01*
X1322000Y462775D01*
X1321583Y462942D01*
X1321125Y463150D01*
X1320500Y463483D01*
Y461817D01*
G01X1323000Y465517D02*
X1320500D01*
Y466517D01*
X1320625Y466850D01*
X1320917Y467100D01*
X1321250Y467183D01*
X1321583Y467100D01*
X1321833Y466892D01*
X1321958Y466517D01*
Y465517D01*
G01X1323000Y468617D02*
X1320500D01*
Y469658D01*
X1320625Y469992D01*
X1320792Y470200D01*
X1321125Y470283D01*
X1321458Y470200D01*
X1321667Y469950D01*
X1321792Y469658D01*
Y468617D01*
G01Y469658D02*
X1323000Y470283D01*
G01X1320917Y471758D02*
X1320667Y472008D01*
X1320542Y472300D01*
X1320500Y472633D01*
X1320583Y473050D01*
X1320792Y473342D01*
X1321042Y473425D01*
X1321292Y473383D01*
X1321500Y473217D01*
X1321917Y472383D01*
X1322208Y472008D01*
X1322625Y471758D01*
X1323000Y471675D01*
Y473425D01*
G01X1320917Y474858D02*
X1320667Y475108D01*
X1320542Y475400D01*
X1320500Y475733D01*
X1320583Y476150D01*
X1320792Y476442D01*
X1321042Y476525D01*
X1321292Y476483D01*
X1321500Y476317D01*
X1321917Y475483D01*
X1322208Y475108D01*
X1322625Y474858D01*
X1323000Y474775D01*
Y476525D01*
G01X1327000Y452517D02*
X1324500D01*
Y453517D01*
X1324625Y453850D01*
X1324917Y454100D01*
X1325250Y454183D01*
X1325583Y454100D01*
X1325833Y453892D01*
X1325958Y453517D01*
Y452517D01*
G01X1324708Y457367D02*
X1324583Y457117D01*
X1324500Y456825D01*
Y456492D01*
X1324625Y456117D01*
X1324833Y455825D01*
X1325083Y455617D01*
X1325500Y455450D01*
X1325875Y455408D01*
X1326250Y455492D01*
X1326500Y455617D01*
X1326750Y455867D01*
X1326917Y456158D01*
X1327000Y456450D01*
Y456742D01*
X1326917Y457033D01*
X1326792Y457283D01*
X1326625Y457492D01*
G01X1324917Y458758D02*
X1324667Y459008D01*
X1324542Y459300D01*
X1324500Y459633D01*
X1324583Y460050D01*
X1324792Y460342D01*
X1325042Y460425D01*
X1325292Y460383D01*
X1325500Y460217D01*
X1325917Y459383D01*
X1326208Y459008D01*
X1326625Y458758D01*
X1327000Y458675D01*
Y460425D01*
G01X1324500Y462650D02*
X1324583Y462317D01*
X1324792Y462067D01*
X1325042Y461900D01*
X1325375Y461775D01*
X1325750Y461733D01*
X1326125Y461775D01*
X1326458Y461900D01*
X1326708Y462067D01*
X1326917Y462317D01*
X1327000Y462650D01*
X1326917Y462983D01*
X1326708Y463233D01*
X1326458Y463400D01*
X1326125Y463525D01*
X1325750Y463567D01*
X1325375Y463525D01*
X1325042Y463400D01*
X1324792Y463233D01*
X1324583Y462983D01*
X1324500Y462650D01*
G01X1328817Y582612D02*
Y577612D01*
X1333817D01*
G01X1327834Y569204D02*
X1327584Y569329D01*
X1327292Y569412D01*
X1326959D01*
X1326584Y569287D01*
X1326292Y569079D01*
X1326084Y568829D01*
X1325917Y568412D01*
X1325875Y568037D01*
X1325959Y567662D01*
X1326084Y567412D01*
X1326334Y567162D01*
X1326625Y566995D01*
X1326917Y566912D01*
X1327209D01*
X1327500Y566995D01*
X1327750Y567120D01*
X1327959Y567287D01*
G01X1330017Y566912D02*
X1330309Y566954D01*
X1330642Y567079D01*
X1330850Y567287D01*
X1330934Y567579D01*
X1330850Y567870D01*
X1330600Y568120D01*
X1330225Y568245D01*
X1329809D01*
X1329559Y568329D01*
X1329350Y568537D01*
X1329267Y568829D01*
X1329392Y569120D01*
X1329684Y569329D01*
X1330017Y569412D01*
X1330350Y569329D01*
X1330642Y569120D01*
X1330767Y568829D01*
X1330684Y568537D01*
X1330475Y568329D01*
X1330225Y568245D01*
X1329809D01*
X1329434Y568120D01*
X1329184Y567870D01*
X1329100Y567579D01*
X1329184Y567287D01*
X1329392Y567079D01*
X1329725Y566954D01*
X1330017Y566912D01*
G01X1333117Y569412D02*
X1332784Y569329D01*
X1332534Y569120D01*
X1332367Y568870D01*
X1332242Y568537D01*
X1332200Y568162D01*
X1332242Y567787D01*
X1332367Y567454D01*
X1332534Y567204D01*
X1332784Y566995D01*
X1333117Y566912D01*
X1333450Y566995D01*
X1333700Y567204D01*
X1333867Y567454D01*
X1333992Y567787D01*
X1334034Y568162D01*
X1333992Y568537D01*
X1333867Y568870D01*
X1333700Y569120D01*
X1333450Y569329D01*
X1333117Y569412D01*
G01X1335509Y567204D02*
X1335800Y566995D01*
X1336134Y566912D01*
X1336467Y566995D01*
X1336759Y567245D01*
X1336967Y567620D01*
X1337050Y567995D01*
Y568454D01*
X1336967Y568829D01*
X1336759Y569162D01*
X1336509Y569329D01*
X1336217Y569412D01*
X1335884Y569329D01*
X1335634Y569162D01*
X1335467Y568912D01*
X1335384Y568579D01*
X1335467Y568287D01*
X1335675Y567995D01*
X1335925Y567829D01*
X1336217Y567787D01*
X1336550Y567870D01*
X1336800Y568079D01*
X1337050Y568454D01*
G01X1339317Y566912D02*
Y569412D01*
X1338817Y568912D01*
G01Y566912D02*
X1339817D01*
G01X1327617Y589512D02*
X1329617D01*
G01X1329517Y599312D02*
X1327117D01*
G01X1328817Y604212D02*
Y609212D01*
X1333817D01*
G01X1332117Y625929D02*
X1329617D01*
Y626970D01*
X1329742Y627304D01*
X1329909Y627512D01*
X1330242Y627595D01*
X1330575Y627512D01*
X1330784Y627262D01*
X1330909Y626970D01*
Y625929D01*
G01Y626970D02*
X1332117Y627595D01*
G01X1330034Y629070D02*
X1329784Y629320D01*
X1329659Y629612D01*
X1329617Y629945D01*
X1329700Y630362D01*
X1329909Y630654D01*
X1330159Y630737D01*
X1330409Y630695D01*
X1330617Y630529D01*
X1331034Y629695D01*
X1331325Y629320D01*
X1331742Y629070D01*
X1332117Y628987D01*
Y630737D01*
G01X1330034Y632170D02*
X1329784Y632420D01*
X1329659Y632712D01*
X1329617Y633045D01*
X1329700Y633462D01*
X1329909Y633754D01*
X1330159Y633837D01*
X1330409Y633795D01*
X1330617Y633629D01*
X1331034Y632795D01*
X1331325Y632420D01*
X1331742Y632170D01*
X1332117Y632087D01*
Y633837D01*
G01X1330034Y635270D02*
X1329784Y635520D01*
X1329659Y635812D01*
X1329617Y636145D01*
X1329700Y636562D01*
X1329909Y636854D01*
X1330159Y636937D01*
X1330409Y636895D01*
X1330617Y636729D01*
X1331034Y635895D01*
X1331325Y635520D01*
X1331742Y635270D01*
X1332117Y635187D01*
Y636937D01*
G01X1334117Y624112D02*
X1330117D01*
Y616712D01*
G01X1327617Y625929D02*
X1325117D01*
Y626970D01*
X1325242Y627304D01*
X1325409Y627512D01*
X1325742Y627595D01*
X1326075Y627512D01*
X1326284Y627262D01*
X1326409Y626970D01*
Y625929D01*
G01Y626970D02*
X1327617Y627595D01*
G01X1327242Y628945D02*
X1327450Y629195D01*
X1327575Y629487D01*
X1327617Y629862D01*
X1327534Y630237D01*
X1327367Y630529D01*
X1327075Y630737D01*
X1326742Y630779D01*
X1326409Y630695D01*
X1326200Y630487D01*
X1326034Y630195D01*
X1325992Y629904D01*
X1326034Y629612D01*
X1326200Y629237D01*
X1325117Y629362D01*
Y630487D01*
G01X1327117Y632045D02*
X1327409Y632295D01*
X1327575Y632629D01*
X1327617Y633004D01*
X1327575Y633337D01*
X1327367Y633670D01*
X1327117Y633879D01*
X1326867Y633920D01*
X1326575Y633837D01*
X1326367Y633545D01*
X1326284Y633254D01*
Y632879D01*
G01Y633254D02*
X1326159Y633504D01*
X1325950Y633712D01*
X1325700Y633795D01*
X1325450Y633712D01*
X1325242Y633504D01*
X1325117Y633129D01*
X1325159Y632754D01*
X1325325Y632379D01*
G01X1327242Y635145D02*
X1327450Y635395D01*
X1327575Y635687D01*
X1327617Y636062D01*
X1327534Y636437D01*
X1327367Y636729D01*
X1327075Y636937D01*
X1326742Y636979D01*
X1326409Y636895D01*
X1326200Y636687D01*
X1326034Y636395D01*
X1325992Y636104D01*
X1326034Y635812D01*
X1326200Y635437D01*
X1325117Y635562D01*
Y636687D01*
G01X1329617Y624112D02*
X1325617D01*
Y616712D01*
G01X1320000Y625467D02*
X1317500D01*
Y626508D01*
X1317625Y626842D01*
X1317792Y627050D01*
X1318125Y627133D01*
X1318458Y627050D01*
X1318667Y626800D01*
X1318792Y626508D01*
Y625467D01*
G01Y626508D02*
X1320000Y627133D01*
G01Y629317D02*
X1319458Y629400D01*
X1319000Y629525D01*
X1318583Y629692D01*
X1318125Y629900D01*
X1317500Y630233D01*
Y628567D01*
G01X1320000Y632500D02*
X1319958Y632792D01*
X1319833Y633125D01*
X1319625Y633333D01*
X1319333Y633417D01*
X1319042Y633333D01*
X1318792Y633083D01*
X1318667Y632708D01*
Y632292D01*
X1318583Y632042D01*
X1318375Y631833D01*
X1318083Y631750D01*
X1317792Y631875D01*
X1317583Y632167D01*
X1317500Y632500D01*
X1317583Y632833D01*
X1317792Y633125D01*
X1318083Y633250D01*
X1318375Y633167D01*
X1318583Y632958D01*
X1318667Y632708D01*
Y632292D01*
X1318792Y631917D01*
X1319042Y631667D01*
X1319333Y631583D01*
X1319625Y631667D01*
X1319833Y631875D01*
X1319958Y632208D01*
X1320000Y632500D01*
G01X1319708Y634892D02*
X1319917Y635183D01*
X1320000Y635517D01*
X1319917Y635850D01*
X1319667Y636142D01*
X1319292Y636350D01*
X1318917Y636433D01*
X1318458D01*
X1318083Y636350D01*
X1317750Y636142D01*
X1317583Y635892D01*
X1317500Y635600D01*
X1317583Y635267D01*
X1317750Y635017D01*
X1318000Y634850D01*
X1318333Y634767D01*
X1318625Y634850D01*
X1318917Y635058D01*
X1319083Y635308D01*
X1319125Y635600D01*
X1319042Y635933D01*
X1318833Y636183D01*
X1318458Y636433D01*
G01X1319708Y637992D02*
X1319917Y638283D01*
X1320000Y638617D01*
X1319917Y638950D01*
X1319667Y639242D01*
X1319292Y639450D01*
X1318917Y639533D01*
X1318458D01*
X1318083Y639450D01*
X1317750Y639242D01*
X1317583Y638992D01*
X1317500Y638700D01*
X1317583Y638367D01*
X1317750Y638117D01*
X1318000Y637950D01*
X1318333Y637867D01*
X1318625Y637950D01*
X1318917Y638158D01*
X1319083Y638408D01*
X1319125Y638700D01*
X1319042Y639033D01*
X1318833Y639283D01*
X1318458Y639533D01*
G01X1321117Y616712D02*
X1325117D01*
Y624112D01*
G01X1337368Y655784D02*
Y647784D01*
X1324968D01*
Y655784D01*
X1337368D01*
G01X1329968Y680301D02*
X1327468D01*
Y681342D01*
X1327593Y681676D01*
X1327760Y681884D01*
X1328093Y681967D01*
X1328426Y681884D01*
X1328635Y681634D01*
X1328760Y681342D01*
Y680301D01*
G01Y681342D02*
X1329968Y681967D01*
G01X1327885Y683442D02*
X1327635Y683692D01*
X1327510Y683984D01*
X1327468Y684317D01*
X1327551Y684734D01*
X1327760Y685026D01*
X1328010Y685109D01*
X1328260Y685067D01*
X1328468Y684901D01*
X1328885Y684067D01*
X1329176Y683692D01*
X1329593Y683442D01*
X1329968Y683359D01*
Y685109D01*
G01Y687251D02*
X1329426Y687334D01*
X1328968Y687459D01*
X1328551Y687626D01*
X1328093Y687834D01*
X1327468Y688167D01*
Y686501D01*
G01X1328926Y689642D02*
X1328635Y689934D01*
X1328468Y690184D01*
X1328385Y690517D01*
X1328468Y690809D01*
X1328635Y691017D01*
X1328885Y691184D01*
X1329176Y691226D01*
X1329426Y691184D01*
X1329676Y691017D01*
X1329885Y690767D01*
X1329968Y690476D01*
X1329885Y690142D01*
X1329635Y689851D01*
X1329260Y689684D01*
X1328843Y689642D01*
X1328301Y689726D01*
X1328010Y689851D01*
X1327718Y690059D01*
X1327510Y690351D01*
X1327468Y690642D01*
X1327551Y690934D01*
X1327760Y691142D01*
G01X1330968Y678484D02*
X1326968D01*
Y671084D01*
G01X1332500Y827517D02*
X1330000D01*
Y828558D01*
X1330125Y828892D01*
X1330292Y829100D01*
X1330625Y829183D01*
X1330958Y829100D01*
X1331167Y828850D01*
X1331292Y828558D01*
Y827517D01*
G01Y828558D02*
X1332500Y829183D01*
G01X1330417Y830658D02*
X1330167Y830908D01*
X1330042Y831200D01*
X1330000Y831533D01*
X1330083Y831950D01*
X1330292Y832242D01*
X1330542Y832325D01*
X1330792Y832283D01*
X1331000Y832117D01*
X1331417Y831283D01*
X1331708Y830908D01*
X1332125Y830658D01*
X1332500Y830575D01*
Y832325D01*
G01X1330000Y834550D02*
X1330083Y834217D01*
X1330292Y833967D01*
X1330542Y833800D01*
X1330875Y833675D01*
X1331250Y833633D01*
X1331625Y833675D01*
X1331958Y833800D01*
X1332208Y833967D01*
X1332417Y834217D01*
X1332500Y834550D01*
X1332417Y834883D01*
X1332208Y835133D01*
X1331958Y835300D01*
X1331625Y835425D01*
X1331250Y835467D01*
X1330875Y835425D01*
X1330542Y835300D01*
X1330292Y835133D01*
X1330083Y834883D01*
X1330000Y834550D01*
G01Y837650D02*
X1330083Y837317D01*
X1330292Y837067D01*
X1330542Y836900D01*
X1330875Y836775D01*
X1331250Y836733D01*
X1331625Y836775D01*
X1331958Y836900D01*
X1332208Y837067D01*
X1332417Y837317D01*
X1332500Y837650D01*
X1332417Y837983D01*
X1332208Y838233D01*
X1331958Y838400D01*
X1331625Y838525D01*
X1331250Y838567D01*
X1330875Y838525D01*
X1330542Y838400D01*
X1330292Y838233D01*
X1330083Y837983D01*
X1330000Y837650D01*
G01X1325992Y829299D02*
X1325867Y829049D01*
X1325784Y828757D01*
Y828424D01*
X1325909Y828049D01*
X1326117Y827757D01*
X1326367Y827549D01*
X1326784Y827382D01*
X1327159Y827340D01*
X1327534Y827424D01*
X1327784Y827549D01*
X1328034Y827799D01*
X1328201Y828090D01*
X1328284Y828382D01*
Y828674D01*
X1328201Y828965D01*
X1328076Y829215D01*
X1327909Y829424D01*
G01X1328284Y831482D02*
X1325784D01*
X1326284Y830982D01*
G01X1328284D02*
Y831982D01*
G01X1327909Y833665D02*
X1328117Y833915D01*
X1328242Y834207D01*
X1328284Y834582D01*
X1328201Y834957D01*
X1328034Y835249D01*
X1327742Y835457D01*
X1327409Y835499D01*
X1327076Y835415D01*
X1326867Y835207D01*
X1326701Y834915D01*
X1326659Y834624D01*
X1326701Y834332D01*
X1326867Y833957D01*
X1325784Y834082D01*
Y835207D01*
G01X1326201Y836890D02*
X1325951Y837140D01*
X1325826Y837432D01*
X1325784Y837765D01*
X1325867Y838182D01*
X1326076Y838474D01*
X1326326Y838557D01*
X1326576Y838515D01*
X1326784Y838349D01*
X1327201Y837515D01*
X1327492Y837140D01*
X1327909Y836890D01*
X1328284Y836807D01*
Y838557D01*
G01X1318500Y828800D02*
X1322500D01*
Y836200D01*
G01X1328000Y859450D02*
X1324000D01*
Y852050D01*
G01X1332000Y849517D02*
X1329500D01*
Y850558D01*
X1329625Y850892D01*
X1329792Y851100D01*
X1330125Y851183D01*
X1330458Y851100D01*
X1330667Y850850D01*
X1330792Y850558D01*
Y849517D01*
G01Y850558D02*
X1332000Y851183D01*
G01Y853450D02*
X1329500D01*
X1330000Y852950D01*
G01X1332000D02*
Y853950D01*
G01Y856550D02*
X1331958Y856842D01*
X1331833Y857175D01*
X1331625Y857383D01*
X1331333Y857467D01*
X1331042Y857383D01*
X1330792Y857133D01*
X1330667Y856758D01*
Y856342D01*
X1330583Y856092D01*
X1330375Y855883D01*
X1330083Y855800D01*
X1329792Y855925D01*
X1329583Y856217D01*
X1329500Y856550D01*
X1329583Y856883D01*
X1329792Y857175D01*
X1330083Y857300D01*
X1330375Y857217D01*
X1330583Y857008D01*
X1330667Y856758D01*
Y856342D01*
X1330792Y855967D01*
X1331042Y855717D01*
X1331333Y855633D01*
X1331625Y855717D01*
X1331833Y855925D01*
X1331958Y856258D01*
X1332000Y856550D01*
G01Y860150D02*
X1329500D01*
X1331292Y858608D01*
Y860692D01*
G01X1319000Y859450D02*
X1315000D01*
Y852050D01*
G01X1323500Y859450D02*
X1319500D01*
Y852050D01*
G01X1322000Y899350D02*
X1324500D01*
G01X1322000Y898392D02*
Y900308D01*
G01X1324500Y901617D02*
X1322000D01*
Y902617D01*
X1322125Y902950D01*
X1322417Y903200D01*
X1322750Y903283D01*
X1323083Y903200D01*
X1323333Y902992D01*
X1323458Y902617D01*
Y901617D01*
G01X1324500Y905550D02*
X1324458Y905842D01*
X1324333Y906175D01*
X1324125Y906383D01*
X1323833Y906467D01*
X1323542Y906383D01*
X1323292Y906133D01*
X1323167Y905758D01*
Y905342D01*
X1323083Y905092D01*
X1322875Y904883D01*
X1322583Y904800D01*
X1322292Y904925D01*
X1322083Y905217D01*
X1322000Y905550D01*
X1322083Y905883D01*
X1322292Y906175D01*
X1322583Y906300D01*
X1322875Y906217D01*
X1323083Y906008D01*
X1323167Y905758D01*
Y905342D01*
X1323292Y904967D01*
X1323542Y904717D01*
X1323833Y904633D01*
X1324125Y904717D01*
X1324333Y904925D01*
X1324458Y905258D01*
X1324500Y905550D01*
G01Y909150D02*
X1322000D01*
X1323792Y907608D01*
Y909692D01*
G01X1329000Y898517D02*
X1326500D01*
Y899558D01*
X1326625Y899892D01*
X1326792Y900100D01*
X1327125Y900183D01*
X1327458Y900100D01*
X1327667Y899850D01*
X1327792Y899558D01*
Y898517D01*
G01Y899558D02*
X1329000Y900183D01*
G01Y902450D02*
X1326500D01*
X1327000Y901950D01*
G01X1329000D02*
Y902950D01*
G01Y905550D02*
X1328958Y905842D01*
X1328833Y906175D01*
X1328625Y906383D01*
X1328333Y906467D01*
X1328042Y906383D01*
X1327792Y906133D01*
X1327667Y905758D01*
Y905342D01*
X1327583Y905092D01*
X1327375Y904883D01*
X1327083Y904800D01*
X1326792Y904925D01*
X1326583Y905217D01*
X1326500Y905550D01*
X1326583Y905883D01*
X1326792Y906175D01*
X1327083Y906300D01*
X1327375Y906217D01*
X1327583Y906008D01*
X1327667Y905758D01*
Y905342D01*
X1327792Y904967D01*
X1328042Y904717D01*
X1328333Y904633D01*
X1328625Y904717D01*
X1328833Y904925D01*
X1328958Y905258D01*
X1329000Y905550D01*
G01Y908567D02*
X1328458Y908650D01*
X1328000Y908775D01*
X1327583Y908942D01*
X1327125Y909150D01*
X1326500Y909483D01*
Y907817D01*
G01X1315500Y900800D02*
X1319500D01*
Y908200D01*
G01X1317968Y921801D02*
X1315468D01*
Y922842D01*
X1315593Y923176D01*
X1315760Y923384D01*
X1316093Y923467D01*
X1316426Y923384D01*
X1316635Y923134D01*
X1316760Y922842D01*
Y921801D01*
G01Y922842D02*
X1317968Y923467D01*
G01Y925734D02*
X1315468D01*
X1315968Y925234D01*
G01X1317968D02*
Y926234D01*
G01Y928834D02*
X1317926Y929126D01*
X1317801Y929459D01*
X1317593Y929667D01*
X1317301Y929751D01*
X1317010Y929667D01*
X1316760Y929417D01*
X1316635Y929042D01*
Y928626D01*
X1316551Y928376D01*
X1316343Y928167D01*
X1316051Y928084D01*
X1315760Y928209D01*
X1315551Y928501D01*
X1315468Y928834D01*
X1315551Y929167D01*
X1315760Y929459D01*
X1316051Y929584D01*
X1316343Y929501D01*
X1316551Y929292D01*
X1316635Y929042D01*
Y928626D01*
X1316760Y928251D01*
X1317010Y928001D01*
X1317301Y927917D01*
X1317593Y928001D01*
X1317801Y928209D01*
X1317926Y928542D01*
X1317968Y928834D01*
G01X1316926Y931142D02*
X1316635Y931434D01*
X1316468Y931684D01*
X1316385Y932017D01*
X1316468Y932309D01*
X1316635Y932517D01*
X1316885Y932684D01*
X1317176Y932726D01*
X1317426Y932684D01*
X1317676Y932517D01*
X1317885Y932267D01*
X1317968Y931976D01*
X1317885Y931642D01*
X1317635Y931351D01*
X1317260Y931184D01*
X1316843Y931142D01*
X1316301Y931226D01*
X1316010Y931351D01*
X1315718Y931559D01*
X1315510Y931851D01*
X1315468Y932142D01*
X1315551Y932434D01*
X1315760Y932642D01*
G01X1318968Y918984D02*
X1314968D01*
Y911584D01*
G01X1338667Y43425D02*
X1338875Y43758D01*
X1339000Y44133D01*
Y44467D01*
X1338875Y44800D01*
X1338667Y45050D01*
X1338375Y45175D01*
X1338083Y45092D01*
X1337833Y44883D01*
X1337667Y44508D01*
X1337583Y44008D01*
X1337417Y43717D01*
X1337125Y43592D01*
X1336833Y43675D01*
X1336625Y43883D01*
X1336500Y44175D01*
Y44467D01*
X1336583Y44758D01*
X1336792Y45008D01*
G01X1339000Y46567D02*
X1336500D01*
Y47608D01*
X1336625Y47942D01*
X1336792Y48150D01*
X1337125Y48233D01*
X1337458Y48150D01*
X1337667Y47900D01*
X1337792Y47608D01*
Y46567D01*
G01Y47608D02*
X1339000Y48233D01*
G01Y50417D02*
X1338458Y50500D01*
X1338000Y50625D01*
X1337583Y50792D01*
X1337125Y51000D01*
X1336500Y51333D01*
Y49667D01*
G01Y53600D02*
X1336583Y53267D01*
X1336792Y53017D01*
X1337042Y52850D01*
X1337375Y52725D01*
X1337750Y52683D01*
X1338125Y52725D01*
X1338458Y52850D01*
X1338708Y53017D01*
X1338917Y53267D01*
X1339000Y53600D01*
X1338917Y53933D01*
X1338708Y54183D01*
X1338458Y54350D01*
X1338125Y54475D01*
X1337750Y54517D01*
X1337375Y54475D01*
X1337042Y54350D01*
X1336792Y54183D01*
X1336583Y53933D01*
X1336500Y53600D01*
G01X1339000Y56617D02*
X1338458Y56700D01*
X1338000Y56825D01*
X1337583Y56992D01*
X1337125Y57200D01*
X1336500Y57533D01*
Y55867D01*
G01X1340000Y75800D02*
X1344000D01*
Y83200D01*
G01X1334000Y75017D02*
X1331500D01*
Y76058D01*
X1331625Y76392D01*
X1331792Y76600D01*
X1332125Y76683D01*
X1332458Y76600D01*
X1332667Y76350D01*
X1332792Y76058D01*
Y75017D01*
G01Y76058D02*
X1334000Y76683D01*
G01Y79450D02*
X1331500D01*
X1333292Y77908D01*
Y79992D01*
G01X1333625Y81133D02*
X1333833Y81383D01*
X1333958Y81675D01*
X1334000Y82050D01*
X1333917Y82425D01*
X1333750Y82717D01*
X1333458Y82925D01*
X1333125Y82967D01*
X1332792Y82883D01*
X1332583Y82675D01*
X1332417Y82383D01*
X1332375Y82092D01*
X1332417Y81800D01*
X1332583Y81425D01*
X1331500Y81550D01*
Y82675D01*
G01X1333500Y84233D02*
X1333792Y84483D01*
X1333958Y84817D01*
X1334000Y85192D01*
X1333958Y85525D01*
X1333750Y85858D01*
X1333500Y86067D01*
X1333250Y86108D01*
X1332958Y86025D01*
X1332750Y85733D01*
X1332667Y85442D01*
Y85067D01*
G01Y85442D02*
X1332542Y85692D01*
X1332333Y85900D01*
X1332083Y85983D01*
X1331833Y85900D01*
X1331625Y85692D01*
X1331500Y85317D01*
X1331542Y84942D01*
X1331708Y84567D01*
G01X1332625Y100792D02*
X1332833Y100625D01*
X1333125Y100500D01*
X1333375D01*
X1333625Y100583D01*
X1333792Y100708D01*
X1333875Y100875D01*
X1333833Y101125D01*
X1333667Y101250D01*
X1332917Y101500D01*
X1332750Y101792D01*
X1332833Y102000D01*
X1333000Y102125D01*
X1333250Y102167D01*
X1333500Y102125D01*
X1333750Y102000D01*
G01X1335642Y100500D02*
Y103000D01*
G01Y101792D02*
X1335850Y102000D01*
X1336058Y102125D01*
X1336392Y102167D01*
X1336642Y102125D01*
X1336933Y101958D01*
X1337058Y101708D01*
Y100500D01*
G01X1338742Y102167D02*
Y101000D01*
X1338908Y100708D01*
X1339158Y100542D01*
X1339450Y100500D01*
X1339742Y100542D01*
X1339992Y100708D01*
X1340158Y101000D01*
G01Y100500D02*
Y102167D01*
G01X1342550Y103000D02*
Y100500D01*
G01X1341967Y102167D02*
X1343133D01*
G01X1349500Y103000D02*
Y100500D01*
G01Y100875D02*
X1349333Y100667D01*
X1349083Y100542D01*
X1348792Y100500D01*
X1348458Y100583D01*
X1348208Y100792D01*
X1348042Y101042D01*
X1348000Y101333D01*
X1348042Y101625D01*
X1348208Y101875D01*
X1348458Y102083D01*
X1348792Y102167D01*
X1349083Y102125D01*
X1349292Y102042D01*
X1349500Y101875D01*
G01X1351850Y100500D02*
X1351600Y100542D01*
X1351350Y100708D01*
X1351183Y101000D01*
X1351100Y101333D01*
X1351183Y101667D01*
X1351350Y101958D01*
X1351600Y102125D01*
X1351850Y102167D01*
X1352100Y102125D01*
X1352350Y101958D01*
X1352517Y101667D01*
X1352558Y101333D01*
X1352517Y101000D01*
X1352350Y100708D01*
X1352100Y100542D01*
X1351850Y100500D01*
G01X1353908Y102167D02*
X1354408Y100500D01*
X1354950Y102167D01*
X1355492Y100500D01*
X1355992Y102167D01*
G01X1357342Y100500D02*
Y102167D01*
G01Y101750D02*
X1357508Y101958D01*
X1357758Y102125D01*
X1358092Y102167D01*
X1358383Y102125D01*
X1358633Y101958D01*
X1358758Y101667D01*
Y100500D01*
G01X1332667Y95500D02*
Y97167D01*
G01Y96833D02*
X1332875Y97000D01*
X1333083Y97125D01*
X1333375Y97167D01*
X1333583Y97125D01*
X1333833Y97000D01*
G01X1335725Y96625D02*
X1337058D01*
X1336933Y96917D01*
X1336725Y97083D01*
X1336433Y97167D01*
X1336142Y97125D01*
X1335892Y97000D01*
X1335725Y96708D01*
X1335642Y96458D01*
Y96208D01*
X1335725Y95958D01*
X1335933Y95708D01*
X1336183Y95542D01*
X1336475Y95500D01*
X1336767Y95583D01*
X1337058Y95833D01*
G01X1339450Y95500D02*
Y98000D01*
G01X1341925Y96625D02*
X1343258D01*
X1343133Y96917D01*
X1342925Y97083D01*
X1342633Y97167D01*
X1342342Y97125D01*
X1342092Y97000D01*
X1341925Y96708D01*
X1341842Y96458D01*
Y96208D01*
X1341925Y95958D01*
X1342133Y95708D01*
X1342383Y95542D01*
X1342675Y95500D01*
X1342967Y95583D01*
X1343258Y95833D01*
G01X1346400Y95500D02*
Y97167D01*
G01Y96875D02*
X1346233Y97042D01*
X1345983Y97125D01*
X1345692Y97167D01*
X1345400Y97083D01*
X1345150Y96917D01*
X1344983Y96667D01*
X1344900Y96333D01*
X1344983Y96000D01*
X1345150Y95750D01*
X1345400Y95583D01*
X1345692Y95500D01*
X1345983Y95542D01*
X1346233Y95667D01*
X1346400Y95833D01*
G01X1348125Y95792D02*
X1348333Y95625D01*
X1348625Y95500D01*
X1348875D01*
X1349125Y95583D01*
X1349292Y95708D01*
X1349375Y95875D01*
X1349333Y96125D01*
X1349167Y96250D01*
X1348417Y96500D01*
X1348250Y96792D01*
X1348333Y97000D01*
X1348500Y97125D01*
X1348750Y97167D01*
X1349000Y97125D01*
X1349250Y97000D01*
G01X1351225Y96625D02*
X1352558D01*
X1352433Y96917D01*
X1352225Y97083D01*
X1351933Y97167D01*
X1351642Y97125D01*
X1351392Y97000D01*
X1351225Y96708D01*
X1351142Y96458D01*
Y96208D01*
X1351225Y95958D01*
X1351433Y95708D01*
X1351683Y95542D01*
X1351975Y95500D01*
X1352267Y95583D01*
X1352558Y95833D01*
G01X1347500Y109000D02*
X1360500D01*
G01X1347500Y123000D02*
Y109000D01*
G01X1345500D02*
Y123000D01*
G01X1332500Y109000D02*
X1345500D01*
G01X1332500Y123000D02*
Y109000D01*
G01X1360500Y123000D02*
X1347500D01*
G01X1341900Y125500D02*
X1341567Y125542D01*
X1341275Y125708D01*
X1341025Y125958D01*
X1340858Y126250D01*
X1340775Y126583D01*
Y126917D01*
X1340858Y127250D01*
X1341025Y127542D01*
X1341275Y127792D01*
X1341567Y127958D01*
X1341900Y128000D01*
X1342233Y127958D01*
X1342525Y127792D01*
X1342775Y127542D01*
X1342942Y127250D01*
X1343025Y126917D01*
Y126583D01*
X1342942Y126250D01*
X1342775Y125958D01*
X1342525Y125708D01*
X1342233Y125542D01*
X1341900Y125500D01*
G01X1342233Y126167D02*
X1342733Y125500D01*
G01X1344208Y127583D02*
X1344458Y127833D01*
X1344750Y127958D01*
X1345083Y128000D01*
X1345500Y127917D01*
X1345792Y127708D01*
X1345875Y127458D01*
X1345833Y127208D01*
X1345667Y127000D01*
X1344833Y126583D01*
X1344458Y126292D01*
X1344208Y125875D01*
X1344125Y125500D01*
X1345875D01*
G01X1348100Y128000D02*
X1347767Y127917D01*
X1347517Y127708D01*
X1347350Y127458D01*
X1347225Y127125D01*
X1347183Y126750D01*
X1347225Y126375D01*
X1347350Y126042D01*
X1347517Y125792D01*
X1347767Y125583D01*
X1348100Y125500D01*
X1348433Y125583D01*
X1348683Y125792D01*
X1348850Y126042D01*
X1348975Y126375D01*
X1349017Y126750D01*
X1348975Y127125D01*
X1348850Y127458D01*
X1348683Y127708D01*
X1348433Y127917D01*
X1348100Y128000D01*
G01X1345500Y123000D02*
X1332500D01*
G01X1338500Y140700D02*
X1334500D01*
Y133300D01*
G01X1337000Y144517D02*
X1334500D01*
Y145558D01*
X1334625Y145892D01*
X1334792Y146100D01*
X1335125Y146183D01*
X1335458Y146100D01*
X1335667Y145850D01*
X1335792Y145558D01*
Y144517D01*
G01Y145558D02*
X1337000Y146183D01*
G01Y148950D02*
X1334500D01*
X1336292Y147408D01*
Y149492D01*
G01X1337000Y151550D02*
X1336958Y151842D01*
X1336833Y152175D01*
X1336625Y152383D01*
X1336333Y152467D01*
X1336042Y152383D01*
X1335792Y152133D01*
X1335667Y151758D01*
Y151342D01*
X1335583Y151092D01*
X1335375Y150883D01*
X1335083Y150800D01*
X1334792Y150925D01*
X1334583Y151217D01*
X1334500Y151550D01*
X1334583Y151883D01*
X1334792Y152175D01*
X1335083Y152300D01*
X1335375Y152217D01*
X1335583Y152008D01*
X1335667Y151758D01*
Y151342D01*
X1335792Y150967D01*
X1336042Y150717D01*
X1336333Y150633D01*
X1336625Y150717D01*
X1336833Y150925D01*
X1336958Y151258D01*
X1337000Y151550D01*
G01Y154567D02*
X1336458Y154650D01*
X1336000Y154775D01*
X1335583Y154942D01*
X1335125Y155150D01*
X1334500Y155483D01*
Y153817D01*
G01X1334484Y276132D02*
X1396684D01*
Y326532D01*
X1334484D01*
Y276132D01*
G01X1346884Y288632D02*
Y314032D01*
G01X1387584Y288632D02*
X1346884D01*
G01Y314032D02*
X1387584D01*
G01X1346900Y426600D02*
X1351900D01*
Y431600D01*
G01X1332100D02*
Y426600D01*
X1337100D01*
G01X1341016Y427594D02*
Y424594D01*
G01X1337100Y446400D02*
X1332100D01*
Y441400D01*
G01X1336067Y467000D02*
Y469500D01*
X1337067D01*
X1337400Y469375D01*
X1337650Y469083D01*
X1337733Y468750D01*
X1337650Y468417D01*
X1337442Y468167D01*
X1337067Y468042D01*
X1336067D01*
G01X1339083Y469500D02*
Y467708D01*
X1339250Y467333D01*
X1339583Y467083D01*
X1340000Y467000D01*
X1340417Y467083D01*
X1340750Y467333D01*
X1340917Y467708D01*
Y469500D01*
G01X1343100Y467000D02*
Y469500D01*
X1342600Y469000D01*
G01Y467000D02*
X1343600D01*
G01X1340500Y461700D02*
X1336500D01*
Y454300D01*
G01X1348000Y465067D02*
X1345500D01*
Y466067D01*
X1345625Y466400D01*
X1345917Y466650D01*
X1346250Y466733D01*
X1346583Y466650D01*
X1346833Y466442D01*
X1346958Y466067D01*
Y465067D01*
G01X1348000Y468167D02*
X1345500D01*
Y469208D01*
X1345625Y469542D01*
X1345792Y469750D01*
X1346125Y469833D01*
X1346458Y469750D01*
X1346667Y469500D01*
X1346792Y469208D01*
Y468167D01*
G01Y469208D02*
X1348000Y469833D01*
G01X1346958Y471308D02*
X1346667Y471600D01*
X1346500Y471850D01*
X1346417Y472183D01*
X1346500Y472475D01*
X1346667Y472683D01*
X1346917Y472850D01*
X1347208Y472892D01*
X1347458Y472850D01*
X1347708Y472683D01*
X1347917Y472433D01*
X1348000Y472142D01*
X1347917Y471808D01*
X1347667Y471517D01*
X1347292Y471350D01*
X1346875Y471308D01*
X1346333Y471392D01*
X1346042Y471517D01*
X1345750Y471725D01*
X1345542Y472017D01*
X1345500Y472308D01*
X1345583Y472600D01*
X1345792Y472808D01*
G01X1349468Y458484D02*
X1345468D01*
Y451084D01*
G01X1344000Y477517D02*
X1341500D01*
Y478517D01*
X1341625Y478850D01*
X1341917Y479100D01*
X1342250Y479183D01*
X1342583Y479100D01*
X1342833Y478892D01*
X1342958Y478517D01*
Y477517D01*
G01X1344000Y480617D02*
X1341500D01*
Y481658D01*
X1341625Y481992D01*
X1341792Y482200D01*
X1342125Y482283D01*
X1342458Y482200D01*
X1342667Y481950D01*
X1342792Y481658D01*
Y480617D01*
G01Y481658D02*
X1344000Y482283D01*
G01Y484550D02*
X1341500D01*
X1342000Y484050D01*
G01X1344000D02*
Y485050D01*
G01X1343500Y486733D02*
X1343792Y486983D01*
X1343958Y487317D01*
X1344000Y487692D01*
X1343958Y488025D01*
X1343750Y488358D01*
X1343500Y488567D01*
X1343250Y488608D01*
X1342958Y488525D01*
X1342750Y488233D01*
X1342667Y487942D01*
Y487567D01*
G01Y487942D02*
X1342542Y488192D01*
X1342333Y488400D01*
X1342083Y488483D01*
X1341833Y488400D01*
X1341625Y488192D01*
X1341500Y487817D01*
X1341542Y487442D01*
X1341708Y487067D01*
G01X1348000Y477517D02*
X1345500D01*
Y478517D01*
X1345625Y478850D01*
X1345917Y479100D01*
X1346250Y479183D01*
X1346583Y479100D01*
X1346833Y478892D01*
X1346958Y478517D01*
Y477517D01*
G01X1345708Y482367D02*
X1345583Y482117D01*
X1345500Y481825D01*
Y481492D01*
X1345625Y481117D01*
X1345833Y480825D01*
X1346083Y480617D01*
X1346500Y480450D01*
X1346875Y480408D01*
X1347250Y480492D01*
X1347500Y480617D01*
X1347750Y480867D01*
X1347917Y481158D01*
X1348000Y481450D01*
Y481742D01*
X1347917Y482033D01*
X1347792Y482283D01*
X1347625Y482492D01*
G01X1348000Y484550D02*
X1345500D01*
X1346000Y484050D01*
G01X1348000D02*
Y485050D01*
G01X1347500Y486733D02*
X1347792Y486983D01*
X1347958Y487317D01*
X1348000Y487692D01*
X1347958Y488025D01*
X1347750Y488358D01*
X1347500Y488567D01*
X1347250Y488608D01*
X1346958Y488525D01*
X1346750Y488233D01*
X1346667Y487942D01*
Y487567D01*
G01Y487942D02*
X1346542Y488192D01*
X1346333Y488400D01*
X1346083Y488483D01*
X1345833Y488400D01*
X1345625Y488192D01*
X1345500Y487817D01*
X1345542Y487442D01*
X1345708Y487067D01*
G01X1333017Y471000D02*
Y473500D01*
X1334017D01*
X1334350Y473375D01*
X1334600Y473083D01*
X1334683Y472750D01*
X1334600Y472417D01*
X1334392Y472167D01*
X1334017Y472042D01*
X1333017D01*
G01X1337867Y473292D02*
X1337617Y473417D01*
X1337325Y473500D01*
X1336992D01*
X1336617Y473375D01*
X1336325Y473167D01*
X1336117Y472917D01*
X1335950Y472500D01*
X1335908Y472125D01*
X1335992Y471750D01*
X1336117Y471500D01*
X1336367Y471250D01*
X1336658Y471083D01*
X1336950Y471000D01*
X1337242D01*
X1337533Y471083D01*
X1337783Y471208D01*
X1337992Y471375D01*
G01X1340050Y471000D02*
Y473500D01*
X1339550Y473000D01*
G01Y471000D02*
X1340550D01*
G01X1343150D02*
Y473500D01*
X1342650Y473000D01*
G01Y471000D02*
X1343650D01*
G01X1339517Y558762D02*
Y542062D01*
X1351717D01*
Y558762D01*
X1339517D01*
G01X1340817Y575712D02*
Y578412D01*
G01X1349317Y565412D02*
Y569412D01*
X1341917D01*
G01X1342717Y608612D02*
Y610412D01*
G01X1348300Y631000D02*
Y628500D01*
G01X1347342Y631000D02*
X1349258D01*
G01X1350567Y628500D02*
Y631000D01*
X1351567D01*
X1351900Y630875D01*
X1352150Y630583D01*
X1352233Y630250D01*
X1352150Y629917D01*
X1351942Y629667D01*
X1351567Y629542D01*
X1350567D01*
G01X1354500Y628500D02*
Y631000D01*
X1354000Y630500D01*
G01Y628500D02*
X1355000D01*
G01X1356808Y629542D02*
X1357100Y629833D01*
X1357350Y630000D01*
X1357683Y630083D01*
X1357975Y630000D01*
X1358183Y629833D01*
X1358350Y629583D01*
X1358392Y629292D01*
X1358350Y629042D01*
X1358183Y628792D01*
X1357933Y628583D01*
X1357642Y628500D01*
X1357308Y628583D01*
X1357017Y628833D01*
X1356850Y629208D01*
X1356808Y629625D01*
X1356892Y630167D01*
X1357017Y630458D01*
X1357225Y630750D01*
X1357517Y630958D01*
X1357808Y631000D01*
X1358100Y630917D01*
X1358308Y630708D01*
G01X1359992Y628792D02*
X1360283Y628583D01*
X1360617Y628500D01*
X1360950Y628583D01*
X1361242Y628833D01*
X1361450Y629208D01*
X1361533Y629583D01*
Y630042D01*
X1361450Y630417D01*
X1361242Y630750D01*
X1360992Y630917D01*
X1360700Y631000D01*
X1360367Y630917D01*
X1360117Y630750D01*
X1359950Y630500D01*
X1359867Y630167D01*
X1359950Y629875D01*
X1360158Y629583D01*
X1360408Y629417D01*
X1360700Y629375D01*
X1361033Y629458D01*
X1361283Y629667D01*
X1361533Y630042D01*
G01X1334134Y628412D02*
Y630912D01*
X1335175D01*
X1335509Y630787D01*
X1335717Y630620D01*
X1335800Y630287D01*
X1335717Y629954D01*
X1335467Y629745D01*
X1335175Y629620D01*
X1334134D01*
G01X1335175D02*
X1335800Y628412D01*
G01X1337275Y630495D02*
X1337525Y630745D01*
X1337817Y630870D01*
X1338150Y630912D01*
X1338567Y630829D01*
X1338859Y630620D01*
X1338942Y630370D01*
X1338900Y630120D01*
X1338734Y629912D01*
X1337900Y629495D01*
X1337525Y629204D01*
X1337275Y628787D01*
X1337192Y628412D01*
X1338942D01*
G01X1340375Y630495D02*
X1340625Y630745D01*
X1340917Y630870D01*
X1341250Y630912D01*
X1341667Y630829D01*
X1341959Y630620D01*
X1342042Y630370D01*
X1342000Y630120D01*
X1341834Y629912D01*
X1341000Y629495D01*
X1340625Y629204D01*
X1340375Y628787D01*
X1340292Y628412D01*
X1342042D01*
G01X1344267D02*
X1344559Y628454D01*
X1344892Y628579D01*
X1345100Y628787D01*
X1345184Y629079D01*
X1345100Y629370D01*
X1344850Y629620D01*
X1344475Y629745D01*
X1344059D01*
X1343809Y629829D01*
X1343600Y630037D01*
X1343517Y630329D01*
X1343642Y630620D01*
X1343934Y630829D01*
X1344267Y630912D01*
X1344600Y630829D01*
X1344892Y630620D01*
X1345017Y630329D01*
X1344934Y630037D01*
X1344725Y629829D01*
X1344475Y629745D01*
X1344059D01*
X1343684Y629620D01*
X1343434Y629370D01*
X1343350Y629079D01*
X1343434Y628787D01*
X1343642Y628579D01*
X1343975Y628454D01*
X1344267Y628412D01*
G01X1344317Y617412D02*
Y621412D01*
X1336917D01*
G01Y625912D02*
Y621912D01*
X1344317D01*
G01X1334134Y632912D02*
Y635412D01*
X1335175D01*
X1335509Y635287D01*
X1335717Y635120D01*
X1335800Y634787D01*
X1335717Y634454D01*
X1335467Y634245D01*
X1335175Y634120D01*
X1334134D01*
G01X1335175D02*
X1335800Y632912D01*
G01X1337150Y633287D02*
X1337400Y633079D01*
X1337692Y632954D01*
X1338067Y632912D01*
X1338442Y632995D01*
X1338734Y633162D01*
X1338942Y633454D01*
X1338984Y633787D01*
X1338900Y634120D01*
X1338692Y634329D01*
X1338400Y634495D01*
X1338109Y634537D01*
X1337817Y634495D01*
X1337442Y634329D01*
X1337567Y635412D01*
X1338692D01*
G01X1341667Y632912D02*
Y635412D01*
X1340125Y633620D01*
X1342209D01*
G01X1344184Y632912D02*
X1344267Y633454D01*
X1344392Y633912D01*
X1344559Y634329D01*
X1344767Y634787D01*
X1345100Y635412D01*
X1343434D01*
G01X1347825Y635679D02*
X1347700Y635429D01*
X1347617Y635137D01*
Y634804D01*
X1347742Y634429D01*
X1347950Y634137D01*
X1348200Y633929D01*
X1348617Y633762D01*
X1348992Y633720D01*
X1349367Y633804D01*
X1349617Y633929D01*
X1349867Y634179D01*
X1350034Y634470D01*
X1350117Y634762D01*
Y635054D01*
X1350034Y635345D01*
X1349909Y635595D01*
X1349742Y635804D01*
G01X1350117Y637862D02*
X1347617D01*
X1348117Y637362D01*
G01X1350117D02*
Y638362D01*
G01X1349075Y640170D02*
X1348784Y640462D01*
X1348617Y640712D01*
X1348534Y641045D01*
X1348617Y641337D01*
X1348784Y641545D01*
X1349034Y641712D01*
X1349325Y641754D01*
X1349575Y641712D01*
X1349825Y641545D01*
X1350034Y641295D01*
X1350117Y641004D01*
X1350034Y640670D01*
X1349784Y640379D01*
X1349409Y640212D01*
X1348992Y640170D01*
X1348450Y640254D01*
X1348159Y640379D01*
X1347867Y640587D01*
X1347659Y640879D01*
X1347617Y641170D01*
X1347700Y641462D01*
X1347909Y641670D01*
G01X1349617Y643145D02*
X1349909Y643395D01*
X1350075Y643729D01*
X1350117Y644104D01*
X1350075Y644437D01*
X1349867Y644770D01*
X1349617Y644979D01*
X1349367Y645020D01*
X1349075Y644937D01*
X1348867Y644645D01*
X1348784Y644354D01*
Y643979D01*
G01Y644354D02*
X1348659Y644604D01*
X1348450Y644812D01*
X1348200Y644895D01*
X1347950Y644812D01*
X1347742Y644604D01*
X1347617Y644229D01*
X1347659Y643854D01*
X1347825Y643479D01*
G01X1340500Y650483D02*
X1342292D01*
X1342667Y650650D01*
X1342917Y650983D01*
X1343000Y651400D01*
X1342917Y651817D01*
X1342667Y652150D01*
X1342292Y652317D01*
X1340500D01*
G01X1340917Y653708D02*
X1340667Y653958D01*
X1340542Y654250D01*
X1340500Y654583D01*
X1340583Y655000D01*
X1340792Y655292D01*
X1341042Y655375D01*
X1341292Y655333D01*
X1341500Y655167D01*
X1341917Y654333D01*
X1342208Y653958D01*
X1342625Y653708D01*
X1343000Y653625D01*
Y655375D01*
G01Y657600D02*
X1342958Y657892D01*
X1342833Y658225D01*
X1342625Y658433D01*
X1342333Y658517D01*
X1342042Y658433D01*
X1341792Y658183D01*
X1341667Y657808D01*
Y657392D01*
X1341583Y657142D01*
X1341375Y656933D01*
X1341083Y656850D01*
X1340792Y656975D01*
X1340583Y657267D01*
X1340500Y657600D01*
X1340583Y657933D01*
X1340792Y658225D01*
X1341083Y658350D01*
X1341375Y658267D01*
X1341583Y658058D01*
X1341667Y657808D01*
Y657392D01*
X1341792Y657017D01*
X1342042Y656767D01*
X1342333Y656683D01*
X1342625Y656767D01*
X1342833Y656975D01*
X1342958Y657308D01*
X1343000Y657600D01*
G01X1335668Y651784D02*
X1337168Y650284D01*
G01X1335668Y651784D02*
X1337168Y653284D01*
G01X1338468Y680301D02*
X1335968D01*
Y681342D01*
X1336093Y681676D01*
X1336260Y681884D01*
X1336593Y681967D01*
X1336926Y681884D01*
X1337135Y681634D01*
X1337260Y681342D01*
Y680301D01*
G01Y681342D02*
X1338468Y681967D01*
G01X1336385Y683442D02*
X1336135Y683692D01*
X1336010Y683984D01*
X1335968Y684317D01*
X1336051Y684734D01*
X1336260Y685026D01*
X1336510Y685109D01*
X1336760Y685067D01*
X1336968Y684901D01*
X1337385Y684067D01*
X1337676Y683692D01*
X1338093Y683442D01*
X1338468Y683359D01*
Y685109D01*
G01Y687251D02*
X1337926Y687334D01*
X1337468Y687459D01*
X1337051Y687626D01*
X1336593Y687834D01*
X1335968Y688167D01*
Y686501D01*
G01X1338468Y690351D02*
X1337926Y690434D01*
X1337468Y690559D01*
X1337051Y690726D01*
X1336593Y690934D01*
X1335968Y691267D01*
Y689601D01*
G01X1335468Y671084D02*
X1339468D01*
Y678484D01*
G01X1334468Y680301D02*
X1331968D01*
Y681342D01*
X1332093Y681676D01*
X1332260Y681884D01*
X1332593Y681967D01*
X1332926Y681884D01*
X1333135Y681634D01*
X1333260Y681342D01*
Y680301D01*
G01Y681342D02*
X1334468Y681967D01*
G01X1332385Y683442D02*
X1332135Y683692D01*
X1332010Y683984D01*
X1331968Y684317D01*
X1332051Y684734D01*
X1332260Y685026D01*
X1332510Y685109D01*
X1332760Y685067D01*
X1332968Y684901D01*
X1333385Y684067D01*
X1333676Y683692D01*
X1334093Y683442D01*
X1334468Y683359D01*
Y685109D01*
G01Y687251D02*
X1333926Y687334D01*
X1333468Y687459D01*
X1333051Y687626D01*
X1332593Y687834D01*
X1331968Y688167D01*
Y686501D01*
G01X1334468Y690434D02*
X1334426Y690726D01*
X1334301Y691059D01*
X1334093Y691267D01*
X1333801Y691351D01*
X1333510Y691267D01*
X1333260Y691017D01*
X1333135Y690642D01*
Y690226D01*
X1333051Y689976D01*
X1332843Y689767D01*
X1332551Y689684D01*
X1332260Y689809D01*
X1332051Y690101D01*
X1331968Y690434D01*
X1332051Y690767D01*
X1332260Y691059D01*
X1332551Y691184D01*
X1332843Y691101D01*
X1333051Y690892D01*
X1333135Y690642D01*
Y690226D01*
X1333260Y689851D01*
X1333510Y689601D01*
X1333801Y689517D01*
X1334093Y689601D01*
X1334301Y689809D01*
X1334426Y690142D01*
X1334468Y690434D01*
G01X1331468Y671084D02*
X1335468D01*
Y678484D01*
G01X1341000Y827517D02*
X1338500D01*
Y828558D01*
X1338625Y828892D01*
X1338792Y829100D01*
X1339125Y829183D01*
X1339458Y829100D01*
X1339667Y828850D01*
X1339792Y828558D01*
Y827517D01*
G01Y828558D02*
X1341000Y829183D01*
G01X1338917Y830658D02*
X1338667Y830908D01*
X1338542Y831200D01*
X1338500Y831533D01*
X1338583Y831950D01*
X1338792Y832242D01*
X1339042Y832325D01*
X1339292Y832283D01*
X1339500Y832117D01*
X1339917Y831283D01*
X1340208Y830908D01*
X1340625Y830658D01*
X1341000Y830575D01*
Y832325D01*
G01X1338500Y834550D02*
X1338583Y834217D01*
X1338792Y833967D01*
X1339042Y833800D01*
X1339375Y833675D01*
X1339750Y833633D01*
X1340125Y833675D01*
X1340458Y833800D01*
X1340708Y833967D01*
X1340917Y834217D01*
X1341000Y834550D01*
X1340917Y834883D01*
X1340708Y835133D01*
X1340458Y835300D01*
X1340125Y835425D01*
X1339750Y835467D01*
X1339375Y835425D01*
X1339042Y835300D01*
X1338792Y835133D01*
X1338583Y834883D01*
X1338500Y834550D01*
G01X1341000Y837650D02*
X1340958Y837942D01*
X1340833Y838275D01*
X1340625Y838483D01*
X1340333Y838567D01*
X1340042Y838483D01*
X1339792Y838233D01*
X1339667Y837858D01*
Y837442D01*
X1339583Y837192D01*
X1339375Y836983D01*
X1339083Y836900D01*
X1338792Y837025D01*
X1338583Y837317D01*
X1338500Y837650D01*
X1338583Y837983D01*
X1338792Y838275D01*
X1339083Y838400D01*
X1339375Y838317D01*
X1339583Y838108D01*
X1339667Y837858D01*
Y837442D01*
X1339792Y837067D01*
X1340042Y836817D01*
X1340333Y836733D01*
X1340625Y836817D01*
X1340833Y837025D01*
X1340958Y837358D01*
X1341000Y837650D01*
G01X1345500Y827517D02*
X1343000D01*
Y828558D01*
X1343125Y828892D01*
X1343292Y829100D01*
X1343625Y829183D01*
X1343958Y829100D01*
X1344167Y828850D01*
X1344292Y828558D01*
Y827517D01*
G01Y828558D02*
X1345500Y829183D01*
G01X1343417Y830658D02*
X1343167Y830908D01*
X1343042Y831200D01*
X1343000Y831533D01*
X1343083Y831950D01*
X1343292Y832242D01*
X1343542Y832325D01*
X1343792Y832283D01*
X1344000Y832117D01*
X1344417Y831283D01*
X1344708Y830908D01*
X1345125Y830658D01*
X1345500Y830575D01*
Y832325D01*
G01Y834550D02*
X1343000D01*
X1343500Y834050D01*
G01X1345500D02*
Y835050D01*
G01X1343417Y836858D02*
X1343167Y837108D01*
X1343042Y837400D01*
X1343000Y837733D01*
X1343083Y838150D01*
X1343292Y838442D01*
X1343542Y838525D01*
X1343792Y838483D01*
X1344000Y838317D01*
X1344417Y837483D01*
X1344708Y837108D01*
X1345125Y836858D01*
X1345500Y836775D01*
Y838525D01*
G01X1336500Y825967D02*
X1334000D01*
Y827008D01*
X1334125Y827342D01*
X1334292Y827550D01*
X1334625Y827633D01*
X1334958Y827550D01*
X1335167Y827300D01*
X1335292Y827008D01*
Y825967D01*
G01Y827008D02*
X1336500Y827633D01*
G01X1336125Y828983D02*
X1336333Y829233D01*
X1336458Y829525D01*
X1336500Y829900D01*
X1336417Y830275D01*
X1336250Y830567D01*
X1335958Y830775D01*
X1335625Y830817D01*
X1335292Y830733D01*
X1335083Y830525D01*
X1334917Y830233D01*
X1334875Y829942D01*
X1334917Y829650D01*
X1335083Y829275D01*
X1334000Y829400D01*
Y830525D01*
G01X1336000Y832083D02*
X1336292Y832333D01*
X1336458Y832667D01*
X1336500Y833042D01*
X1336458Y833375D01*
X1336250Y833708D01*
X1336000Y833917D01*
X1335750Y833958D01*
X1335458Y833875D01*
X1335250Y833583D01*
X1335167Y833292D01*
Y832917D01*
G01Y833292D02*
X1335042Y833542D01*
X1334833Y833750D01*
X1334583Y833833D01*
X1334333Y833750D01*
X1334125Y833542D01*
X1334000Y833167D01*
X1334042Y832792D01*
X1334208Y832417D01*
G01X1334000Y836100D02*
X1334083Y835767D01*
X1334292Y835517D01*
X1334542Y835350D01*
X1334875Y835225D01*
X1335250Y835183D01*
X1335625Y835225D01*
X1335958Y835350D01*
X1336208Y835517D01*
X1336417Y835767D01*
X1336500Y836100D01*
X1336417Y836433D01*
X1336208Y836683D01*
X1335958Y836850D01*
X1335625Y836975D01*
X1335250Y837017D01*
X1334875Y836975D01*
X1334542Y836850D01*
X1334292Y836683D01*
X1334083Y836433D01*
X1334000Y836100D01*
G01X1336125Y838283D02*
X1336333Y838533D01*
X1336458Y838825D01*
X1336500Y839200D01*
X1336417Y839575D01*
X1336250Y839867D01*
X1335958Y840075D01*
X1335625Y840117D01*
X1335292Y840033D01*
X1335083Y839825D01*
X1334917Y839533D01*
X1334875Y839242D01*
X1334917Y838950D01*
X1335083Y838575D01*
X1334000Y838700D01*
Y839825D01*
G01X1344500Y851017D02*
X1342000D01*
Y852058D01*
X1342125Y852392D01*
X1342292Y852600D01*
X1342625Y852683D01*
X1342958Y852600D01*
X1343167Y852350D01*
X1343292Y852058D01*
Y851017D01*
G01Y852058D02*
X1344500Y852683D01*
G01Y854950D02*
X1342000D01*
X1342500Y854450D01*
G01X1344500D02*
Y855450D01*
G01Y858050D02*
X1344458Y858342D01*
X1344333Y858675D01*
X1344125Y858883D01*
X1343833Y858967D01*
X1343542Y858883D01*
X1343292Y858633D01*
X1343167Y858258D01*
Y857842D01*
X1343083Y857592D01*
X1342875Y857383D01*
X1342583Y857300D01*
X1342292Y857425D01*
X1342083Y857717D01*
X1342000Y858050D01*
X1342083Y858383D01*
X1342292Y858675D01*
X1342583Y858800D01*
X1342875Y858717D01*
X1343083Y858508D01*
X1343167Y858258D01*
Y857842D01*
X1343292Y857467D01*
X1343542Y857217D01*
X1343833Y857133D01*
X1344125Y857217D01*
X1344333Y857425D01*
X1344458Y857758D01*
X1344500Y858050D01*
G01X1344000Y860233D02*
X1344292Y860483D01*
X1344458Y860817D01*
X1344500Y861192D01*
X1344458Y861525D01*
X1344250Y861858D01*
X1344000Y862067D01*
X1343750Y862108D01*
X1343458Y862025D01*
X1343250Y861733D01*
X1343167Y861442D01*
Y861067D01*
G01Y861442D02*
X1343042Y861692D01*
X1342833Y861900D01*
X1342583Y861983D01*
X1342333Y861900D01*
X1342125Y861692D01*
X1342000Y861317D01*
X1342042Y860942D01*
X1342208Y860567D01*
G01X1336000Y849467D02*
X1333500D01*
Y850508D01*
X1333625Y850842D01*
X1333792Y851050D01*
X1334125Y851133D01*
X1334458Y851050D01*
X1334667Y850800D01*
X1334792Y850508D01*
Y849467D01*
G01Y850508D02*
X1336000Y851133D01*
G01X1335625Y852483D02*
X1335833Y852733D01*
X1335958Y853025D01*
X1336000Y853400D01*
X1335917Y853775D01*
X1335750Y854067D01*
X1335458Y854275D01*
X1335125Y854317D01*
X1334792Y854233D01*
X1334583Y854025D01*
X1334417Y853733D01*
X1334375Y853442D01*
X1334417Y853150D01*
X1334583Y852775D01*
X1333500Y852900D01*
Y854025D01*
G01X1335500Y855583D02*
X1335792Y855833D01*
X1335958Y856167D01*
X1336000Y856542D01*
X1335958Y856875D01*
X1335750Y857208D01*
X1335500Y857417D01*
X1335250Y857458D01*
X1334958Y857375D01*
X1334750Y857083D01*
X1334667Y856792D01*
Y856417D01*
G01Y856792D02*
X1334542Y857042D01*
X1334333Y857250D01*
X1334083Y857333D01*
X1333833Y857250D01*
X1333625Y857042D01*
X1333500Y856667D01*
X1333542Y856292D01*
X1333708Y855917D01*
G01X1333500Y859600D02*
X1333583Y859267D01*
X1333792Y859017D01*
X1334042Y858850D01*
X1334375Y858725D01*
X1334750Y858683D01*
X1335125Y858725D01*
X1335458Y858850D01*
X1335708Y859017D01*
X1335917Y859267D01*
X1336000Y859600D01*
X1335917Y859933D01*
X1335708Y860183D01*
X1335458Y860350D01*
X1335125Y860475D01*
X1334750Y860517D01*
X1334375Y860475D01*
X1334042Y860350D01*
X1333792Y860183D01*
X1333583Y859933D01*
X1333500Y859600D01*
G01X1333917Y861908D02*
X1333667Y862158D01*
X1333542Y862450D01*
X1333500Y862783D01*
X1333583Y863200D01*
X1333792Y863492D01*
X1334042Y863575D01*
X1334292Y863533D01*
X1334500Y863367D01*
X1334917Y862533D01*
X1335208Y862158D01*
X1335625Y861908D01*
X1336000Y861825D01*
Y863575D01*
G01X1340500Y849467D02*
X1338000D01*
Y850508D01*
X1338125Y850842D01*
X1338292Y851050D01*
X1338625Y851133D01*
X1338958Y851050D01*
X1339167Y850800D01*
X1339292Y850508D01*
Y849467D01*
G01Y850508D02*
X1340500Y851133D01*
G01X1340125Y852483D02*
X1340333Y852733D01*
X1340458Y853025D01*
X1340500Y853400D01*
X1340417Y853775D01*
X1340250Y854067D01*
X1339958Y854275D01*
X1339625Y854317D01*
X1339292Y854233D01*
X1339083Y854025D01*
X1338917Y853733D01*
X1338875Y853442D01*
X1338917Y853150D01*
X1339083Y852775D01*
X1338000Y852900D01*
Y854025D01*
G01X1340000Y855583D02*
X1340292Y855833D01*
X1340458Y856167D01*
X1340500Y856542D01*
X1340458Y856875D01*
X1340250Y857208D01*
X1340000Y857417D01*
X1339750Y857458D01*
X1339458Y857375D01*
X1339250Y857083D01*
X1339167Y856792D01*
Y856417D01*
G01Y856792D02*
X1339042Y857042D01*
X1338833Y857250D01*
X1338583Y857333D01*
X1338333Y857250D01*
X1338125Y857042D01*
X1338000Y856667D01*
X1338042Y856292D01*
X1338208Y855917D01*
G01X1338000Y859600D02*
X1338083Y859267D01*
X1338292Y859017D01*
X1338542Y858850D01*
X1338875Y858725D01*
X1339250Y858683D01*
X1339625Y858725D01*
X1339958Y858850D01*
X1340208Y859017D01*
X1340417Y859267D01*
X1340500Y859600D01*
X1340417Y859933D01*
X1340208Y860183D01*
X1339958Y860350D01*
X1339625Y860475D01*
X1339250Y860517D01*
X1338875Y860475D01*
X1338542Y860350D01*
X1338292Y860183D01*
X1338083Y859933D01*
X1338000Y859600D01*
G01X1340000Y861783D02*
X1340292Y862033D01*
X1340458Y862367D01*
X1340500Y862742D01*
X1340458Y863075D01*
X1340250Y863408D01*
X1340000Y863617D01*
X1339750Y863658D01*
X1339458Y863575D01*
X1339250Y863283D01*
X1339167Y862992D01*
Y862617D01*
G01Y862992D02*
X1339042Y863242D01*
X1338833Y863450D01*
X1338583Y863533D01*
X1338333Y863450D01*
X1338125Y863242D01*
X1338000Y862867D01*
X1338042Y862492D01*
X1338208Y862117D01*
G01X1357446Y-4509D02*
Y-2509D01*
G01X1366846Y-4509D02*
Y-2509D01*
X1357446D01*
G01X1396462Y64381D02*
X1363262D01*
Y37981D01*
X1396462D01*
Y64381D01*
G01X1349025Y52833D02*
X1349358Y52625D01*
X1349733Y52500D01*
X1350067D01*
X1350400Y52625D01*
X1350650Y52833D01*
X1350775Y53125D01*
X1350692Y53417D01*
X1350483Y53667D01*
X1350108Y53833D01*
X1349608Y53917D01*
X1349317Y54083D01*
X1349192Y54375D01*
X1349275Y54667D01*
X1349483Y54875D01*
X1349775Y55000D01*
X1350067D01*
X1350358Y54917D01*
X1350608Y54708D01*
G01X1351750Y55000D02*
X1352333Y52500D01*
X1353000Y55000D01*
X1353667Y52500D01*
X1354250Y55000D01*
G01X1356100Y52500D02*
Y55000D01*
X1355600Y54500D01*
G01Y52500D02*
X1356600D01*
G01X1354000Y83700D02*
X1350000D01*
Y76300D01*
G01X1351525Y89333D02*
X1351858Y89125D01*
X1352233Y89000D01*
X1352567D01*
X1352900Y89125D01*
X1353150Y89333D01*
X1353275Y89625D01*
X1353192Y89917D01*
X1352983Y90167D01*
X1352608Y90333D01*
X1352108Y90417D01*
X1351817Y90583D01*
X1351692Y90875D01*
X1351775Y91167D01*
X1351983Y91375D01*
X1352275Y91500D01*
X1352567D01*
X1352858Y91417D01*
X1353108Y91208D01*
G01X1354250Y91500D02*
X1354833Y89000D01*
X1355500Y91500D01*
X1356167Y89000D01*
X1356750Y91500D01*
G01X1357808Y91083D02*
X1358058Y91333D01*
X1358350Y91458D01*
X1358683Y91500D01*
X1359100Y91417D01*
X1359392Y91208D01*
X1359475Y90958D01*
X1359433Y90708D01*
X1359267Y90500D01*
X1358433Y90083D01*
X1358058Y89792D01*
X1357808Y89375D01*
X1357725Y89000D01*
X1359475D01*
G01X1396462Y100602D02*
X1363262D01*
Y74202D01*
X1396462D01*
Y100602D01*
G01X1364200Y104000D02*
Y108000D01*
X1356800D01*
G01X1360500Y109000D02*
Y123000D01*
G01X1364500Y112017D02*
X1362000D01*
Y113058D01*
X1362125Y113392D01*
X1362292Y113600D01*
X1362625Y113683D01*
X1362958Y113600D01*
X1363167Y113350D01*
X1363292Y113058D01*
Y112017D01*
G01Y113058D02*
X1364500Y113683D01*
G01Y116450D02*
X1362000D01*
X1363792Y114908D01*
Y116992D01*
G01X1364125Y118133D02*
X1364333Y118383D01*
X1364458Y118675D01*
X1364500Y119050D01*
X1364417Y119425D01*
X1364250Y119717D01*
X1363958Y119925D01*
X1363625Y119967D01*
X1363292Y119883D01*
X1363083Y119675D01*
X1362917Y119383D01*
X1362875Y119092D01*
X1362917Y118800D01*
X1363083Y118425D01*
X1362000Y118550D01*
Y119675D01*
G01X1364500Y122650D02*
X1362000D01*
X1363792Y121108D01*
Y123192D01*
G01X1353400Y125500D02*
X1353067Y125542D01*
X1352775Y125708D01*
X1352525Y125958D01*
X1352358Y126250D01*
X1352275Y126583D01*
Y126917D01*
X1352358Y127250D01*
X1352525Y127542D01*
X1352775Y127792D01*
X1353067Y127958D01*
X1353400Y128000D01*
X1353733Y127958D01*
X1354025Y127792D01*
X1354275Y127542D01*
X1354442Y127250D01*
X1354525Y126917D01*
Y126583D01*
X1354442Y126250D01*
X1354275Y125958D01*
X1354025Y125708D01*
X1353733Y125542D01*
X1353400Y125500D01*
G01X1353733Y126167D02*
X1354233Y125500D01*
G01X1356500D02*
Y128000D01*
X1356000Y127500D01*
G01Y125500D02*
X1357000D01*
G01X1358892Y125792D02*
X1359183Y125583D01*
X1359517Y125500D01*
X1359850Y125583D01*
X1360142Y125833D01*
X1360350Y126208D01*
X1360433Y126583D01*
Y127042D01*
X1360350Y127417D01*
X1360142Y127750D01*
X1359892Y127917D01*
X1359600Y128000D01*
X1359267Y127917D01*
X1359017Y127750D01*
X1358850Y127500D01*
X1358767Y127167D01*
X1358850Y126875D01*
X1359058Y126583D01*
X1359308Y126417D01*
X1359600Y126375D01*
X1359933Y126458D01*
X1360183Y126667D01*
X1360433Y127042D01*
G01X1358700Y367500D02*
Y375500D01*
G01X1364200Y367500D02*
X1358700D01*
G01Y366500D02*
X1364200D01*
G01X1358700Y358500D02*
Y366500D01*
G01X1364200Y358500D02*
X1358700D01*
G01Y375500D02*
X1364200D01*
G01X1363500Y405017D02*
X1361000D01*
Y406017D01*
X1361125Y406350D01*
X1361417Y406600D01*
X1361750Y406683D01*
X1362083Y406600D01*
X1362333Y406392D01*
X1362458Y406017D01*
Y405017D01*
G01X1361208Y409867D02*
X1361083Y409617D01*
X1361000Y409325D01*
Y408992D01*
X1361125Y408617D01*
X1361333Y408325D01*
X1361583Y408117D01*
X1362000Y407950D01*
X1362375Y407908D01*
X1362750Y407992D01*
X1363000Y408117D01*
X1363250Y408367D01*
X1363417Y408658D01*
X1363500Y408950D01*
Y409242D01*
X1363417Y409533D01*
X1363292Y409783D01*
X1363125Y409992D01*
G01X1363500Y412050D02*
X1361000D01*
X1361500Y411550D01*
G01X1363500D02*
Y412550D01*
G01X1361000Y415150D02*
X1361083Y414817D01*
X1361292Y414567D01*
X1361542Y414400D01*
X1361875Y414275D01*
X1362250Y414233D01*
X1362625Y414275D01*
X1362958Y414400D01*
X1363208Y414567D01*
X1363417Y414817D01*
X1363500Y415150D01*
X1363417Y415483D01*
X1363208Y415733D01*
X1362958Y415900D01*
X1362625Y416025D01*
X1362250Y416067D01*
X1361875Y416025D01*
X1361542Y415900D01*
X1361292Y415733D01*
X1361083Y415483D01*
X1361000Y415150D01*
G01X1353000Y418300D02*
X1357000D01*
Y425700D01*
G01X1350906Y437484D02*
X1352906D01*
G01X1352300Y450000D02*
Y446000D01*
X1359700D01*
G01Y454000D02*
Y458000D01*
X1352300D01*
G01X1359000Y483067D02*
X1356500D01*
Y484067D01*
X1356625Y484400D01*
X1356917Y484650D01*
X1357250Y484733D01*
X1357583Y484650D01*
X1357833Y484442D01*
X1357958Y484067D01*
Y483067D01*
G01X1359000Y486167D02*
X1356500D01*
Y487208D01*
X1356625Y487542D01*
X1356792Y487750D01*
X1357125Y487833D01*
X1357458Y487750D01*
X1357667Y487500D01*
X1357792Y487208D01*
Y486167D01*
G01Y487208D02*
X1359000Y487833D01*
G01X1358708Y489392D02*
X1358917Y489683D01*
X1359000Y490017D01*
X1358917Y490350D01*
X1358667Y490642D01*
X1358292Y490850D01*
X1357917Y490933D01*
X1357458D01*
X1357083Y490850D01*
X1356750Y490642D01*
X1356583Y490392D01*
X1356500Y490100D01*
X1356583Y489767D01*
X1356750Y489517D01*
X1357000Y489350D01*
X1357333Y489267D01*
X1357625Y489350D01*
X1357917Y489558D01*
X1358083Y489808D01*
X1358125Y490100D01*
X1358042Y490433D01*
X1357833Y490683D01*
X1357458Y490933D01*
G01X1352517Y470500D02*
Y473000D01*
X1353517D01*
X1353850Y472875D01*
X1354100Y472583D01*
X1354183Y472250D01*
X1354100Y471917D01*
X1353892Y471667D01*
X1353517Y471542D01*
X1352517D01*
G01X1355617Y470500D02*
Y473000D01*
X1356658D01*
X1356992Y472875D01*
X1357200Y472708D01*
X1357283Y472375D01*
X1357200Y472042D01*
X1356950Y471833D01*
X1356658Y471708D01*
X1355617D01*
G01X1356658D02*
X1357283Y470500D01*
G01X1359550D02*
Y473000D01*
X1359050Y472500D01*
G01Y470500D02*
X1360050D01*
G01X1362650D02*
Y473000D01*
X1362150Y472500D01*
G01Y470500D02*
X1363150D01*
G01X1352517Y478500D02*
Y481000D01*
X1353517D01*
X1353850Y480875D01*
X1354100Y480583D01*
X1354183Y480250D01*
X1354100Y479917D01*
X1353892Y479667D01*
X1353517Y479542D01*
X1352517D01*
G01X1355617Y478500D02*
Y481000D01*
X1356658D01*
X1356992Y480875D01*
X1357200Y480708D01*
X1357283Y480375D01*
X1357200Y480042D01*
X1356950Y479833D01*
X1356658Y479708D01*
X1355617D01*
G01X1356658D02*
X1357283Y478500D01*
G01X1359550D02*
Y481000D01*
X1359050Y480500D01*
G01Y478500D02*
X1360050D01*
G01X1362650Y481000D02*
X1362317Y480917D01*
X1362067Y480708D01*
X1361900Y480458D01*
X1361775Y480125D01*
X1361733Y479750D01*
X1361775Y479375D01*
X1361900Y479042D01*
X1362067Y478792D01*
X1362317Y478583D01*
X1362650Y478500D01*
X1362983Y478583D01*
X1363233Y478792D01*
X1363400Y479042D01*
X1363525Y479375D01*
X1363567Y479750D01*
X1363525Y480125D01*
X1363400Y480458D01*
X1363233Y480708D01*
X1362983Y480917D01*
X1362650Y481000D01*
G01X1354067Y474500D02*
Y477000D01*
X1355067D01*
X1355400Y476875D01*
X1355650Y476583D01*
X1355733Y476250D01*
X1355650Y475917D01*
X1355442Y475667D01*
X1355067Y475542D01*
X1354067D01*
G01X1358917Y476792D02*
X1358667Y476917D01*
X1358375Y477000D01*
X1358042D01*
X1357667Y476875D01*
X1357375Y476667D01*
X1357167Y476417D01*
X1357000Y476000D01*
X1356958Y475625D01*
X1357042Y475250D01*
X1357167Y475000D01*
X1357417Y474750D01*
X1357708Y474583D01*
X1358000Y474500D01*
X1358292D01*
X1358583Y474583D01*
X1358833Y474708D01*
X1359042Y474875D01*
G01X1360392Y474792D02*
X1360683Y474583D01*
X1361017Y474500D01*
X1361350Y474583D01*
X1361642Y474833D01*
X1361850Y475208D01*
X1361933Y475583D01*
Y476042D01*
X1361850Y476417D01*
X1361642Y476750D01*
X1361392Y476917D01*
X1361100Y477000D01*
X1360767Y476917D01*
X1360517Y476750D01*
X1360350Y476500D01*
X1360267Y476167D01*
X1360350Y475875D01*
X1360558Y475583D01*
X1360808Y475417D01*
X1361100Y475375D01*
X1361433Y475458D01*
X1361683Y475667D01*
X1361933Y476042D01*
G01X1355025Y538500D02*
X1356775Y541000D01*
G01X1355025D02*
X1356775Y538500D01*
G01X1359000D02*
Y541000D01*
X1358500Y540500D01*
G01Y538500D02*
X1359500D01*
G01X1362100D02*
Y541000D01*
X1361600Y540500D01*
G01Y538500D02*
X1362600D01*
G01X1353825Y546629D02*
X1353700Y546379D01*
X1353617Y546087D01*
Y545754D01*
X1353742Y545379D01*
X1353950Y545087D01*
X1354200Y544879D01*
X1354617Y544712D01*
X1354992Y544670D01*
X1355367Y544754D01*
X1355617Y544879D01*
X1355867Y545129D01*
X1356034Y545420D01*
X1356117Y545712D01*
Y546004D01*
X1356034Y546295D01*
X1355909Y546545D01*
X1355742Y546754D01*
G01X1356117Y548812D02*
X1356075Y549104D01*
X1355950Y549437D01*
X1355742Y549645D01*
X1355450Y549729D01*
X1355159Y549645D01*
X1354909Y549395D01*
X1354784Y549020D01*
Y548604D01*
X1354700Y548354D01*
X1354492Y548145D01*
X1354200Y548062D01*
X1353909Y548187D01*
X1353700Y548479D01*
X1353617Y548812D01*
X1353700Y549145D01*
X1353909Y549437D01*
X1354200Y549562D01*
X1354492Y549479D01*
X1354700Y549270D01*
X1354784Y549020D01*
Y548604D01*
X1354909Y548229D01*
X1355159Y547979D01*
X1355450Y547895D01*
X1355742Y547979D01*
X1355950Y548187D01*
X1356075Y548520D01*
X1356117Y548812D01*
G01X1353617Y551912D02*
X1353700Y551579D01*
X1353909Y551329D01*
X1354159Y551162D01*
X1354492Y551037D01*
X1354867Y550995D01*
X1355242Y551037D01*
X1355575Y551162D01*
X1355825Y551329D01*
X1356034Y551579D01*
X1356117Y551912D01*
X1356034Y552245D01*
X1355825Y552495D01*
X1355575Y552662D01*
X1355242Y552787D01*
X1354867Y552829D01*
X1354492Y552787D01*
X1354159Y552662D01*
X1353909Y552495D01*
X1353700Y552245D01*
X1353617Y551912D01*
G01X1355825Y554304D02*
X1356034Y554595D01*
X1356117Y554929D01*
X1356034Y555262D01*
X1355784Y555554D01*
X1355409Y555762D01*
X1355034Y555845D01*
X1354575D01*
X1354200Y555762D01*
X1353867Y555554D01*
X1353700Y555304D01*
X1353617Y555012D01*
X1353700Y554679D01*
X1353867Y554429D01*
X1354117Y554262D01*
X1354450Y554179D01*
X1354742Y554262D01*
X1355034Y554470D01*
X1355200Y554720D01*
X1355242Y555012D01*
X1355159Y555345D01*
X1354950Y555595D01*
X1354575Y555845D01*
G01X1353617Y558112D02*
X1353700Y557779D01*
X1353909Y557529D01*
X1354159Y557362D01*
X1354492Y557237D01*
X1354867Y557195D01*
X1355242Y557237D01*
X1355575Y557362D01*
X1355825Y557529D01*
X1356034Y557779D01*
X1356117Y558112D01*
X1356034Y558445D01*
X1355825Y558695D01*
X1355575Y558862D01*
X1355242Y558987D01*
X1354867Y559029D01*
X1354492Y558987D01*
X1354159Y558862D01*
X1353909Y558695D01*
X1353700Y558445D01*
X1353617Y558112D01*
G01X1364617Y546429D02*
X1362117D01*
Y547470D01*
X1362242Y547804D01*
X1362409Y548012D01*
X1362742Y548095D01*
X1363075Y548012D01*
X1363284Y547762D01*
X1363409Y547470D01*
Y546429D01*
G01Y547470D02*
X1364617Y548095D01*
G01Y550279D02*
X1364075Y550362D01*
X1363617Y550487D01*
X1363200Y550654D01*
X1362742Y550862D01*
X1362117Y551195D01*
Y549529D01*
G01Y553462D02*
X1362200Y553129D01*
X1362409Y552879D01*
X1362659Y552712D01*
X1362992Y552587D01*
X1363367Y552545D01*
X1363742Y552587D01*
X1364075Y552712D01*
X1364325Y552879D01*
X1364534Y553129D01*
X1364617Y553462D01*
X1364534Y553795D01*
X1364325Y554045D01*
X1364075Y554212D01*
X1363742Y554337D01*
X1363367Y554379D01*
X1362992Y554337D01*
X1362659Y554212D01*
X1362409Y554045D01*
X1362200Y553795D01*
X1362117Y553462D01*
G01Y556562D02*
X1362200Y556229D01*
X1362409Y555979D01*
X1362659Y555812D01*
X1362992Y555687D01*
X1363367Y555645D01*
X1363742Y555687D01*
X1364075Y555812D01*
X1364325Y555979D01*
X1364534Y556229D01*
X1364617Y556562D01*
X1364534Y556895D01*
X1364325Y557145D01*
X1364075Y557312D01*
X1363742Y557437D01*
X1363367Y557479D01*
X1362992Y557437D01*
X1362659Y557312D01*
X1362409Y557145D01*
X1362200Y556895D01*
X1362117Y556562D01*
G01X1357825Y548179D02*
X1357700Y547929D01*
X1357617Y547637D01*
Y547304D01*
X1357742Y546929D01*
X1357950Y546637D01*
X1358200Y546429D01*
X1358617Y546262D01*
X1358992Y546220D01*
X1359367Y546304D01*
X1359617Y546429D01*
X1359867Y546679D01*
X1360034Y546970D01*
X1360117Y547262D01*
Y547554D01*
X1360034Y547845D01*
X1359909Y548095D01*
X1359742Y548304D01*
G01X1360117Y550362D02*
X1357617D01*
X1358117Y549862D01*
G01X1360117D02*
Y550862D01*
G01X1359742Y552545D02*
X1359950Y552795D01*
X1360075Y553087D01*
X1360117Y553462D01*
X1360034Y553837D01*
X1359867Y554129D01*
X1359575Y554337D01*
X1359242Y554379D01*
X1358909Y554295D01*
X1358700Y554087D01*
X1358534Y553795D01*
X1358492Y553504D01*
X1358534Y553212D01*
X1358700Y552837D01*
X1357617Y552962D01*
Y554087D01*
G01X1359825Y555854D02*
X1360034Y556145D01*
X1360117Y556479D01*
X1360034Y556812D01*
X1359784Y557104D01*
X1359409Y557312D01*
X1359034Y557395D01*
X1358575D01*
X1358200Y557312D01*
X1357867Y557104D01*
X1357700Y556854D01*
X1357617Y556562D01*
X1357700Y556229D01*
X1357867Y555979D01*
X1358117Y555812D01*
X1358450Y555729D01*
X1358742Y555812D01*
X1359034Y556020D01*
X1359200Y556270D01*
X1359242Y556562D01*
X1359159Y556895D01*
X1358950Y557145D01*
X1358575Y557395D01*
G01X1365117Y567612D02*
X1361117D01*
Y560212D01*
G01X1350617Y576312D02*
Y578212D01*
G01X1364917Y578912D02*
Y576412D01*
G01X1363959Y578912D02*
X1365875D01*
G01X1367184Y576412D02*
Y578912D01*
X1368184D01*
X1368517Y578787D01*
X1368767Y578495D01*
X1368850Y578162D01*
X1368767Y577829D01*
X1368559Y577579D01*
X1368184Y577454D01*
X1367184D01*
G01X1371117Y576412D02*
Y578912D01*
X1370617Y578412D01*
G01Y576412D02*
X1371617D01*
G01X1373425Y577454D02*
X1373717Y577745D01*
X1373967Y577912D01*
X1374300Y577995D01*
X1374592Y577912D01*
X1374800Y577745D01*
X1374967Y577495D01*
X1375009Y577204D01*
X1374967Y576954D01*
X1374800Y576704D01*
X1374550Y576495D01*
X1374259Y576412D01*
X1373925Y576495D01*
X1373634Y576745D01*
X1373467Y577120D01*
X1373425Y577537D01*
X1373509Y578079D01*
X1373634Y578370D01*
X1373842Y578662D01*
X1374134Y578870D01*
X1374425Y578912D01*
X1374717Y578829D01*
X1374925Y578620D01*
G01X1377234Y576412D02*
X1377317Y576954D01*
X1377442Y577412D01*
X1377609Y577829D01*
X1377817Y578287D01*
X1378150Y578912D01*
X1376484D01*
G01X1351017Y569000D02*
Y571500D01*
X1352058D01*
X1352392Y571375D01*
X1352600Y571208D01*
X1352683Y570875D01*
X1352600Y570542D01*
X1352350Y570333D01*
X1352058Y570208D01*
X1351017D01*
G01X1352058D02*
X1352683Y569000D01*
G01X1354867D02*
X1354950Y569542D01*
X1355075Y570000D01*
X1355242Y570417D01*
X1355450Y570875D01*
X1355783Y571500D01*
X1354117D01*
G01X1358050D02*
X1357717Y571417D01*
X1357467Y571208D01*
X1357300Y570958D01*
X1357175Y570625D01*
X1357133Y570250D01*
X1357175Y569875D01*
X1357300Y569542D01*
X1357467Y569292D01*
X1357717Y569083D01*
X1358050Y569000D01*
X1358383Y569083D01*
X1358633Y569292D01*
X1358800Y569542D01*
X1358925Y569875D01*
X1358967Y570250D01*
X1358925Y570625D01*
X1358800Y570958D01*
X1358633Y571208D01*
X1358383Y571417D01*
X1358050Y571500D01*
G01X1361150Y569000D02*
Y571500D01*
X1360650Y571000D01*
G01Y569000D02*
X1361650D01*
G01X1359517Y593512D02*
X1361517D01*
G01X1363117Y599345D02*
X1364909D01*
X1365284Y599512D01*
X1365534Y599845D01*
X1365617Y600262D01*
X1365534Y600679D01*
X1365284Y601012D01*
X1364909Y601179D01*
X1363117D01*
G01X1365617Y603362D02*
X1363117D01*
X1363617Y602862D01*
G01X1365617D02*
Y603862D01*
G01Y606462D02*
X1365575Y606754D01*
X1365450Y607087D01*
X1365242Y607295D01*
X1364950Y607379D01*
X1364659Y607295D01*
X1364409Y607045D01*
X1364284Y606670D01*
Y606254D01*
X1364200Y606004D01*
X1363992Y605795D01*
X1363700Y605712D01*
X1363409Y605837D01*
X1363200Y606129D01*
X1363117Y606462D01*
X1363200Y606795D01*
X1363409Y607087D01*
X1363700Y607212D01*
X1363992Y607129D01*
X1364200Y606920D01*
X1364284Y606670D01*
Y606254D01*
X1364409Y605879D01*
X1364659Y605629D01*
X1364950Y605545D01*
X1365242Y605629D01*
X1365450Y605837D01*
X1365575Y606170D01*
X1365617Y606462D01*
G01X1365117Y608645D02*
X1365409Y608895D01*
X1365575Y609229D01*
X1365617Y609604D01*
X1365575Y609937D01*
X1365367Y610270D01*
X1365117Y610479D01*
X1364867Y610520D01*
X1364575Y610437D01*
X1364367Y610145D01*
X1364284Y609854D01*
Y609479D01*
G01Y609854D02*
X1364159Y610104D01*
X1363950Y610312D01*
X1363700Y610395D01*
X1363450Y610312D01*
X1363242Y610104D01*
X1363117Y609729D01*
X1363159Y609354D01*
X1363325Y608979D01*
G01X1352517Y608312D02*
Y611012D01*
G01X1355417Y609212D02*
X1360417D01*
Y604212D01*
G01X1356417Y625112D02*
X1352417D01*
Y617712D01*
G01X1358617D02*
X1362617D01*
Y625112D01*
G01X1357017Y634500D02*
Y637000D01*
X1358058D01*
X1358392Y636875D01*
X1358600Y636708D01*
X1358683Y636375D01*
X1358600Y636042D01*
X1358350Y635833D01*
X1358058Y635708D01*
X1357017D01*
G01X1358058D02*
X1358683Y634500D01*
G01X1360158Y636583D02*
X1360408Y636833D01*
X1360700Y636958D01*
X1361033Y637000D01*
X1361450Y636917D01*
X1361742Y636708D01*
X1361825Y636458D01*
X1361783Y636208D01*
X1361617Y636000D01*
X1360783Y635583D01*
X1360408Y635292D01*
X1360158Y634875D01*
X1360075Y634500D01*
X1361825D01*
G01X1363258Y636583D02*
X1363508Y636833D01*
X1363800Y636958D01*
X1364133Y637000D01*
X1364550Y636917D01*
X1364842Y636708D01*
X1364925Y636458D01*
X1364883Y636208D01*
X1364717Y636000D01*
X1363883Y635583D01*
X1363508Y635292D01*
X1363258Y634875D01*
X1363175Y634500D01*
X1364925D01*
G01X1367067D02*
X1367150Y635042D01*
X1367275Y635500D01*
X1367442Y635917D01*
X1367650Y636375D01*
X1367983Y637000D01*
X1366317D01*
G01X1352208Y635767D02*
X1352083Y635517D01*
X1352000Y635225D01*
Y634892D01*
X1352125Y634517D01*
X1352333Y634225D01*
X1352583Y634017D01*
X1353000Y633850D01*
X1353375Y633808D01*
X1353750Y633892D01*
X1354000Y634017D01*
X1354250Y634267D01*
X1354417Y634558D01*
X1354500Y634850D01*
Y635142D01*
X1354417Y635433D01*
X1354292Y635683D01*
X1354125Y635892D01*
G01X1354500Y637950D02*
X1352000D01*
X1352500Y637450D01*
G01X1354500D02*
Y638450D01*
G01X1353458Y640258D02*
X1353167Y640550D01*
X1353000Y640800D01*
X1352917Y641133D01*
X1353000Y641425D01*
X1353167Y641633D01*
X1353417Y641800D01*
X1353708Y641842D01*
X1353958Y641800D01*
X1354208Y641633D01*
X1354417Y641383D01*
X1354500Y641092D01*
X1354417Y640758D01*
X1354167Y640467D01*
X1353792Y640300D01*
X1353375Y640258D01*
X1352833Y640342D01*
X1352542Y640467D01*
X1352250Y640675D01*
X1352042Y640967D01*
X1352000Y641258D01*
X1352083Y641550D01*
X1352292Y641758D01*
G01X1352417Y643358D02*
X1352167Y643608D01*
X1352042Y643900D01*
X1352000Y644233D01*
X1352083Y644650D01*
X1352292Y644942D01*
X1352542Y645025D01*
X1352792Y644983D01*
X1353000Y644817D01*
X1353417Y643983D01*
X1353708Y643608D01*
X1354125Y643358D01*
X1354500Y643275D01*
Y645025D01*
G01X1350500Y825967D02*
X1348000D01*
Y827008D01*
X1348125Y827342D01*
X1348292Y827550D01*
X1348625Y827633D01*
X1348958Y827550D01*
X1349167Y827300D01*
X1349292Y827008D01*
Y825967D01*
G01Y827008D02*
X1350500Y827633D01*
G01X1350125Y828983D02*
X1350333Y829233D01*
X1350458Y829525D01*
X1350500Y829900D01*
X1350417Y830275D01*
X1350250Y830567D01*
X1349958Y830775D01*
X1349625Y830817D01*
X1349292Y830733D01*
X1349083Y830525D01*
X1348917Y830233D01*
X1348875Y829942D01*
X1348917Y829650D01*
X1349083Y829275D01*
X1348000Y829400D01*
Y830525D01*
G01X1350000Y832083D02*
X1350292Y832333D01*
X1350458Y832667D01*
X1350500Y833042D01*
X1350458Y833375D01*
X1350250Y833708D01*
X1350000Y833917D01*
X1349750Y833958D01*
X1349458Y833875D01*
X1349250Y833583D01*
X1349167Y833292D01*
Y832917D01*
G01Y833292D02*
X1349042Y833542D01*
X1348833Y833750D01*
X1348583Y833833D01*
X1348333Y833750D01*
X1348125Y833542D01*
X1348000Y833167D01*
X1348042Y832792D01*
X1348208Y832417D01*
G01X1348000Y836100D02*
X1348083Y835767D01*
X1348292Y835517D01*
X1348542Y835350D01*
X1348875Y835225D01*
X1349250Y835183D01*
X1349625Y835225D01*
X1349958Y835350D01*
X1350208Y835517D01*
X1350417Y835767D01*
X1350500Y836100D01*
X1350417Y836433D01*
X1350208Y836683D01*
X1349958Y836850D01*
X1349625Y836975D01*
X1349250Y837017D01*
X1348875Y836975D01*
X1348542Y836850D01*
X1348292Y836683D01*
X1348083Y836433D01*
X1348000Y836100D01*
G01X1350500Y839700D02*
X1348000D01*
X1349792Y838158D01*
Y840242D01*
G01X1379862Y41181D02*
Y48181D01*
G01Y54181D02*
Y61181D01*
G01Y48181D02*
X1377862Y53181D01*
G01X1380162Y48181D02*
G03I-300J0D01*
G01Y54181D02*
G03I-300J0D01*
G01X1379862Y77402D02*
Y84402D01*
G01D02*
X1377862Y89402D01*
G01X1380162Y84402D02*
G03I-300J0D01*
G01X1373962Y124680D02*
Y121680D01*
X1393862D01*
Y105880D01*
X1365862D01*
Y120080D01*
X1369162D01*
Y124680D01*
X1373962D01*
G01X1379862Y90402D02*
Y97402D01*
G01X1380162Y90402D02*
G03I-300J0D01*
G01X1370567Y353000D02*
Y355500D01*
X1371567D01*
X1371900Y355375D01*
X1372150Y355083D01*
X1372233Y354750D01*
X1372150Y354417D01*
X1371942Y354167D01*
X1371567Y354042D01*
X1370567D01*
G01X1374750Y354250D02*
X1375583D01*
Y353500D01*
X1375333Y353250D01*
X1375042Y353083D01*
X1374625Y353000D01*
X1374208Y353083D01*
X1373917Y353250D01*
X1373667Y353500D01*
X1373500Y353792D01*
X1373417Y354125D01*
Y354417D01*
X1373500Y354667D01*
X1373667Y354958D01*
X1373917Y355208D01*
X1374167Y355375D01*
X1374500Y355500D01*
X1374792D01*
X1375125Y355417D01*
X1375375Y355250D01*
G01X1377600Y353000D02*
Y355500D01*
X1377100Y355000D01*
G01Y353000D02*
X1378100D01*
G01X1379017Y367500D02*
Y370000D01*
X1380017D01*
X1380350Y369875D01*
X1380600Y369583D01*
X1380683Y369250D01*
X1380600Y368917D01*
X1380392Y368667D01*
X1380017Y368542D01*
X1379017D01*
G01X1383867Y369792D02*
X1383617Y369917D01*
X1383325Y370000D01*
X1382992D01*
X1382617Y369875D01*
X1382325Y369667D01*
X1382117Y369417D01*
X1381950Y369000D01*
X1381908Y368625D01*
X1381992Y368250D01*
X1382117Y368000D01*
X1382367Y367750D01*
X1382658Y367583D01*
X1382950Y367500D01*
X1383242D01*
X1383533Y367583D01*
X1383783Y367708D01*
X1383992Y367875D01*
G01X1386050Y367500D02*
Y370000D01*
X1385550Y369500D01*
G01Y367500D02*
X1386550D01*
G01X1389067D02*
X1389150Y368042D01*
X1389275Y368500D01*
X1389442Y368917D01*
X1389650Y369375D01*
X1389983Y370000D01*
X1388317D01*
G01X1376300Y367500D02*
X1370800D01*
G01X1376300Y375500D02*
Y367500D01*
G01X1379017Y363000D02*
Y365500D01*
X1380017D01*
X1380350Y365375D01*
X1380600Y365083D01*
X1380683Y364750D01*
X1380600Y364417D01*
X1380392Y364167D01*
X1380017Y364042D01*
X1379017D01*
G01X1383867Y365292D02*
X1383617Y365417D01*
X1383325Y365500D01*
X1382992D01*
X1382617Y365375D01*
X1382325Y365167D01*
X1382117Y364917D01*
X1381950Y364500D01*
X1381908Y364125D01*
X1381992Y363750D01*
X1382117Y363500D01*
X1382367Y363250D01*
X1382658Y363083D01*
X1382950Y363000D01*
X1383242D01*
X1383533Y363083D01*
X1383783Y363208D01*
X1383992Y363375D01*
G01X1386050Y363000D02*
Y365500D01*
X1385550Y365000D01*
G01Y363000D02*
X1386550D01*
G01X1389150D02*
X1389442Y363042D01*
X1389775Y363167D01*
X1389983Y363375D01*
X1390067Y363667D01*
X1389983Y363958D01*
X1389733Y364208D01*
X1389358Y364333D01*
X1388942D01*
X1388692Y364417D01*
X1388483Y364625D01*
X1388400Y364917D01*
X1388525Y365208D01*
X1388817Y365417D01*
X1389150Y365500D01*
X1389483Y365417D01*
X1389775Y365208D01*
X1389900Y364917D01*
X1389817Y364625D01*
X1389608Y364417D01*
X1389358Y364333D01*
X1388942D01*
X1388567Y364208D01*
X1388317Y363958D01*
X1388233Y363667D01*
X1388317Y363375D01*
X1388525Y363167D01*
X1388858Y363042D01*
X1389150Y363000D01*
G01X1376300Y358500D02*
X1370800D01*
G01X1376300Y366500D02*
Y358500D01*
G01X1370800Y366500D02*
X1376300D01*
G01X1378517Y381000D02*
Y383500D01*
X1379517D01*
X1379850Y383375D01*
X1380100Y383083D01*
X1380183Y382750D01*
X1380100Y382417D01*
X1379892Y382167D01*
X1379517Y382042D01*
X1378517D01*
G01X1383367Y383292D02*
X1383117Y383417D01*
X1382825Y383500D01*
X1382492D01*
X1382117Y383375D01*
X1381825Y383167D01*
X1381617Y382917D01*
X1381450Y382500D01*
X1381408Y382125D01*
X1381492Y381750D01*
X1381617Y381500D01*
X1381867Y381250D01*
X1382158Y381083D01*
X1382450Y381000D01*
X1382742D01*
X1383033Y381083D01*
X1383283Y381208D01*
X1383492Y381375D01*
G01X1385550Y381000D02*
Y383500D01*
X1385050Y383000D01*
G01Y381000D02*
X1386050D01*
G01X1387858Y382042D02*
X1388150Y382333D01*
X1388400Y382500D01*
X1388733Y382583D01*
X1389025Y382500D01*
X1389233Y382333D01*
X1389400Y382083D01*
X1389442Y381792D01*
X1389400Y381542D01*
X1389233Y381292D01*
X1388983Y381083D01*
X1388692Y381000D01*
X1388358Y381083D01*
X1388067Y381333D01*
X1387900Y381708D01*
X1387858Y382125D01*
X1387942Y382667D01*
X1388067Y382958D01*
X1388275Y383250D01*
X1388567Y383458D01*
X1388858Y383500D01*
X1389150Y383417D01*
X1389358Y383208D01*
G01X1370800Y375500D02*
X1376300D01*
G01X1378517Y386500D02*
Y389000D01*
X1379517D01*
X1379850Y388875D01*
X1380100Y388583D01*
X1380183Y388250D01*
X1380100Y387917D01*
X1379892Y387667D01*
X1379517Y387542D01*
X1378517D01*
G01X1383367Y388792D02*
X1383117Y388917D01*
X1382825Y389000D01*
X1382492D01*
X1382117Y388875D01*
X1381825Y388667D01*
X1381617Y388417D01*
X1381450Y388000D01*
X1381408Y387625D01*
X1381492Y387250D01*
X1381617Y387000D01*
X1381867Y386750D01*
X1382158Y386583D01*
X1382450Y386500D01*
X1382742D01*
X1383033Y386583D01*
X1383283Y386708D01*
X1383492Y386875D01*
G01X1385550Y386500D02*
Y389000D01*
X1385050Y388500D01*
G01Y386500D02*
X1386050D01*
G01X1387733Y386875D02*
X1387983Y386667D01*
X1388275Y386542D01*
X1388650Y386500D01*
X1389025Y386583D01*
X1389317Y386750D01*
X1389525Y387042D01*
X1389567Y387375D01*
X1389483Y387708D01*
X1389275Y387917D01*
X1388983Y388083D01*
X1388692Y388125D01*
X1388400Y388083D01*
X1388025Y387917D01*
X1388150Y389000D01*
X1389275D01*
G01X1379000Y409067D02*
X1376500D01*
Y410067D01*
X1376625Y410400D01*
X1376917Y410650D01*
X1377250Y410733D01*
X1377583Y410650D01*
X1377833Y410442D01*
X1377958Y410067D01*
Y409067D01*
G01X1376708Y413917D02*
X1376583Y413667D01*
X1376500Y413375D01*
Y413042D01*
X1376625Y412667D01*
X1376833Y412375D01*
X1377083Y412167D01*
X1377500Y412000D01*
X1377875Y411958D01*
X1378250Y412042D01*
X1378500Y412167D01*
X1378750Y412417D01*
X1378917Y412708D01*
X1379000Y413000D01*
Y413292D01*
X1378917Y413583D01*
X1378792Y413833D01*
X1378625Y414042D01*
G01X1379000Y416017D02*
X1378458Y416100D01*
X1378000Y416225D01*
X1377583Y416392D01*
X1377125Y416600D01*
X1376500Y416933D01*
Y415267D01*
G01X1368000Y405017D02*
X1365500D01*
Y406017D01*
X1365625Y406350D01*
X1365917Y406600D01*
X1366250Y406683D01*
X1366583Y406600D01*
X1366833Y406392D01*
X1366958Y406017D01*
Y405017D01*
G01X1368000Y408117D02*
X1365500D01*
Y409158D01*
X1365625Y409492D01*
X1365792Y409700D01*
X1366125Y409783D01*
X1366458Y409700D01*
X1366667Y409450D01*
X1366792Y409158D01*
Y408117D01*
G01Y409158D02*
X1368000Y409783D01*
G01Y412050D02*
X1365500D01*
X1366000Y411550D01*
G01X1368000D02*
Y412550D01*
G01X1365917Y414358D02*
X1365667Y414608D01*
X1365542Y414900D01*
X1365500Y415233D01*
X1365583Y415650D01*
X1365792Y415942D01*
X1366042Y416025D01*
X1366292Y415983D01*
X1366500Y415817D01*
X1366917Y414983D01*
X1367208Y414608D01*
X1367625Y414358D01*
X1368000Y414275D01*
Y416025D01*
G01X1374500Y409067D02*
X1372000D01*
Y410067D01*
X1372125Y410400D01*
X1372417Y410650D01*
X1372750Y410733D01*
X1373083Y410650D01*
X1373333Y410442D01*
X1373458Y410067D01*
Y409067D01*
G01X1372208Y413917D02*
X1372083Y413667D01*
X1372000Y413375D01*
Y413042D01*
X1372125Y412667D01*
X1372333Y412375D01*
X1372583Y412167D01*
X1373000Y412000D01*
X1373375Y411958D01*
X1373750Y412042D01*
X1374000Y412167D01*
X1374250Y412417D01*
X1374417Y412708D01*
X1374500Y413000D01*
Y413292D01*
X1374417Y413583D01*
X1374292Y413833D01*
X1374125Y414042D01*
G01X1373458Y415308D02*
X1373167Y415600D01*
X1373000Y415850D01*
X1372917Y416183D01*
X1373000Y416475D01*
X1373167Y416683D01*
X1373417Y416850D01*
X1373708Y416892D01*
X1373958Y416850D01*
X1374208Y416683D01*
X1374417Y416433D01*
X1374500Y416142D01*
X1374417Y415808D01*
X1374167Y415517D01*
X1373792Y415350D01*
X1373375Y415308D01*
X1372833Y415392D01*
X1372542Y415517D01*
X1372250Y415725D01*
X1372042Y416017D01*
X1372000Y416308D01*
X1372083Y416600D01*
X1372292Y416808D01*
G01X1383000Y440067D02*
X1380500D01*
Y441067D01*
X1380625Y441400D01*
X1380917Y441650D01*
X1381250Y441733D01*
X1381583Y441650D01*
X1381833Y441442D01*
X1381958Y441067D01*
Y440067D01*
G01X1383000Y443167D02*
X1380500D01*
Y444208D01*
X1380625Y444542D01*
X1380792Y444750D01*
X1381125Y444833D01*
X1381458Y444750D01*
X1381667Y444500D01*
X1381792Y444208D01*
Y443167D01*
G01Y444208D02*
X1383000Y444833D01*
G01X1382625Y446183D02*
X1382833Y446433D01*
X1382958Y446725D01*
X1383000Y447100D01*
X1382917Y447475D01*
X1382750Y447767D01*
X1382458Y447975D01*
X1382125Y448017D01*
X1381792Y447933D01*
X1381583Y447725D01*
X1381417Y447433D01*
X1381375Y447142D01*
X1381417Y446850D01*
X1381583Y446475D01*
X1380500Y446600D01*
Y447725D01*
G01X1378500Y435200D02*
X1370500D01*
Y452800D01*
X1378500D01*
Y435200D01*
G01X1369000Y437067D02*
X1366500D01*
Y438067D01*
X1366625Y438400D01*
X1366917Y438650D01*
X1367250Y438733D01*
X1367583Y438650D01*
X1367833Y438442D01*
X1367958Y438067D01*
Y437067D01*
G01X1369000Y440167D02*
X1366500D01*
Y441208D01*
X1366625Y441542D01*
X1366792Y441750D01*
X1367125Y441833D01*
X1367458Y441750D01*
X1367667Y441500D01*
X1367792Y441208D01*
Y440167D01*
G01Y441208D02*
X1369000Y441833D01*
G01Y444600D02*
X1366500D01*
X1368292Y443058D01*
Y445142D01*
G01X1369000Y448067D02*
X1366500D01*
Y449067D01*
X1366625Y449400D01*
X1366917Y449650D01*
X1367250Y449733D01*
X1367583Y449650D01*
X1367833Y449442D01*
X1367958Y449067D01*
Y448067D01*
G01X1366708Y452917D02*
X1366583Y452667D01*
X1366500Y452375D01*
Y452042D01*
X1366625Y451667D01*
X1366833Y451375D01*
X1367083Y451167D01*
X1367500Y451000D01*
X1367875Y450958D01*
X1368250Y451042D01*
X1368500Y451167D01*
X1368750Y451417D01*
X1368917Y451708D01*
X1369000Y452000D01*
Y452292D01*
X1368917Y452583D01*
X1368792Y452833D01*
X1368625Y453042D01*
G01Y454183D02*
X1368833Y454433D01*
X1368958Y454725D01*
X1369000Y455100D01*
X1368917Y455475D01*
X1368750Y455767D01*
X1368458Y455975D01*
X1368125Y456017D01*
X1367792Y455933D01*
X1367583Y455725D01*
X1367417Y455433D01*
X1367375Y455142D01*
X1367417Y454850D01*
X1367583Y454475D01*
X1366500Y454600D01*
Y455725D01*
G01X1371208Y548267D02*
X1371083Y548017D01*
X1371000Y547725D01*
Y547392D01*
X1371125Y547017D01*
X1371333Y546725D01*
X1371583Y546517D01*
X1372000Y546350D01*
X1372375Y546308D01*
X1372750Y546392D01*
X1373000Y546517D01*
X1373250Y546767D01*
X1373417Y547058D01*
X1373500Y547350D01*
Y547642D01*
X1373417Y547933D01*
X1373292Y548183D01*
X1373125Y548392D01*
G01X1373500Y550450D02*
X1371000D01*
X1371500Y549950D01*
G01X1373500D02*
Y550950D01*
G01X1373125Y552633D02*
X1373333Y552883D01*
X1373458Y553175D01*
X1373500Y553550D01*
X1373417Y553925D01*
X1373250Y554217D01*
X1372958Y554425D01*
X1372625Y554467D01*
X1372292Y554383D01*
X1372083Y554175D01*
X1371917Y553883D01*
X1371875Y553592D01*
X1371917Y553300D01*
X1372083Y552925D01*
X1371000Y553050D01*
Y554175D01*
G01X1373500Y556650D02*
X1373458Y556942D01*
X1373333Y557275D01*
X1373125Y557483D01*
X1372833Y557567D01*
X1372542Y557483D01*
X1372292Y557233D01*
X1372167Y556858D01*
Y556442D01*
X1372083Y556192D01*
X1371875Y555983D01*
X1371583Y555900D01*
X1371292Y556025D01*
X1371083Y556317D01*
X1371000Y556650D01*
X1371083Y556983D01*
X1371292Y557275D01*
X1371583Y557400D01*
X1371875Y557317D01*
X1372083Y557108D01*
X1372167Y556858D01*
Y556442D01*
X1372292Y556067D01*
X1372542Y555817D01*
X1372833Y555733D01*
X1373125Y555817D01*
X1373333Y556025D01*
X1373458Y556358D01*
X1373500Y556650D01*
G01X1366825Y548179D02*
X1366700Y547929D01*
X1366617Y547637D01*
Y547304D01*
X1366742Y546929D01*
X1366950Y546637D01*
X1367200Y546429D01*
X1367617Y546262D01*
X1367992Y546220D01*
X1368367Y546304D01*
X1368617Y546429D01*
X1368867Y546679D01*
X1369034Y546970D01*
X1369117Y547262D01*
Y547554D01*
X1369034Y547845D01*
X1368909Y548095D01*
X1368742Y548304D01*
G01X1367034Y549570D02*
X1366784Y549820D01*
X1366659Y550112D01*
X1366617Y550445D01*
X1366700Y550862D01*
X1366909Y551154D01*
X1367159Y551237D01*
X1367409Y551195D01*
X1367617Y551029D01*
X1368034Y550195D01*
X1368325Y549820D01*
X1368742Y549570D01*
X1369117Y549487D01*
Y551237D01*
G01X1368742Y552545D02*
X1368950Y552795D01*
X1369075Y553087D01*
X1369117Y553462D01*
X1369034Y553837D01*
X1368867Y554129D01*
X1368575Y554337D01*
X1368242Y554379D01*
X1367909Y554295D01*
X1367700Y554087D01*
X1367534Y553795D01*
X1367492Y553504D01*
X1367534Y553212D01*
X1367700Y552837D01*
X1366617Y552962D01*
Y554087D01*
G01X1369117Y557062D02*
X1366617D01*
X1368409Y555520D01*
Y557604D01*
G01X1379134Y588412D02*
Y590912D01*
X1380175D01*
X1380509Y590787D01*
X1380717Y590620D01*
X1380800Y590287D01*
X1380717Y589954D01*
X1380467Y589745D01*
X1380175Y589620D01*
X1379134D01*
G01X1380175D02*
X1380800Y588412D01*
G01X1383567D02*
Y590912D01*
X1382025Y589120D01*
X1384109D01*
G01X1386667Y588412D02*
Y590912D01*
X1385125Y589120D01*
X1387209D01*
G01X1388559Y588704D02*
X1388850Y588495D01*
X1389184Y588412D01*
X1389517Y588495D01*
X1389809Y588745D01*
X1390017Y589120D01*
X1390100Y589495D01*
Y589954D01*
X1390017Y590329D01*
X1389809Y590662D01*
X1389559Y590829D01*
X1389267Y590912D01*
X1388934Y590829D01*
X1388684Y590662D01*
X1388517Y590412D01*
X1388434Y590079D01*
X1388517Y589787D01*
X1388725Y589495D01*
X1388975Y589329D01*
X1389267Y589287D01*
X1389600Y589370D01*
X1389850Y589579D01*
X1390100Y589954D01*
G01X1375317Y587912D02*
Y591912D01*
X1367917D01*
G01X1379134Y583912D02*
Y586412D01*
X1380175D01*
X1380509Y586287D01*
X1380717Y586120D01*
X1380800Y585787D01*
X1380717Y585454D01*
X1380467Y585245D01*
X1380175Y585120D01*
X1379134D01*
G01X1380175D02*
X1380800Y583912D01*
G01X1383567D02*
Y586412D01*
X1382025Y584620D01*
X1384109D01*
G01X1385250Y584287D02*
X1385500Y584079D01*
X1385792Y583954D01*
X1386167Y583912D01*
X1386542Y583995D01*
X1386834Y584162D01*
X1387042Y584454D01*
X1387084Y584787D01*
X1387000Y585120D01*
X1386792Y585329D01*
X1386500Y585495D01*
X1386209Y585537D01*
X1385917Y585495D01*
X1385542Y585329D01*
X1385667Y586412D01*
X1386792D01*
G01X1389267D02*
X1388934Y586329D01*
X1388684Y586120D01*
X1388517Y585870D01*
X1388392Y585537D01*
X1388350Y585162D01*
X1388392Y584787D01*
X1388517Y584454D01*
X1388684Y584204D01*
X1388934Y583995D01*
X1389267Y583912D01*
X1389600Y583995D01*
X1389850Y584204D01*
X1390017Y584454D01*
X1390142Y584787D01*
X1390184Y585162D01*
X1390142Y585537D01*
X1390017Y585870D01*
X1389850Y586120D01*
X1389600Y586329D01*
X1389267Y586412D01*
G01X1375317Y583412D02*
Y587412D01*
X1367917D01*
G01X1379134Y596412D02*
Y598912D01*
X1380175D01*
X1380509Y598787D01*
X1380717Y598620D01*
X1380800Y598287D01*
X1380717Y597954D01*
X1380467Y597745D01*
X1380175Y597620D01*
X1379134D01*
G01X1380175D02*
X1380800Y596412D01*
G01X1383567D02*
Y598912D01*
X1382025Y597120D01*
X1384109D01*
G01X1385250Y596787D02*
X1385500Y596579D01*
X1385792Y596454D01*
X1386167Y596412D01*
X1386542Y596495D01*
X1386834Y596662D01*
X1387042Y596954D01*
X1387084Y597287D01*
X1387000Y597620D01*
X1386792Y597829D01*
X1386500Y597995D01*
X1386209Y598037D01*
X1385917Y597995D01*
X1385542Y597829D01*
X1385667Y598912D01*
X1386792D01*
G01X1388475Y598495D02*
X1388725Y598745D01*
X1389017Y598870D01*
X1389350Y598912D01*
X1389767Y598829D01*
X1390059Y598620D01*
X1390142Y598370D01*
X1390100Y598120D01*
X1389934Y597912D01*
X1389100Y597495D01*
X1388725Y597204D01*
X1388475Y596787D01*
X1388392Y596412D01*
X1390142D01*
G01X1375317Y595912D02*
Y599912D01*
X1367917D01*
G01X1380884Y594704D02*
X1380634Y594829D01*
X1380342Y594912D01*
X1380009D01*
X1379634Y594787D01*
X1379342Y594579D01*
X1379134Y594329D01*
X1378967Y593912D01*
X1378925Y593537D01*
X1379009Y593162D01*
X1379134Y592912D01*
X1379384Y592662D01*
X1379675Y592495D01*
X1379967Y592412D01*
X1380259D01*
X1380550Y592495D01*
X1380800Y592620D01*
X1381009Y592787D01*
G01X1383067Y592412D02*
Y594912D01*
X1382567Y594412D01*
G01Y592412D02*
X1383567D01*
G01X1385375Y593454D02*
X1385667Y593745D01*
X1385917Y593912D01*
X1386250Y593995D01*
X1386542Y593912D01*
X1386750Y593745D01*
X1386917Y593495D01*
X1386959Y593204D01*
X1386917Y592954D01*
X1386750Y592704D01*
X1386500Y592495D01*
X1386209Y592412D01*
X1385875Y592495D01*
X1385584Y592745D01*
X1385417Y593120D01*
X1385375Y593537D01*
X1385459Y594079D01*
X1385584Y594370D01*
X1385792Y594662D01*
X1386084Y594870D01*
X1386375Y594912D01*
X1386667Y594829D01*
X1386875Y594620D01*
G01X1389184Y592412D02*
X1389267Y592954D01*
X1389392Y593412D01*
X1389559Y593829D01*
X1389767Y594287D01*
X1390100Y594912D01*
X1388434D01*
G01X1379134Y600912D02*
Y603412D01*
X1380175D01*
X1380509Y603287D01*
X1380717Y603120D01*
X1380800Y602787D01*
X1380717Y602454D01*
X1380467Y602245D01*
X1380175Y602120D01*
X1379134D01*
G01X1380175D02*
X1380800Y600912D01*
G01X1383567D02*
Y603412D01*
X1382025Y601620D01*
X1384109D01*
G01X1385250Y601287D02*
X1385500Y601079D01*
X1385792Y600954D01*
X1386167Y600912D01*
X1386542Y600995D01*
X1386834Y601162D01*
X1387042Y601454D01*
X1387084Y601787D01*
X1387000Y602120D01*
X1386792Y602329D01*
X1386500Y602495D01*
X1386209Y602537D01*
X1385917Y602495D01*
X1385542Y602329D01*
X1385667Y603412D01*
X1386792D01*
G01X1389267Y600912D02*
Y603412D01*
X1388767Y602912D01*
G01Y600912D02*
X1389767D01*
G01X1375317Y600412D02*
Y604412D01*
X1367917D01*
G01X1379134Y609912D02*
Y612412D01*
X1380175D01*
X1380509Y612287D01*
X1380717Y612120D01*
X1380800Y611787D01*
X1380717Y611454D01*
X1380467Y611245D01*
X1380175Y611120D01*
X1379134D01*
G01X1380175D02*
X1380800Y609912D01*
G01X1382150Y610287D02*
X1382400Y610079D01*
X1382692Y609954D01*
X1383067Y609912D01*
X1383442Y609995D01*
X1383734Y610162D01*
X1383942Y610454D01*
X1383984Y610787D01*
X1383900Y611120D01*
X1383692Y611329D01*
X1383400Y611495D01*
X1383109Y611537D01*
X1382817Y611495D01*
X1382442Y611329D01*
X1382567Y612412D01*
X1383692D01*
G01X1385250Y610412D02*
X1385500Y610120D01*
X1385834Y609954D01*
X1386209Y609912D01*
X1386542Y609954D01*
X1386875Y610162D01*
X1387084Y610412D01*
X1387125Y610662D01*
X1387042Y610954D01*
X1386750Y611162D01*
X1386459Y611245D01*
X1386084D01*
G01X1386459D02*
X1386709Y611370D01*
X1386917Y611579D01*
X1387000Y611829D01*
X1386917Y612079D01*
X1386709Y612287D01*
X1386334Y612412D01*
X1385959Y612370D01*
X1385584Y612204D01*
G01X1388350Y610412D02*
X1388600Y610120D01*
X1388934Y609954D01*
X1389309Y609912D01*
X1389642Y609954D01*
X1389975Y610162D01*
X1390184Y610412D01*
X1390225Y610662D01*
X1390142Y610954D01*
X1389850Y611162D01*
X1389559Y611245D01*
X1389184D01*
G01X1389559D02*
X1389809Y611370D01*
X1390017Y611579D01*
X1390100Y611829D01*
X1390017Y612079D01*
X1389809Y612287D01*
X1389434Y612412D01*
X1389059Y612370D01*
X1388684Y612204D01*
G01X1375317Y609412D02*
Y613412D01*
X1367917D01*
G01X1379134Y605412D02*
Y607912D01*
X1380175D01*
X1380509Y607787D01*
X1380717Y607620D01*
X1380800Y607287D01*
X1380717Y606954D01*
X1380467Y606745D01*
X1380175Y606620D01*
X1379134D01*
G01X1380175D02*
X1380800Y605412D01*
G01X1382150Y605787D02*
X1382400Y605579D01*
X1382692Y605454D01*
X1383067Y605412D01*
X1383442Y605495D01*
X1383734Y605662D01*
X1383942Y605954D01*
X1383984Y606287D01*
X1383900Y606620D01*
X1383692Y606829D01*
X1383400Y606995D01*
X1383109Y607037D01*
X1382817Y606995D01*
X1382442Y606829D01*
X1382567Y607912D01*
X1383692D01*
G01X1385250Y605912D02*
X1385500Y605620D01*
X1385834Y605454D01*
X1386209Y605412D01*
X1386542Y605454D01*
X1386875Y605662D01*
X1387084Y605912D01*
X1387125Y606162D01*
X1387042Y606454D01*
X1386750Y606662D01*
X1386459Y606745D01*
X1386084D01*
G01X1386459D02*
X1386709Y606870D01*
X1386917Y607079D01*
X1387000Y607329D01*
X1386917Y607579D01*
X1386709Y607787D01*
X1386334Y607912D01*
X1385959Y607870D01*
X1385584Y607704D01*
G01X1389767Y605412D02*
Y607912D01*
X1388225Y606120D01*
X1390309D01*
G01X1375317Y604912D02*
Y608912D01*
X1367917D01*
G01X1371500Y618017D02*
X1369000D01*
Y619058D01*
X1369125Y619392D01*
X1369292Y619600D01*
X1369625Y619683D01*
X1369958Y619600D01*
X1370167Y619350D01*
X1370292Y619058D01*
Y618017D01*
G01Y619058D02*
X1371500Y619683D01*
G01X1371125Y621033D02*
X1371333Y621283D01*
X1371458Y621575D01*
X1371500Y621950D01*
X1371417Y622325D01*
X1371250Y622617D01*
X1370958Y622825D01*
X1370625Y622867D01*
X1370292Y622783D01*
X1370083Y622575D01*
X1369917Y622283D01*
X1369875Y621992D01*
X1369917Y621700D01*
X1370083Y621325D01*
X1369000Y621450D01*
Y622575D01*
G01X1371125Y624133D02*
X1371333Y624383D01*
X1371458Y624675D01*
X1371500Y625050D01*
X1371417Y625425D01*
X1371250Y625717D01*
X1370958Y625925D01*
X1370625Y625967D01*
X1370292Y625883D01*
X1370083Y625675D01*
X1369917Y625383D01*
X1369875Y625092D01*
X1369917Y624800D01*
X1370083Y624425D01*
X1369000Y624550D01*
Y625675D01*
G01X1371000Y627233D02*
X1371292Y627483D01*
X1371458Y627817D01*
X1371500Y628192D01*
X1371458Y628525D01*
X1371250Y628858D01*
X1371000Y629067D01*
X1370750Y629108D01*
X1370458Y629025D01*
X1370250Y628733D01*
X1370167Y628442D01*
Y628067D01*
G01Y628442D02*
X1370042Y628692D01*
X1369833Y628900D01*
X1369583Y628983D01*
X1369333Y628900D01*
X1369125Y628692D01*
X1369000Y628317D01*
X1369042Y627942D01*
X1369208Y627567D01*
G01X1373708Y619767D02*
X1373583Y619517D01*
X1373500Y619225D01*
Y618892D01*
X1373625Y618517D01*
X1373833Y618225D01*
X1374083Y618017D01*
X1374500Y617850D01*
X1374875Y617808D01*
X1375250Y617892D01*
X1375500Y618017D01*
X1375750Y618267D01*
X1375917Y618558D01*
X1376000Y618850D01*
Y619142D01*
X1375917Y619433D01*
X1375792Y619683D01*
X1375625Y619892D01*
G01X1376000Y621950D02*
X1373500D01*
X1374000Y621450D01*
G01X1376000D02*
Y622450D01*
G01X1374958Y624258D02*
X1374667Y624550D01*
X1374500Y624800D01*
X1374417Y625133D01*
X1374500Y625425D01*
X1374667Y625633D01*
X1374917Y625800D01*
X1375208Y625842D01*
X1375458Y625800D01*
X1375708Y625633D01*
X1375917Y625383D01*
X1376000Y625092D01*
X1375917Y624758D01*
X1375667Y624467D01*
X1375292Y624300D01*
X1374875Y624258D01*
X1374333Y624342D01*
X1374042Y624467D01*
X1373750Y624675D01*
X1373542Y624967D01*
X1373500Y625258D01*
X1373583Y625550D01*
X1373792Y625758D01*
G01X1374958Y627358D02*
X1374667Y627650D01*
X1374500Y627900D01*
X1374417Y628233D01*
X1374500Y628525D01*
X1374667Y628733D01*
X1374917Y628900D01*
X1375208Y628942D01*
X1375458Y628900D01*
X1375708Y628733D01*
X1375917Y628483D01*
X1376000Y628192D01*
X1375917Y627858D01*
X1375667Y627567D01*
X1375292Y627400D01*
X1374875Y627358D01*
X1374333Y627442D01*
X1374042Y627567D01*
X1373750Y627775D01*
X1373542Y628067D01*
X1373500Y628358D01*
X1373583Y628650D01*
X1373792Y628858D01*
G01X1382525Y123833D02*
X1382858Y123625D01*
X1383233Y123500D01*
X1383567D01*
X1383900Y123625D01*
X1384150Y123833D01*
X1384275Y124125D01*
X1384192Y124417D01*
X1383983Y124667D01*
X1383608Y124833D01*
X1383108Y124917D01*
X1382817Y125083D01*
X1382692Y125375D01*
X1382775Y125667D01*
X1382983Y125875D01*
X1383275Y126000D01*
X1383567D01*
X1383858Y125917D01*
X1384108Y125708D01*
G01X1385250Y126000D02*
X1385833Y123500D01*
X1386500Y126000D01*
X1387167Y123500D01*
X1387750Y126000D01*
G01X1388683Y124000D02*
X1388933Y123708D01*
X1389267Y123542D01*
X1389642Y123500D01*
X1389975Y123542D01*
X1390308Y123750D01*
X1390517Y124000D01*
X1390558Y124250D01*
X1390475Y124542D01*
X1390183Y124750D01*
X1389892Y124833D01*
X1389517D01*
G01X1389892D02*
X1390142Y124958D01*
X1390350Y125167D01*
X1390433Y125417D01*
X1390350Y125667D01*
X1390142Y125875D01*
X1389767Y126000D01*
X1389392Y125958D01*
X1389017Y125792D01*
G01X1396634Y305632D02*
X1392034Y301032D01*
X1396684Y296382D01*
G01X1385614Y301332D02*
X1387584Y303302D01*
G01Y299362D02*
X1385614Y301332D01*
G01X1387584Y314032D02*
Y288632D01*
G01X1383500Y409067D02*
X1381000D01*
Y410067D01*
X1381125Y410400D01*
X1381417Y410650D01*
X1381750Y410733D01*
X1382083Y410650D01*
X1382333Y410442D01*
X1382458Y410067D01*
Y409067D01*
G01X1381208Y413917D02*
X1381083Y413667D01*
X1381000Y413375D01*
Y413042D01*
X1381125Y412667D01*
X1381333Y412375D01*
X1381583Y412167D01*
X1382000Y412000D01*
X1382375Y411958D01*
X1382750Y412042D01*
X1383000Y412167D01*
X1383250Y412417D01*
X1383417Y412708D01*
X1383500Y413000D01*
Y413292D01*
X1383417Y413583D01*
X1383292Y413833D01*
X1383125Y414042D01*
G01X1383500Y416100D02*
X1383458Y416392D01*
X1383333Y416725D01*
X1383125Y416933D01*
X1382833Y417017D01*
X1382542Y416933D01*
X1382292Y416683D01*
X1382167Y416308D01*
Y415892D01*
X1382083Y415642D01*
X1381875Y415433D01*
X1381583Y415350D01*
X1381292Y415475D01*
X1381083Y415767D01*
X1381000Y416100D01*
X1381083Y416433D01*
X1381292Y416725D01*
X1381583Y416850D01*
X1381875Y416767D01*
X1382083Y416558D01*
X1382167Y416308D01*
Y415892D01*
X1382292Y415517D01*
X1382542Y415267D01*
X1382833Y415183D01*
X1383125Y415267D01*
X1383333Y415475D01*
X1383458Y415808D01*
X1383500Y416100D01*
G54D13*
G01X28572Y337795D02*
G02I-9300J0D01*
G01Y396850D02*
G02I-9300J0D01*
G01X69146Y988189D02*
X43949D01*
G01X108138Y337795D02*
G02I-9300J0D01*
G01Y396850D02*
G02I-9300J0D01*
G01X108268Y266096D02*
Y240899D01*
G01X135790Y269528D02*
G02I-3900J0D01*
G01X125790D02*
G02I-3900J0D01*
G01X145790D02*
G02I-3900J0D01*
G01X184568Y729409D02*
G02I-4450J0D01*
G01Y739409D02*
G02I-4450J0D01*
G01X204200Y401500D02*
G02I-4200J0D01*
G01Y391500D02*
G02I-4200J0D01*
G01Y411500D02*
G02I-4200J0D01*
G01Y421500D02*
G02I-4200J0D01*
G01X194568Y729409D02*
G02I-4450J0D01*
G01X204568D02*
G02I-4450J0D01*
G01X194568Y739409D02*
G02I-4450J0D01*
G01X204568D02*
G02I-4450J0D01*
G01X220700Y401500D02*
G02I-4200J0D01*
G01Y391500D02*
G02I-4200J0D01*
G01Y411500D02*
G02I-4200J0D01*
G01Y421500D02*
G02I-4200J0D01*
G01X214568Y729409D02*
G02I-4450J0D01*
G01Y739409D02*
G02I-4450J0D01*
G01X237876Y988189D02*
X212680D01*
G01X224568Y729409D02*
G02I-4450J0D01*
G01X234568D02*
G02I-4450J0D01*
G01X224568Y739409D02*
G02I-4450J0D01*
G01X234568D02*
G02I-4450J0D01*
G01X243898Y189684D02*
Y164487D01*
G01X244568Y729409D02*
G02I-4450J0D01*
G01X254568D02*
G02I-4450J0D01*
G01X244568Y739409D02*
G02I-4450J0D01*
G01X254568D02*
G02I-4450J0D01*
G01X264568Y729409D02*
G02I-4450J0D01*
G01Y739409D02*
G02I-4450J0D01*
G01X274568Y729409D02*
G02I-4450J0D01*
G01Y739409D02*
G02I-4450J0D01*
G01X318509Y0D02*
X301186D01*
G01X540498D02*
X515301D01*
G01X595015Y9134D02*
G02I-4700J0D01*
G01Y19134D02*
G02I-4700J0D01*
G01X590615Y44134D02*
G02I-5300J0D01*
G01X599905Y80118D02*
G02I-4000J0D01*
G01X611933Y70118D02*
G02I-4000J0D01*
G01X603941D02*
G02I-4000J0D01*
G01X615889Y80118D02*
G02I-4000J0D01*
G01X607897D02*
G02I-4000J0D01*
G01X619925Y70118D02*
G02I-4000J0D01*
G01X627917D02*
G02I-4000J0D01*
G01X631953Y80118D02*
G02I-4000J0D01*
G01X643901Y70118D02*
G02I-4000J0D01*
G01X635909D02*
G02I-4000J0D01*
G01X647937Y80118D02*
G02I-4000J0D01*
G01X639945D02*
G02I-4000J0D01*
G01X666394Y988189D02*
X641197D01*
G01X654227Y9134D02*
G02I-4700J0D01*
G01Y19134D02*
G02I-4700J0D01*
G01Y29134D02*
G02I-4700J0D01*
G01X659827Y44134D02*
G02I-5300J0D01*
G01X752245Y0D02*
X727048D01*
G01X884305Y988189D02*
X859108D01*
G01X921851Y912078D02*
Y886881D01*
G01X1009397Y0D02*
X984200D01*
G01X988781Y886881D02*
Y912078D01*
G01X1051750Y32598D02*
G02I-6750J0D01*
G01X1070866Y42122D02*
G02Y44412I-3937J1145D01*
G02Y42122I3937J-1145D01*
G01X1061186Y43267D02*
G02I-4100J0D01*
G01X1088746D02*
G02I-4100J0D01*
G01X1070591Y988189D02*
X1095788D01*
G01X1103482Y32598D02*
G02I-6750J0D01*
G01X1112146Y125146D02*
Y99949D01*
G01X1226319Y0D02*
X1210571D01*
G01X1206635Y97099D02*
Y122296D01*
G01X1262804Y329331D02*
G02I-4300J0D01*
G01Y368701D02*
G02I-4300J0D01*
G01X1276977Y349016D02*
G02I-4300J0D01*
G01X1300200Y319500D02*
G02I-4200J0D01*
G01Y329500D02*
G02I-4200J0D01*
G01X1342426Y21656D02*
G02I-3900J0D01*
G01X1350296D02*
G02I-3900J0D01*
G01X1342426Y29526D02*
G02I-3900J0D01*
G01X1350296D02*
G02I-3900J0D01*
G01X1358171Y21656D02*
G02I-3900J0D01*
G01X1366046D02*
G02I-3900J0D01*
G01X1358171Y29526D02*
G02I-3900J0D01*
G01X1366046D02*
G02I-3900J0D01*
G01X1371267Y42323D02*
G02I-4200J0D01*
G01Y60039D02*
G02I-4200J0D01*
G01Y78544D02*
G02I-4200J0D01*
G01Y96260D02*
G02I-4200J0D01*
G01X1354800Y988189D02*
X1379997D01*
G01X1396063Y0D02*
X1380315D01*
G01X1373921Y21656D02*
G02I-3900J0D01*
G01X1381796D02*
G02I-3900J0D01*
G01X1373921Y29526D02*
G02I-3900J0D01*
G01X1381796D02*
G02I-3900J0D01*
G01X1389666Y21656D02*
G02I-3900J0D01*
G01Y29526D02*
G02I-3900J0D01*
G01X1396857Y42323D02*
G02I-4200J0D01*
G01Y60039D02*
G02I-4200J0D01*
G01Y78544D02*
G02I-4200J0D01*
G01Y96260D02*
G02I-4200J0D01*
G54D23*
G01X41804Y934220D02*
X37804D01*
G01X99500Y934000D02*
X95500D01*
G01X126854Y300953D02*
X125754D01*
G01X129554D02*
X128454D01*
G01X155200Y663400D02*
X151200D01*
G01X169000Y668500D02*
Y664500D01*
G01X181000Y854500D02*
X177000D01*
G01X182000Y909000D02*
X178000D01*
G01X187000Y859000D02*
Y863000D01*
G01X190500Y850000D02*
Y854000D01*
G01X191000Y872000D02*
Y876000D01*
G01X188500Y887000D02*
X192500D01*
G01X192000Y909000D02*
X188000D01*
G01X187000D02*
X183000D01*
G01X214500Y793500D02*
X210500D01*
G01X211700Y804500D02*
X210600D01*
G01X214400D02*
X213300D01*
G01X212500Y815700D02*
Y814600D01*
G01Y818400D02*
Y817300D01*
G01X201500Y887000D02*
X205500D01*
G01X218500D02*
X222500D01*
G01X273200Y913000D02*
X272100D01*
G01X275900D02*
X274800D01*
G01X267000D02*
X271000D01*
G01X294700Y127500D02*
X293600D01*
G01X297400D02*
X296300D01*
G01X312900Y58700D02*
Y54700D01*
G01Y53700D02*
Y49700D01*
G01X304400Y72400D02*
X308400D01*
G01X299400D02*
X303400D01*
G01X312900Y63700D02*
Y59700D01*
G01X300159Y427678D02*
X304159D01*
G01X345000Y70500D02*
X341000D01*
G01X346000Y84500D02*
X350000D01*
G01X346000Y73500D02*
X350000D01*
G01X330500Y938600D02*
X334500D01*
G01X351000Y74000D02*
X355000D01*
G01X391200Y42500D02*
X390100D01*
G01X393900D02*
X392800D01*
G01X383000Y945000D02*
Y941000D01*
G01X599398Y425316D02*
Y424216D01*
G01Y428016D02*
Y426916D01*
G01Y430316D02*
Y429216D01*
G01Y433016D02*
Y431916D01*
G01Y435316D02*
Y434216D01*
G01Y440316D02*
Y439216D01*
G01Y443016D02*
Y441916D01*
G01Y438016D02*
Y436916D01*
G01Y450316D02*
Y449216D01*
G01Y445316D02*
Y444216D01*
G01Y448016D02*
Y446916D01*
G01Y453016D02*
Y451916D01*
G01X657462Y492464D02*
X661462D01*
G01X673748Y55700D02*
Y54600D01*
G01Y62700D02*
Y61600D01*
G01Y65400D02*
Y64300D01*
G01Y58400D02*
Y57300D01*
G01X685500Y475000D02*
Y471000D01*
G01X689968Y762984D02*
X685968D01*
G01Y773984D02*
X689968D01*
G01X722200Y200000D02*
Y204000D01*
G01X729968Y760984D02*
X725968D01*
G01Y771984D02*
X729968D01*
G01X763500Y901000D02*
X740000D01*
G01X749500Y880500D02*
X749600D01*
Y901100D01*
G01X763500Y880500D02*
X749500D01*
G01X756500Y897000D02*
X752500Y901000D01*
G01X756500Y897000D02*
X760500Y901000D01*
G01X762748Y125500D02*
Y121500D01*
G01X766774Y439078D02*
Y443078D01*
G01X763500Y901000D02*
Y880500D01*
G01X782274Y478578D02*
X786274D01*
G01X774700Y708000D02*
X773600D01*
G01X777400D02*
X776300D01*
G01X787000Y899000D02*
Y895000D01*
G01X790774Y436078D02*
Y432078D01*
G01X805474Y457078D02*
X804374D01*
G01X795500Y730500D02*
X791500D01*
G01X809800Y341000D02*
X810900D01*
G01X807100D02*
X808200D01*
G01X808174Y457078D02*
X807074D01*
G01X809274Y467078D02*
Y463078D01*
G01X810800Y477000D02*
X811900D01*
G01X808100D02*
X809200D01*
G01X849500Y718000D02*
Y722000D01*
G01X879000Y332000D02*
Y328000D01*
G01X872968Y708984D02*
Y707884D01*
G01Y711684D02*
Y710584D01*
G01X902600Y79000D02*
X903700D01*
G01X905300D02*
X906400D01*
G01X1017700Y499000D02*
X1016600D01*
G01X1020400D02*
X1019300D01*
G01X1025700Y144500D02*
X1024600D01*
G01X1028400D02*
X1027300D01*
G01X1041500Y103500D02*
Y107500D01*
G01Y109000D02*
Y113000D01*
G01X1051300Y179600D02*
X1050200D01*
G01X1067500Y161500D02*
X1063500D01*
G01X1054000Y179600D02*
X1052900D01*
G01X1058700Y176000D02*
X1054700D01*
G01X1053716Y279968D02*
Y275968D01*
G01X1053500Y285000D02*
Y281000D01*
G01X1070500Y143000D02*
Y139000D01*
G01X1082000Y414000D02*
Y410000D01*
G01X1094500Y61800D02*
Y62900D01*
G01Y59100D02*
Y60200D01*
G01Y67300D02*
Y68400D01*
G01Y64600D02*
Y65700D01*
G01X1093000Y755000D02*
X1097000D01*
G01X1108768Y253784D02*
X1109868D01*
G01X1106068D02*
X1107168D01*
G01X1113500Y282000D02*
Y278000D01*
G01X1103500Y778500D02*
Y782500D01*
G01X1142968Y254784D02*
Y250784D01*
G01X1148000Y594500D02*
Y590500D01*
G01X1149900Y602700D02*
Y606700D01*
G01X1149500Y829000D02*
Y825000D01*
G01X1173177Y229000D02*
X1177177D01*
G01X1188500Y230500D02*
X1192500D01*
G01X1184070Y779000D02*
Y775000D01*
G01X1225000Y450600D02*
Y451700D01*
G01Y453300D02*
Y454400D01*
G01X1251200Y211700D02*
Y207700D01*
G01X1262900Y470200D02*
X1261800D01*
G01X1265600D02*
X1264500D01*
G01X1252000Y677500D02*
Y673500D01*
G01Y715200D02*
Y714100D01*
G01Y717900D02*
Y716800D01*
G01X1270468Y468784D02*
X1266468D01*
G01X1279000Y569800D02*
Y570900D01*
G01Y567100D02*
Y568200D01*
G01X1290500Y361000D02*
Y365000D01*
G01X1288912Y436712D02*
Y432712D01*
G01X1289000Y450000D02*
X1285000D01*
G01X1307000Y365000D02*
Y361000D01*
G01X1305500Y562500D02*
Y566500D01*
G01X1314617Y575412D02*
Y579412D01*
G01X1328000Y418000D02*
Y422000D01*
G01X1345000Y81000D02*
X1349000D01*
G01X1347500Y422000D02*
Y418000D01*
G01X1341000Y459000D02*
X1345000D01*
G01X1339617Y560412D02*
Y564412D01*
G01X1362000Y426500D02*
X1358000D01*
G01X1361700Y441000D02*
X1360600D01*
G01X1364400D02*
X1363300D01*
G01X1358300Y463500D02*
X1359400D01*
G01X1355600D02*
X1356700D01*
G01X1360500Y452000D02*
X1364500D01*
G01X1351117Y564412D02*
Y560412D01*
G54D14*
G01X29704Y849820D02*
Y852670D01*
X32404D01*
G01X120154Y312853D02*
X124554D01*
Y309353D01*
G01X141691Y309743D02*
X146091D01*
Y306243D01*
G01X160076Y318321D02*
X162776D01*
G01X197955Y532600D02*
Y535450D01*
X200655D01*
G01X197955Y545100D02*
Y547950D01*
X200655D01*
G01X212155Y552900D02*
Y550050D01*
X209455D01*
G01X234450Y912600D02*
Y918600D01*
X229100D01*
G01X244700Y889400D02*
X243200D01*
G01X441555Y287650D02*
X439705D01*
G01X441555Y293550D02*
X439705D01*
G01X448929Y104450D02*
X450779D01*
G01X448929Y98550D02*
X450779D01*
G01X517050Y142500D02*
Y144350D01*
G01X522950Y142500D02*
Y144350D01*
G01X706600Y880600D02*
X709450D01*
Y877900D01*
G01X730100Y474922D02*
X732950D01*
Y472222D01*
G01X731600Y870400D02*
Y867550D01*
X728900D01*
G01X778900Y856100D02*
Y858950D01*
X781600D01*
G01X788100Y875100D02*
X790950D01*
Y872400D01*
G01X828400Y868600D02*
Y871450D01*
X831100D01*
G01X843100Y846400D02*
Y843550D01*
X840400D01*
G01X869550Y637250D02*
Y633400D01*
X865750D01*
G01X869100Y659900D02*
Y657050D01*
X866400D01*
G01X936100Y56900D02*
Y54050D01*
X933400D01*
G01X974258Y365200D02*
X971308D01*
X971258Y365250D01*
G01X999900Y469600D02*
Y472450D01*
X1002600D01*
G01X1059300Y264600D02*
X1060800D01*
G01X1096611Y105742D02*
Y104242D01*
G01X1094418Y735754D02*
X1090818D01*
Y739654D01*
G01X1107146Y827194D02*
X1109996D01*
Y824494D01*
G01X1154234Y573122D02*
Y568122D01*
X1159234D01*
G01X1195900Y858400D02*
X1193050D01*
Y861100D01*
G01X1208900Y858400D02*
X1206050D01*
Y861100D01*
G01X1225697Y577326D02*
Y571704D01*
X1219144D01*
G01X1238166Y191540D02*
Y189540D01*
G01X1240700Y844700D02*
X1243550D01*
Y842000D01*
G01X1276777Y24287D02*
X1275277D01*
G01X1326950Y59500D02*
Y57650D01*
G01X1321050Y59500D02*
Y57650D01*
G01X1339117Y554912D02*
Y559112D01*
X1343017D01*
G01X1394262Y111180D02*
Y109680D01*
G54D15*
G01X387000Y880600D02*
X394000D01*
G54D16*
G01X775034Y545641D02*
X767284D01*
G01X787118Y740234D02*
Y747984D01*
G01X878350Y744050D02*
Y736300D01*
G01X1020824Y196728D02*
X1013074D01*
G01X1159318Y249334D02*
Y241584D01*
G01X1183484Y596822D02*
X1175734D01*
G01X1278550Y580150D02*
X1270800D01*
G01X1300934Y797482D02*
Y805232D01*
G54D17*
G01X702868Y775184D02*
X695268D01*
G01X700868Y810684D02*
X693268D01*
G01X1202300Y779900D02*
Y772300D01*
G54D18*
G01X158618Y720409D02*
Y715409D01*
X163618D01*
G01X173100Y465200D02*
X179800D01*
G01X206500Y423000D02*
Y428000D01*
X201500D01*
G01X223000Y423000D02*
Y428000D01*
X218000D01*
G01X390029Y11492D02*
Y4492D01*
G01X437273Y11492D02*
Y4492D01*
G01X865020Y350980D02*
X858320D01*
G01X957250Y445600D02*
X963950D01*
G01X1252704Y306666D02*
Y301666D01*
X1257704D01*
G01X1298800Y336600D02*
X1302800D01*
Y332600D01*
G01X1392562Y36881D02*
X1397562D01*
Y41881D01*
G01X1392562Y73102D02*
X1397562D01*
Y78102D01*
G54D19*
G01X637000Y614900D02*
X640400D01*
G01X772498Y683054D02*
Y686454D01*
G01X866496Y685411D02*
Y688811D01*
G01X1071768Y211224D02*
Y207824D01*
M02*
